G04 ================== begin FILE IDENTIFICATION RECORD ==================*
G04 Layout Name:  15126-1b.brd*
G04 Film Name:    L7VCC*
G04 File Format:  Gerber RS274X*
G04 File Origin:  Cadence Allegro 16.6-2015-S079*
G04 Origin Date:  Fri Feb 10 17:22:40 2017*
G04 *
G04 Layer:  VIA CLASS/L7VCC*
G04 Layer:  PIN/L7VCC*
G04 Layer:  PACKAGE GEOMETRY/PWRVCC*
G04 Layer:  ETCH/L7VCC*
G04 Layer:  DRAWING FORMAT/LAYER_PCB_STORY*
G04 Layer:  DRAWING FORMAT/LAYER_L7VCC*
G04 *
G04 Offset:    (0.00 0.00)*
G04 Mirror:    No*
G04 Mode:      Positive*
G04 Rotation:  0*
G04 FullContactRelief:  No*
G04 UndefLineWidth:     6.00*
G04 ================== end FILE IDENTIFICATION RECORD ====================*
%FSLAX35Y35*MOIN*%
%IR0*IPPOS*OFA0.00000B0.00000*MIA0B0*SFA1.00000B1.00000*%
%ADD12C,.02*%
%ADD10C,.022*%
%ADD14C,.071*%
%ADD17C,.018*%
%ADD16C,.028*%
%ADD11C,.046*%
%ADD15C,.039*%
%ADD13C,.057*%
%ADD18O,.099X.048*%
%ADD19C,.01*%
%ADD20C,.025*%
%ADD21C,.006*%
%ADD56O,.07202X.12102*%
%ADD24C,.03004*%
%ADD49C,.04004*%
%ADD48C,.04104*%
%ADD25C,.03204*%
%ADD35C,.06004*%
%ADD33C,.06104*%
%ADD32C,.07004*%
%ADD60C,.08004*%
%ADD45C,.04404*%
%ADD28C,.06204*%
%ADD27C,.02604*%
%ADD59C,.06404*%
%ADD52C,.05504*%
%ADD26C,.02804*%
%ADD57C,.02904*%
%ADD55C,.07404*%
%ADD53C,.06504*%
%ADD47C,.04704*%
%ADD23C,.05604*%
%ADD54C,.05704*%
%ADD50C,.09304*%
%ADD41C,.04804*%
%ADD29C,.07504*%
%ADD43C,.05804*%
%ADD34C,.07604*%
%ADD51C,.06804*%
%ADD44C,.08604*%
%ADD38C,.06941*%
%ADD42C,.11204*%
%ADD31C,.12104*%
%ADD46C,.15004*%
%ADD22C,.11404*%
%ADD39C,.11207*%
%ADD61O,.06004X.07204*%
%ADD40C,.11209*%
%ADD58O,.15404X.21904*%
%ADD37C,.15504*%
%ADD36C,.26404*%
%ADD30C,.17804*%
G75*
%LPD*%
G75*
G36*
G01X1973300Y-60000D02*
X-19810D01*
Y-34500D01*
X1973300D01*
Y-60000D01*
G37*
G36*
G01X60136Y395236D02*
Y422452D01*
G02X60634Y422840I400J0D01*
G03X62094Y423257I371J1465D01*
G02X62659Y423268I288J-277D01*
G03X63075Y425567I971J1011D01*
G02X62516Y425934I-159J367D01*
G01Y427333D01*
G02X63068Y427703I400J0D01*
G03X62770Y430130I532J1297D01*
G02X62214Y430212I-236J323D01*
G03X60634Y430770I-1209J-907D01*
G02X60136Y431158I-98J388D01*
G01Y442033D01*
X44558Y457611D01*
G03X39311Y462770I-4046J1133D01*
G01X39283Y462762D01*
X12088D01*
X11558Y463292D01*
G02X11704Y463951I283J283D01*
G03X8168Y469846I-1192J3293D01*
G02X7500Y470143I-268J297D01*
G01Y514205D01*
X15295Y522000D01*
X30000D01*
X39536Y512464D01*
X39530Y512455D01*
X39545D01*
X46522Y505478D01*
X46403Y505337D01*
G03X48520Y503220I1147J-970D01*
G01X48661Y503339D01*
X52374Y499626D01*
X52389Y499584D01*
G03X53284Y498689I1411J516D01*
G01X53326Y498674D01*
X55931Y496069D01*
X55888Y495949D01*
G03X57809Y494028I1414J-507D01*
G01X57929Y494071D01*
X68500Y483500D01*
X93814D01*
G02X94063Y482787I0J-400D01*
G03X93548Y482003I935J-1175D01*
G02X92986Y481747I-386J104D01*
G03X90864Y480741I-660J-1349D01*
G02X90269Y480490I-389J92D01*
G03X90959Y478858I-772J-1288D01*
G02X91554Y479109I389J-92D01*
G03X93776Y480007I772J1289D01*
G02X94338Y480263I386J-104D01*
G03X95976Y482752I660J1349D01*
G02X96236Y483456I260J304D01*
G01X98019D01*
G02X98201Y483500I182J-356D01*
G01X603704D01*
Y483299D01*
G03X604134Y482239I1502J-8D01*
G01X604160Y482212D01*
X604221Y482069D01*
X604165Y481932D01*
X604141Y481905D01*
G03X606321Y481943I1108J-1014D01*
G01X606295Y481970D01*
X606234Y482113D01*
X606290Y482250D01*
X606314Y482277D01*
G03X606708Y483298I-1108J1014D01*
G01Y483500D01*
X607050D01*
X607065Y483486D01*
X607218D01*
G03X607229Y483500I-1175J935D01*
G01X608071D01*
X608126Y483389D01*
G03X610442Y482915I1344J671D01*
G02X610974Y482903I259J-305D01*
G03X613369Y483382I1026J1097D01*
G01X613422Y483500D01*
X626277D01*
G03X627019Y483125I1022J1100D01*
G02X627314Y482578I-74J-393D01*
G03X627258Y482422I1384J-585D01*
G01X627240Y482361D01*
X627048Y482210D01*
X626875Y482310D01*
X626849Y482353D01*
G03X626920Y480911I-1280J-786D01*
G02X627578Y481002I360J-175D01*
G03X630089Y482571I1122J999D01*
G02X630348Y483107I370J152D01*
G03X631004Y483500I-419J1443D01*
G01X639999D01*
G03X642301I1151J800D01*
G01X642612D01*
G02X642832Y483434I0J-400D01*
G01X648769D01*
G02X648988Y483500I220J-334D01*
G01X654949D01*
G03X655443Y483061I1152J799D01*
G01X655490Y483036D01*
X655609Y482846D01*
X655577Y482755D01*
G03X656295Y481025I1323J-465D01*
G02X656355Y480339I-173J-361D01*
G03X658246Y478012I873J-1222D01*
G02X658780Y478019I271J-294D01*
G03X660834Y478089I990J1130D01*
G02X661117I141J-141D01*
G03Y480209I1064J1060D01*
G02X660834I-142J141D01*
G03X658751Y480253I-1064J-1060D01*
G02X658217Y480246I-271J294D01*
G03X657832Y480491I-990J-1130D01*
G02X657750Y481175I161J366D01*
G03X658152Y482920I-850J1115D01*
G02X658509Y483500I357J180D01*
G01X665631D01*
G03X667369I869J1100D01*
G01X668631D01*
G03X668723Y483433I871J1099D01*
G02Y482767I-222J-333D01*
G03X670277I777J-1167D01*
G02Y483433I222J333D01*
G03X670369Y483500I-779J1166D01*
G01X676753D01*
X677401Y484148D01*
X677506Y484127D01*
G03X678832Y484509I294J1473D01*
G02X679358Y484530I275J-290D01*
G03X681008Y487025I941J1170D01*
G02X680913Y487660I188J353D01*
G01X688822Y495569D01*
X695303D01*
X697840Y493032D01*
Y489791D01*
X714131Y473500D01*
X1254936D01*
X1254974Y473483D01*
G03X1255189Y473410I557J1287D01*
G01X1255264Y473392D01*
X1255271D01*
X1255288Y473389D01*
G03X1255772I242J1381D01*
G01X1255789Y473392D01*
X1257171D01*
G03X1259109I969J1148D01*
G01X1260971D01*
G02X1261244Y473500I273J-292D01*
G01X1270453D01*
G03X1271345Y472947I1188J920D01*
G02X1271613Y472356I-79J-392D01*
G03X1272952Y473057I1217J-696D01*
G01X1272877Y473063D01*
X1272782Y473161D01*
G02X1272926Y473500I144J139D01*
G01X1318072D01*
G02X1318433Y472928I0J-400D01*
G03X1320779Y471433I1267J-601D01*
G02X1321355Y471476I309J-255D01*
G03X1323807Y472993I1005J1116D01*
G02X1324192Y473500I386J107D01*
G01X1337938D01*
X1346033Y465405D01*
G02X1345970Y464787I-282J-283D01*
G03X1345769Y464627I769J-1172D01*
G02X1345197Y464645I-277J288D01*
G03X1342979Y464641I-1107J-1015D01*
G02X1342427Y464604I-295J270D01*
G03X1342510Y462527I-899J-1076D01*
G02X1343063Y462534I280J-285D01*
G03X1345185Y462602I1027J1096D01*
G02X1345757Y462614I292J-273D01*
G03X1347911Y462846I982J1001D01*
G02X1348529Y462909I335J-219D01*
G01X1352578Y458860D01*
Y438104D01*
X1352130Y437656D01*
G02X1351460Y437842I-282J283D01*
G03X1349758Y436140I-1360J-342D01*
G02X1349944Y435470I-97J-388D01*
G01X1342130Y427656D01*
G02X1341460Y427842I-282J283D01*
G03X1339758Y426140I-1360J-342D01*
G02X1339944Y425470I-97J-388D01*
G01X1339024Y424550D01*
X1336166D01*
X1336115Y424602D01*
X1314435D01*
X1311510Y421676D01*
X1215085D01*
X1215000Y421591D01*
X1214200D01*
X1204109Y411500D01*
X816961D01*
G03X816839I-61J-1400D01*
G01X800268D01*
G02X799897Y412047I1J400D01*
G03X799945Y413010I-1397J552D01*
G02X800389Y413514I385J109D01*
G03X799165Y414590I221J1486D01*
G02X798721Y414086I-385J-109D01*
G03X797103Y412047I-221J-1486D01*
G02X796732Y411500I-372J-147D01*
G01X785770D01*
G02X785642Y412279I0J400D01*
G03X780699I-2471J7347D01*
G02X780572Y411500I-127J-379D01*
G01X768200D01*
X767167Y412533D01*
G02X767228Y413148I283J282D01*
G03X767405Y415508I-834J1249D01*
G02X767364Y416056I269J296D01*
G03X767699Y416905I-1164J950D01*
G02X768094Y417278I399J-27D01*
G03X766581Y418880I-14J1502D01*
G02X766186Y418507I-399J27D01*
G03X765189Y415894I14J-1502D01*
G02X765230Y415346I-269J-296D01*
G03X765145Y415231I1164J-949D01*
G02X764530Y415170I-333J222D01*
G01X753400Y426300D01*
X681942D01*
G02X681612Y426925I1J400D01*
G03X679128I-1242J845D01*
G02X678798Y426300I-331J-225D01*
G01X634190D01*
X632156Y428334D01*
X616934D01*
X614852Y426252D01*
X614742D01*
X612324Y423834D01*
Y423724D01*
X612300Y423700D01*
Y416900D01*
X612324Y416876D01*
Y416804D01*
X622633Y406494D01*
X718506D01*
X720400Y404600D01*
Y387300D01*
X712000Y378900D01*
X640100D01*
X633400Y372200D01*
X577800D01*
X560661Y389339D01*
X560683Y389444D01*
G03X558909Y391218I-1471J303D01*
G01X558804Y391196D01*
X548504Y401496D01*
G02X548453Y401558I282J284D01*
G01X548278Y401733D01*
X548267D01*
X547850Y402150D01*
X548108Y402454D01*
G03X547497Y403509I882J1215D01*
G02X546816Y403184I-398J-42D01*
G01X540910Y409090D01*
X447632D01*
X447565Y409102D01*
X447550Y409107D01*
G03X446618Y409102I-459J-1325D01*
G01X446585Y409090D01*
X428774D01*
X428739Y409104D01*
G03X427709I-515J-1304D01*
G01X427674Y409090D01*
X232110D01*
X232105Y409095D01*
X174385D01*
X172050Y411430D01*
Y429370D01*
X170620Y430800D01*
X165716D01*
X165715Y430802D01*
X131985D01*
X131984Y430800D01*
X131578D01*
X131524Y430841D01*
G03X129650Y430800I-911J-1194D01*
G01X127416D01*
X127415Y430802D01*
X96785D01*
X96784Y430800D01*
X96500D01*
X93555Y427855D01*
Y382101D01*
G03Y378913I157J-1594D01*
G01Y336478D01*
G03Y333942I805J-1268D01*
G01Y325831D01*
G02X92930Y325500I-400J0D01*
G03X90916Y325200I-844J-1242D01*
G02X90233Y325301I-312J250D01*
G03X90010Y323798I-1393J-561D01*
G02X90693Y323697I312J-250D01*
G03X92930Y323016I1393J561D01*
G02X93555Y322685I225J-331D01*
G01Y319669D01*
X94505Y318719D01*
Y318695D01*
X100298Y312901D01*
Y260290D01*
G02X99625Y259998I-400J0D01*
G03X97573Y259996I-1025J-1098D01*
G02X97027I-273J292D01*
G03X94973I-1027J-1096D01*
G02X94427I-273J292D01*
G03X92373I-1027J-1096D01*
G02X91827I-273J292D01*
G03X89773I-1027J-1096D01*
G02X89227I-273J292D01*
G03X87104Y257873I-1027J-1096D01*
G02Y257327I-292J-273D01*
G03X87228Y255155I1096J-1027D01*
G02Y254545I-259J-305D01*
G03X87277Y252215I972J-1145D01*
G02Y251585I-246J-315D01*
G03Y249215I923J-1185D01*
G02Y248585I-246J-315D01*
G03Y246215I923J-1185D01*
G02Y245585I-246J-315D01*
G03X89227Y243304I923J-1185D01*
G02X89773I273J-292D01*
G03X91827I1027J1096D01*
G02X92373I273J-292D01*
G03X94427I1027J1096D01*
G02X94973I273J-292D01*
G03X97027I1027J1096D01*
G02X97573I273J-292D01*
G03X99625Y243302I1027J1096D01*
G02X100298Y243010I273J-292D01*
G01Y242197D01*
G02X99869Y241798I-400J0D01*
G03Y238802I-111J-1498D01*
G02X100298Y238403I29J-399D01*
G01Y238126D01*
G02X99709Y237774I-400J1D01*
G03X97973Y237546I-709J-1324D01*
G02X97427I-273J292D01*
G03X95373I-1027J-1096D01*
G02X94827I-273J292D01*
G03X92773I-1027J-1096D01*
G02X92227I-273J292D01*
G03X90173I-1027J-1096D01*
G02X89627I-273J292D01*
G03X87677Y235265I-1027J-1096D01*
G02Y234635I-246J-315D01*
G03Y232265I923J-1185D01*
G02Y231635I-246J-315D01*
G03Y229265I923J-1185D01*
G02Y228635I-246J-315D01*
G03X89627Y226354I923J-1185D01*
G02X90173I273J-292D01*
G03X92227I1027J1096D01*
G02X92773I273J-292D01*
G03X94827I1027J1096D01*
G02X95373I273J-292D01*
G03X97427I1027J1096D01*
G02X97973I273J-292D01*
G03X99709Y226126I1027J1096D01*
G02X100298Y225774I189J-353D01*
G01Y225660D01*
G02X99814Y225269I-400J0D01*
G03Y222331I-314J-1469D01*
G02X100298Y221940I84J-391D01*
G01Y220298D01*
X97797Y217797D01*
G02X97125Y217987I-283J283D01*
G03X96499Y219001I-1850J-442D01*
G02X96476Y219592I257J306D01*
G03X93789Y222285I-1336J1354D01*
G02X93210Y222295I-285J281D01*
G03X90469Y222359I-1401J-1286D01*
G02X89885Y222381I-282J284D01*
G03X87185Y222559I-1438J-1245D01*
G02X86619Y222594I-266J299D01*
G03X86450Y219918I-1431J-1253D01*
G02X87016Y219883I266J-299D01*
G03X89787Y219786I1431J1253D01*
G02X90371Y219764I282J-284D01*
G03X93160Y219670I1438J1245D01*
G02X93739Y219660I285J-281D01*
G03X93916Y219490I1403J1284D01*
G02X93939Y218899I-257J-306D01*
G03X94833Y215695I1336J-1354D01*
G02X95023Y215023I-93J-389D01*
G01X94700Y214700D01*
Y214316D01*
X94598Y214215D01*
Y201004D01*
G02X94129Y200610I-400J0D01*
G03Y197652I-259J-1479D01*
G02X94598Y197258I69J-394D01*
G01Y194885D01*
X94898Y194585D01*
Y194502D01*
G03X98834Y191647I3002J-2D01*
G01X98865Y191657D01*
X113757D01*
X117731Y187683D01*
X126551D01*
G02X126895Y187079I0J-400D01*
G03X140231I6668J-3953D01*
G02X140575Y187683I344J204D01*
G01X147387D01*
X147411Y187510D01*
G03X147754Y186766I1389J189D01*
G02Y186234I-298J-266D01*
G03Y184366I1046J-934D01*
G02Y183834I-298J-266D01*
G03X147831Y181887I1046J-934D01*
G02X147853Y181332I-277J-289D01*
G03X149869Y181413I1047J-932D01*
G02X149847Y181968I277J289D01*
G03X149846Y183834I-1047J932D01*
G02Y184366I298J266D01*
G03Y186234I-1046J934D01*
G02Y186766I298J266D01*
G03X149894Y186823I-1048J931D01*
G01X149921Y186857D01*
X150079Y186936D01*
X150238Y186857D01*
X150265Y186822D01*
G03X152141Y186536I1094J878D01*
G02X152680Y186450I223J-332D01*
G03X154888Y186440I1108J859D01*
G02X155444Y186510I314J-248D01*
G03X157690Y187501I850J1115D01*
G01X157707Y187683D01*
X402903D01*
X406949Y183637D01*
X566622D01*
X603359Y146900D01*
X776898D01*
X817681Y187683D01*
X1216252D01*
X1225323Y178612D01*
X1225337Y178563D01*
G03X1226363Y177537I1443J417D01*
G01X1226412Y177523D01*
X1240038Y163897D01*
G02X1239878Y163234I-283J-282D01*
G03X1241643Y161469I431J-1334D01*
G02X1242306Y161629I381J-123D01*
G01X1253758Y150177D01*
X1254211D01*
X1258852Y145536D01*
X1258766Y145401D01*
G03X1260701Y143466I1184J-751D01*
G01X1260836Y143552D01*
X1261472Y142916D01*
X1266529D01*
G02X1266908Y142388I0J-400D01*
G03X1266872Y142261I1329J-445D01*
G02X1266345Y141978I-389J93D01*
G03X1267304Y140292I-517J-1410D01*
G02X1267817Y140600I393J-74D01*
G03X1269564Y142388I419J1338D01*
G02X1269943Y142916I379J128D01*
G01X1270432D01*
G02X1270782Y142324I-1J-400D01*
G03X1273418I1318J-721D01*
G02X1273768Y142916I351J192D01*
G01X1326388D01*
X1326409Y142740D01*
G03X1329391I1491J178D01*
G01X1329412Y142916D01*
X1417855D01*
X1432239Y157300D01*
X1475253D01*
X1475283Y157135D01*
G03X1478239I1478J265D01*
G01X1478269Y157300D01*
X1487317D01*
G03X1489283I983J1000D01*
G01X1490482D01*
G02X1490788Y156642I0J-400D01*
G03X1491585Y154066I1225J-1032D01*
G02X1491831Y153493I-107J-385D01*
G03X1493556Y154149I1238J-659D01*
G02X1493359Y154741I139J375D01*
G03X1493238Y156642I-1346J869D01*
G02X1493544Y157300I306J258D01*
G01X1499657D01*
G03X1501749I1046J933D01*
G01X1511734D01*
Y157097D01*
G03X1512624Y155776I1402J-16D01*
G02X1512692Y155066I-146J-372D01*
G03X1513470Y152298I808J-1266D01*
G02X1513861Y151866I-8J-400D01*
G03X1515388Y153245I1497J-123D01*
G02X1514997Y153677I8J400D01*
G03X1514010Y155213I-1497J123D01*
G02X1513922Y155920I136J376D01*
G03X1514538Y157097I-786J1161D01*
G01Y157300D01*
X1523876D01*
G03X1529723Y155385I3968J2231D01*
G02X1530269Y155143I165J-364D01*
G03X1533097Y156151I1431J457D01*
G02X1533394Y156691I372J147D01*
G03X1534305Y157300I-262J1377D01*
G01X1549300D01*
X1549900Y157900D01*
Y195211D01*
X1550052Y195249D01*
G03Y198165I-359J1458D01*
G01X1549900Y198203D01*
Y203000D01*
X1595300Y248400D01*
Y248621D01*
G02X1595833Y248998I400J0D01*
G03Y251642I467J1322D01*
G02X1595300Y252019I-133J377D01*
G01Y266550D01*
X1592510Y269340D01*
X1581120D01*
X1574880Y263100D01*
X1548802D01*
G02X1548402Y263500I0J400D01*
G03X1545598I-1402J0D01*
G02X1545198Y263100I-400J0D01*
G01X1542802D01*
G02X1542402Y263500I0J400D01*
G03X1539598I-1402J0D01*
G02X1539198Y263100I-400J0D01*
G01X1509255D01*
X1506990Y265365D01*
Y270836D01*
X1507167Y270857D01*
G03Y273641I-164J1392D01*
G01X1506990Y273662D01*
Y291800D01*
X1522140Y306950D01*
X1525425D01*
X1525452Y306781D01*
G03X1528420I1484J234D01*
G01X1528447Y306950D01*
X1553700D01*
X1553716Y306934D01*
X1559098D01*
G03X1561702I1302J749D01*
G01X1564004D01*
X1564029Y306928D01*
G03X1564771I371J1455D01*
G01X1564796Y306934D01*
X1568790D01*
G03X1571062I1136J1130D01*
G01X1576150D01*
G03X1578822I1336J687D01*
G01X1587196D01*
X1587235Y306917D01*
G03X1588365I565J1283D01*
G01X1588404Y306934D01*
X1598982D01*
G02X1599367Y306429I-1J-400D01*
G03X1626771I13702J-3737D01*
G02X1627156Y306934I386J105D01*
G01X1630786D01*
X1631918Y305802D01*
Y290260D01*
X1627977Y286320D01*
G02X1627306Y286508I-283J283D01*
G03X1626045Y284665I-1460J-354D01*
G02X1626498Y284269I53J-396D01*
G01Y276889D01*
X1630148Y273239D01*
Y266711D01*
G02X1629545Y266367I-400J0D01*
G03Y261631I-1403J-2368D01*
G02X1630148Y261287I203J-344D01*
G01Y242911D01*
G02X1629545Y242567I-400J0D01*
G03X1626599Y242478I-1403J-2368D01*
G02X1626025Y242615I-224J331D01*
G03X1624948Y240543I-1227J-678D01*
G02X1625390Y240152I42J-398D01*
G03X1629545Y237831I2752J47D01*
G02X1630148Y237487I203J-344D01*
G01Y228702D01*
X1631453Y227398D01*
G02X1631371Y226769I-283J-283D01*
G03X1632283Y223978I757J-1297D01*
G02X1632724Y223581I41J-398D01*
G01Y218050D01*
X1642556Y208218D01*
X1652289D01*
X1654045Y209974D01*
X1655965D01*
X1658579Y207360D01*
X1665440D01*
X1671487Y201313D01*
X1672005D01*
G02X1672403Y200948I0J-400D01*
G03X1675202Y201051I1397J122D01*
G01X1675205Y201248D01*
X1711818D01*
X1711883Y201313D01*
X1711900D01*
X1718437Y207850D01*
X1720980D01*
X1723589Y205240D01*
Y178732D01*
X1723194Y178337D01*
X1721106D01*
G02X1720716Y178824I0J400D01*
G03X1717784I-1466J326D01*
G02X1717394Y178337I-390J-87D01*
G01X1717382D01*
X1715519Y176474D01*
G02X1714892Y176555I-282J283D01*
G03X1712836Y174499I-1296J-760D01*
G02X1712917Y173872I-202J-345D01*
G01X1711523Y172478D01*
X1696390D01*
X1695200Y173668D01*
Y184520D01*
X1691110Y188610D01*
X1678600D01*
X1674196Y184206D01*
X1674176Y184194D01*
G03X1673707Y183717I737J-1193D01*
G01X1673532Y183542D01*
G02X1672903Y183625I-283J283D01*
G03X1670988Y181710I-1215J-700D01*
G02X1671071Y181081I-200J-346D01*
G01X1666192Y176202D01*
X1623416D01*
G02X1623135Y176885I1J400D01*
G03X1621762Y176589I-918J924D01*
G01X1621892Y176541D01*
Y176202D01*
X1621185D01*
X1619098Y174115D01*
Y169890D01*
G03Y168022I908J-934D01*
G01Y166783D01*
G03Y164987I943J-898D01*
G01Y163634D01*
G03Y161836I942J-899D01*
G01Y160484D01*
G03Y158686I942J-899D01*
G01Y154132D01*
G03Y152468I1002J-832D01*
G01Y151032D01*
G03Y149368I1002J-832D01*
G01Y147886D01*
G03Y146088I942J-899D01*
G01Y141586D01*
G03Y139788I942J-899D01*
G01Y135427D01*
G03Y133349I942J-1039D01*
G01Y129128D01*
G03Y127050I942J-1039D01*
G01Y121785D01*
X1619300Y121584D01*
Y121000D01*
X1621911Y118389D01*
G03X1624434Y118259I1278J251D01*
G01X1624477Y118400D01*
X1625061D01*
G03X1627617I1278J251D01*
G01X1628201D01*
X1628244Y118259D01*
G03X1630734I1245J381D01*
G01X1630777Y118400D01*
X1631351D01*
X1631394Y118259D01*
G03X1633884I1245J381D01*
G01X1633927Y118400D01*
X1634500D01*
X1634543Y118259D01*
G03X1637033I1245J381D01*
G01X1637076Y118400D01*
X1637650D01*
X1637693Y118259D01*
G03X1640183I1245J382D01*
G01X1640226Y118400D01*
X1640866D01*
X1640911Y118261D01*
G03X1643389I1239J399D01*
G01X1643434Y118400D01*
X1643949D01*
X1643992Y118259D01*
G03X1646474Y118233I1245J381D01*
G01X1646519Y118371D01*
X1649629D01*
X1650700Y117300D01*
Y116489D01*
G03Y114493I836J-998D01*
G01Y113339D01*
G03Y111343I836J-998D01*
G01Y110189D01*
G03Y108193I836J-998D01*
G01Y80459D01*
G02X1650216Y80068I-400J0D01*
G03Y77132I-316J-1468D01*
G02X1650700Y76741I84J-391D01*
G01Y66729D01*
G03X1649843Y66327I177J-1492D01*
G02X1649296Y66324I-275J290D01*
G03X1649309Y64131I-1020J-1103D01*
G02X1649856Y64134I275J-290D01*
G03X1650544Y63772I1020J1103D01*
G01X1650700Y63737D01*
Y40850D01*
G03X1649839Y39857I598J-1388D01*
G02X1649369Y39570I-386J104D01*
G03X1648777I-296J-1370D01*
G02X1648307Y39857I-84J391D01*
G03X1646849Y40974I-1459J-395D01*
G01X1641848D01*
G03X1640371Y39782I0J-1512D01*
G02X1639901Y39474I-391J84D01*
G03X1639379Y39481I-279J-1374D01*
G02X1638910Y39869I-69J394D01*
G01Y39872D01*
G03X1637399Y41374I-1512J-10D01*
G01X1632398D01*
G03X1632289Y41370I1J-1512D01*
G02X1631867Y41701I-28J399D01*
G03X1628895Y41630I-1481J-252D01*
G02X1628334Y41313I-397J48D01*
G03X1627704Y41445I-618J-1379D01*
G01X1622625Y41411D01*
G03X1622645Y38389I10J-1511D01*
G01X1626196Y38412D01*
G02X1626461Y37710I3J-400D01*
G03X1628720Y36240I919J-1058D01*
G02X1629329Y36452I382J-118D01*
G03X1631485Y37932I792J1157D01*
G02X1631984Y38408I389J91D01*
G03X1632398Y38350I415J1454D01*
G01X1637398D01*
G03X1637735Y38388I0J1512D01*
G02X1638223Y38021I89J-390D01*
G03X1640973Y37722I1400J79D01*
G02X1641461Y38001I385J-108D01*
G03X1641848Y37950I389J1461D01*
G01X1646848D01*
G03X1647258Y38007I-1J1512D01*
G02X1647745Y37750I108J-385D01*
G03X1649309Y36818I1328J450D01*
G02X1649770Y36492I67J-394D01*
G03X1650588Y35402I1480J258D01*
G01X1650700Y35347D01*
Y24000D01*
X1647200Y20500D01*
X1639241D01*
G02X1638871Y21052I0J400D01*
G03X1636093I-1389J571D01*
G02X1635723Y20500I-370J-152D01*
G01X1572000D01*
X1570400Y22100D01*
Y73697D01*
X1570588Y73894D01*
X1570662Y73902D01*
G03X1571494Y74261I-151J1494D01*
G02X1572034Y74246I262J-303D01*
G03X1572093Y76463I1042J1082D01*
G02X1571553Y76478I-262J303D01*
G03X1570662Y76891I-1043J-1082D01*
G01X1570588Y76898D01*
X1570400Y77095D01*
Y78300D01*
X1555984Y92716D01*
G02X1556252Y93399I282J283D01*
G03X1554799Y94852I-52J1401D01*
G02X1554116Y94584I-400J14D01*
G01X1549310Y99390D01*
G02X1549451Y100047I283J283D01*
G03X1547644Y101854I-496J1311D01*
G02X1546987Y101713I-374J142D01*
G01X1545800Y102900D01*
Y113900D01*
X1545700Y114000D01*
X1543278D01*
X1543257Y114176D01*
G03X1540273I-1492J-176D01*
G01X1540252Y114000D01*
X1529300D01*
X1524900Y109600D01*
X1524757Y109743D01*
X1524756Y109744D01*
G03X1522774Y107762I-1000J-982D01*
G01X1522775Y107761D01*
X1522918Y107618D01*
X1522600Y107300D01*
Y104426D01*
G03Y103674I1350J-376D01*
G01Y99586D01*
X1522586Y99550D01*
Y99549D01*
G03Y98517I1303J-516D01*
G01Y98516D01*
X1522600Y98480D01*
Y94584D01*
G03Y92546I963J-1019D01*
G01Y35200D01*
X1514436Y27036D01*
X1514337Y27049D01*
G03X1510845Y23557I-419J-3073D01*
G01X1510858Y23458D01*
X1507900Y20500D01*
X1505889D01*
G03X1502911I-1489J-200D01*
G01X1422140D01*
X1422120Y20480D01*
X1408060D01*
X1408039Y20500D01*
X1404523D01*
G02X1404244Y21186I1J400D01*
G03X1398788I-2728J2790D01*
G02X1398509Y20500I-280J-286D01*
G01X1396800D01*
X1391974Y15674D01*
G02X1391774Y15566I-282J283D01*
G01X1389534Y13326D01*
G02X1389426Y13126I-391J82D01*
G01X1383700Y7400D01*
X1377470D01*
G02X1377072Y7762I0J400D01*
G03X1374280I-1396J-132D01*
G02X1373882Y7400I-398J38D01*
G01X1357554D01*
X1349200Y15754D01*
Y38776D01*
X1349347Y38817D01*
G03X1350159Y39379I-401J1447D01*
G02X1350782Y39408I323J-236D01*
G03X1350694Y41287I1126J994D01*
G02X1350071Y41258I-323J236D01*
G03X1349347Y41711I-1126J-994D01*
G01X1349200Y41752D01*
Y59413D01*
G02X1349873Y59705I400J0D01*
G03Y61755I957J1025D01*
G02X1349200Y62047I-273J292D01*
G01Y65256D01*
G02X1349866Y65554I400J0D01*
G03Y67646I934J1046D01*
G02X1349200Y67944I-266J298D01*
G01Y94965D01*
G03X1348112Y97548I-584J1275D01*
G01X1347991Y97501D01*
X1346436Y99056D01*
X1346523Y99191D01*
G03X1346235Y101140I-1266J809D01*
G02X1346319Y101803I260J304D01*
G03X1346766Y106927I-1319J2697D01*
G03X1344107Y107366I-1266J602D01*
G03X1341998Y104464I893J-2866D01*
G02X1341315Y104177I-400J-5D01*
G01X1323995Y121497D01*
G02X1324127Y122151I282J283D01*
G03X1324767Y122673I-527J1299D01*
G02X1325433I333J-222D01*
G03X1327377Y124617I1167J777D01*
G02Y125283I222J333D01*
G03X1325433Y127227I-777J1167D01*
G02X1324767I-333J222D01*
G03X1322823Y125283I-1167J-777D01*
G02Y124617I-222J-333D01*
G03X1322215Y123230I777J-1167D01*
G02X1321820Y122767I-395J-63D01*
G01X1303213D01*
G02X1302922Y123441I1J400D01*
G03X1300878I-1022J959D01*
G02X1300587Y122767I-292J-274D01*
G01X1294849D01*
G03X1292551I-1149J-967D01*
G01X1278608D01*
X1278579Y122932D01*
G03X1275621I-1479J-262D01*
G01X1275592Y122767D01*
X1272986D01*
X1272944Y122912D01*
G03X1270473Y123596I-1444J-412D01*
G02X1269927I-273J292D01*
G03X1267780Y123500I-1027J-1096D01*
G02X1267197Y123486I-298J267D01*
G03X1265322Y123593I-997J-986D01*
G02X1265055Y123608I-125J156D01*
G01X1257562Y131101D01*
X1250383D01*
G03X1249546Y131869I-1359J-641D01*
G02X1249460Y132575I139J375D01*
G03X1248095Y132408I-845J1242D01*
G02X1248181Y131702I-139J-375D01*
G03X1247667Y131101I844J-1242D01*
G01X1247200D01*
X1247144Y131147D01*
G03X1245305Y131101I-893J-1081D01*
G01X921101D01*
X903500Y113500D01*
X903197D01*
G03X900697I-1250J-635D01*
G01X898176D01*
X898126Y113627D01*
G03X895516I-1305J-513D01*
G01X895466Y113500D01*
X891292D01*
G03X889416I-938J-1173D01*
G01X884599D01*
G03X882723I-938J-1173D01*
G01X761000D01*
X741599Y94099D01*
X741570Y94085D01*
G03X738885Y91400I2721J-5406D01*
G01X738871Y91371D01*
X736809Y89309D01*
G02X736241Y89312I-283J283D01*
G03X734242I-999J-983D01*
G02X733655Y89330I-285J281D01*
G03X731603Y89394I-1056J-922D01*
G02X731034I-284J282D01*
G03Y87422I-996J-986D01*
G02X731603I285J-282D01*
G03X733598Y87425I996J986D01*
G02X734185Y87407I285J-281D01*
G03X734258Y87329I1059J918D01*
G02X734261Y86761I-280J-285D01*
G01X734000Y86500D01*
Y84206D01*
G02X733408Y83855I-400J0D01*
G03Y81397I-674J-1229D01*
G02X734000Y81046I192J-351D01*
G01Y77312D01*
G02X733615Y76913I-400J1D01*
G03X732549Y76411I56J-1501D01*
G02X731971Y76391I-299J266D01*
G03X732045Y74316I-1048J-1076D01*
G02X732623Y74336I299J-266D01*
G03X733615Y73911I1048J1076D01*
G02X734000Y73512I-15J-400D01*
G01Y73084D01*
X733995Y73079D01*
X734000Y73074D01*
Y70448D01*
G02X733600Y70048I-400J0D01*
G03X732565Y69634I0J-1501D01*
G02X732283Y69641I-137J145D01*
G03X730105Y67572I-1083J-1041D01*
G02X730130Y67054I-292J-274D01*
G03X730232Y65228I1112J-854D01*
G02X730252Y64695I-288J-278D01*
G03X732242Y62735I1080J-893D01*
G02X732775Y62723I260J-304D01*
G03X733629Y62349I957J1024D01*
G02X734000Y61950I-29J-399D01*
G01Y49000D01*
X710500Y25500D01*
X707500D01*
X707434Y25566D01*
X706271D01*
G02X705878Y26040I0J400D01*
G03X703422Y27196I-1378J260D01*
G02X702831Y27169I-308J256D01*
G01X693000Y37000D01*
X691335D01*
G02X690949Y37505I0J400D01*
G03X688051I-1449J395D01*
G02X687665Y37000I-386J-105D01*
G01X676731D01*
X676694Y37153D01*
G03X673776I-1459J-356D01*
G01X673739Y37000D01*
X660500D01*
X660250Y37250D01*
X640765D01*
G03X635565Y37605I-2972J-5272D01*
G01X635443Y37557D01*
X622500Y50500D01*
Y96500D01*
X621500Y97500D01*
X387853D01*
G02X387507Y98100I0J400D01*
G03X385077I-1215J700D01*
G02X384731Y97500I-346J-200D01*
G01X90500D01*
X88071Y95071D01*
G02X87525Y95054I-282J283D01*
G03X85546Y93075I-925J-1054D01*
G02X85529Y92529I-300J-264D01*
G01X83872Y90872D01*
G02X83265Y90921I-283J283D01*
G03X81168Y88824I-1219J-878D01*
G02X81217Y88217I-234J-324D01*
G01X78000Y85000D01*
X59500D01*
X54500Y80000D01*
Y28700D01*
X63400Y19800D01*
Y18660D01*
G03Y16118I800J-1271D01*
G01Y14753D01*
G02X62780Y14419I-400J0D01*
G03X62287Y11875I-772J-1170D01*
G02X62764Y11443I79J-392D01*
G03X63400Y10124I1395J-140D01*
G01Y7122D01*
G02X62795Y6779I-400J0D01*
G03Y4371I-719J-1204D01*
G02X63400Y4028I205J-343D01*
G01Y1976D01*
G02X62788Y1637I-400J0D01*
G03X60821Y1300I-794J-1275D01*
G02X60187Y1311I-313J249D01*
G03X60119Y-444I-1126J-835D01*
G02X60751Y-482I301J-263D01*
G03X61208Y-918I1242J845D01*
G02X61322Y-1494I-209J-341D01*
G03X62902Y-3836I1214J-885D01*
G02X63400Y-4223I98J-388D01*
G01Y-11383D01*
X63257Y-11426D01*
G03X62674Y-11753I425J-1441D01*
G02X62127Y-11745I-269J296D01*
G03X62033Y-13843I-975J-1007D01*
G02X62578Y-13883I251J-311D01*
G03X63257Y-14306I1105J1017D01*
G01X63400Y-14349D01*
Y-16600D01*
X62309Y-17691D01*
X62245Y-17701D01*
G03X61003Y-18943I241J-1483D01*
G01X60993Y-19007D01*
X60319Y-19681D01*
X60179Y-19564D01*
G03X57911Y-20343I-898J-1077D01*
G01X57877Y-20500D01*
X52085D01*
X52049Y-20345D01*
G03X49123I-1463J-342D01*
G01X49087Y-20500D01*
X39740D01*
X39720Y-20322D01*
G03X36734I-1493J-163D01*
G01X36714Y-20500D01*
X27251D01*
X27233Y-20320D01*
G03X24443I-1395J-138D01*
G01X24425Y-20500D01*
X23932D01*
X23732Y-20501D01*
X23731Y-20242D01*
X23763Y-20192D01*
G03X21692Y-18114I-1264J811D01*
G02X21150Y-18008I-215J337D01*
G03X18775Y-19842I-1226J-867D01*
G02X18469Y-20500I-306J-258D01*
G01X-16500D01*
X-21500Y-15500D01*
Y20543D01*
G02X-21011Y20933I400J0D01*
G03X-19868Y23428I311J1367D01*
G02Y24072I238J322D01*
G03Y26328I-832J1128D01*
G02Y26972I238J322D01*
G03X-20968Y29476I-832J1128D01*
G02X-21445Y29869I-77J393D01*
G01Y30094D01*
X-21210D01*
X-21177Y30082D01*
G03X-19963Y32593I477J1318D01*
G02X-19986Y33259I210J341D01*
G03X-20033Y35574I-814J1141D01*
G02X-20017Y36254I219J335D01*
G03X-19800Y38516I-709J1209D01*
G02X-19818Y39099I264J300D01*
G01X-19617Y39300D01*
X-235D01*
G02X145Y38775I0J-400D01*
G03X1681Y36809I1427J-468D01*
G02X2107Y36366I29J-399D01*
G03X3491Y37698I1493J-166D01*
G02X3065Y38141I-29J399D01*
G03X2901Y39007I-1493J166D01*
G02X3078Y39300I177J93D01*
G01X3210D01*
X6200Y42290D01*
Y48690D01*
X6768Y49258D01*
G02X7417Y49136I283J-283D01*
G03X9632Y48653I1283J564D01*
G02X10187Y48631I266J-299D01*
G03X10330Y48501I1012J970D01*
G02X10405Y47952I-248J-314D01*
G03X12816Y46549I1134J-825D01*
G01X12840Y46600D01*
X13032Y46730D01*
X13124Y46702D01*
G03X11366Y50992I886J2868D01*
G03X10268Y50647I-166J-1392D01*
G02X9713Y50669I-266J299D01*
G03X9264Y50983I-1012J-970D01*
G02X9142Y51632I161J366D01*
G01X12811Y55301D01*
X12954Y55158D01*
X12955Y55157D01*
G03X15052Y55115I1070J1054D01*
G02X15598I273J-292D01*
G03X15478Y57180I1027J1096D01*
G02X15172I-153J130D01*
G03X15078Y57282I-1150J-966D01*
G01X14935Y57425D01*
X17850Y60340D01*
Y80710D01*
X26150Y89010D01*
G02X26736Y88987I282J-283D01*
G03X27023Y88733I1064J913D01*
G02Y88067I-222J-333D01*
G03Y85733I777J-1167D01*
G02Y85067I-222J-333D01*
G03X27256Y82608I777J-1167D01*
G02X27366Y81940I-155J-369D01*
G03X27347Y81923I925J-1053D01*
G02X26809Y81921I-270J295D01*
G03X26817Y79846I-939J-1041D01*
G02X27355Y79848I270J-295D01*
G03X27601Y79670I940J1040D01*
G01X27646Y79644D01*
X27793Y79402D01*
X27575Y79269D01*
X27519D01*
G03X26132Y77705I6J-1402D01*
G02X25777Y77261I-397J-46D01*
G03X25848Y74467I148J-1394D01*
G02X26225Y74045I-22J-399D01*
G03X26333Y73423I1400J-77D01*
G02X25947Y72868I-368J-155D01*
G03X25779Y70069I-61J-1401D01*
G02X26143Y69603I-30J-399D01*
G03X26199Y68912I1382J-236D01*
G02X25902Y68390I-378J-130D01*
G03X25874Y65650I283J-1373D01*
G02X26163Y65129I-89J-390D01*
G03X26625Y63566I1325J-458D01*
G02X26642Y62950I-246J-315D01*
G03X26554Y60921I922J-1056D01*
G02Y60367I-288J-277D01*
G03X26998Y58111I1010J-973D01*
G02X27073Y57423I-162J-366D01*
G03X26815Y57177I831J-1129D01*
G02X26193Y57178I-311J252D01*
G03X23959Y57114I-1093J-878D01*
G02X23293Y57137I-325J233D01*
G03X23241Y55586I-1193J-736D01*
G02X23907Y55563I325J-233D01*
G03X26189Y55417I1193J737D01*
G02X26811Y55416I311J-252D01*
G03X28470Y57577I1093J878D01*
G02X28395Y58265I162J366D01*
G03X28574Y60367I-831J1129D01*
G02Y60921I288J277D01*
G03X28427Y62999I-1010J973D01*
G02X28410Y63615I246J315D01*
G03X27799Y66038I-922J1056D01*
G02X27510Y66559I89J390D01*
G03X27511Y67472I-1325J458D01*
G02X27808Y67994I378J130D01*
G03X27632Y70765I-283J1373D01*
G02X27268Y71231I30J399D01*
G03X27178Y72011I-1382J236D01*
G02X27564Y72566I368J155D01*
G03X27702Y75367I61J1401D01*
G02X27325Y75789I22J399D01*
G03X27318Y76029I-1400J79D01*
G02X27673Y76473I397J46D01*
G03X28505Y78869I-148J1394D01*
G02X28676Y79540I280J286D01*
G03X28863Y79608I-384J1348D01*
G02X29394Y79398I162J-366D01*
G03X32088Y79979I1292J544D01*
G02X32490Y80389I400J10D01*
G03X32256Y83172I9J1402D01*
G02X31790Y83618I-70J394D01*
G03X31177Y84967I-1390J182D01*
G02Y85633I222J333D01*
G03Y87967I-777J1167D01*
G02Y88633I222J333D01*
G03X29426Y90808I-776J1167D01*
G02X28849Y90830I-278J288D01*
G03X28713Y90964I-1050J-929D01*
G02X28690Y91550I260J304D01*
G01X29240Y92100D01*
X29266D01*
X31180Y94014D01*
X32117D01*
G02X32513Y93559I0J-400D01*
G03X33821Y91859I1487J-209D01*
G02X34168Y91396I-48J-397D01*
G03X35829Y92641I1482J-246D01*
G02X35482Y93104I48J397D01*
G03X35309Y94086I-1482J245D01*
G01X35235Y94218D01*
X40002Y98985D01*
Y115725D01*
X40867Y116590D01*
X42805D01*
X42845Y116441D01*
G03X44814Y115539I1355J359D01*
G02X45388Y115180I174J-360D01*
G01Y113120D01*
G02X44814Y112761I-400J1D01*
G03X45283Y110610I-614J-1261D01*
G02X45866Y110648I309J-254D01*
G03X46911Y110239I1034J1102D01*
G02X47310Y109786I3J-400D01*
G03X49299Y108332I1390J-186D01*
G02X49870Y107971I171J-362D01*
G01Y106478D01*
G02X49277Y106128I-400J0D01*
G03X47211Y104713I-677J-1228D01*
G02X46832Y104260I-397J-53D01*
G03X45790Y103776I68J-1510D01*
G02X45231Y103748I-294J271D01*
G03X44836Y101404I-931J-1048D01*
G02X45388Y101035I152J-369D01*
G01Y99367D01*
G02X44791Y99020I-400J1D01*
G03X45116Y96834I-691J-1220D01*
G02X45718Y96807I289J-276D01*
G03X46924Y96239I1181J943D01*
G02X47323Y95764I6J-400D01*
G03X49299Y94232I1377J-264D01*
G02X49870Y93871I171J-362D01*
G01Y92329D01*
G02X49299Y91968I-400J1D01*
G03X49703Y89720I-599J-1268D01*
G02X50280Y89714I286J-280D01*
G03X52883Y90581I1101J1036D01*
G01X52892Y90665D01*
Y95760D01*
G03X50168Y96651I-1511J-10D01*
G02X49592Y96581I-321J239D01*
G03X48745Y96901I-892J-1081D01*
G02X48369Y97395I13J400D01*
G03X48402Y97581I-1469J357D01*
G01X48412Y97665D01*
Y102760D01*
G03X48385Y103032I-1512J-13D01*
G02X48738Y103505I393J75D01*
G03X49574Y103891I-137J1395D01*
G02X50172Y103843I278J-288D01*
G03X52883Y104581I1209J907D01*
G01X52892Y104665D01*
Y109760D01*
G03X50205Y110699I-1511J-10D01*
G02X49628Y110651I-311J251D01*
G03X48762Y111001I-928J-1051D01*
G02X48386Y111473I17J399D01*
G03X48402Y111580I-1486J277D01*
G01Y111581D01*
X48412Y111665D01*
Y116590D01*
X59188D01*
Y111750D01*
G03X60677Y110239I1511J0D01*
G02X61060Y109744I-6J-400D01*
G03X63239Y108274I1362J-331D01*
G02X63872Y107949I233J-325D01*
G01Y106618D01*
G02X63257Y106281I-400J0D01*
G03X61142Y104758I-755J-1181D01*
G02X60764Y104261I-388J-97D01*
G03X59290Y102751I37J-1511D01*
G01Y97750D01*
G03X62027Y96866I1511J0D01*
G02X62686Y96851I324J-234D01*
G03X62967Y98702I1172J769D01*
G02X62312Y99010I-255J309D01*
G01Y102760D01*
G03X62248Y103187I-1511J-8D01*
G02X62602Y103702I383J116D01*
G03X63461Y104077I-99J1398D01*
G02X64079Y103987I273J-292D01*
G03X64987Y103291I1305J763D01*
G02X65264Y102784I-104J-386D01*
G03X67044Y103690I1336J-424D01*
G02X66796Y104212I126J380D01*
G03X66886Y104581I-1412J540D01*
G01X66896Y104665D01*
Y109341D01*
G02X67452Y109710I400J1D01*
G03X66643Y111351I548J1290D01*
G02X66073Y111095I-387J100D01*
G03X64060Y110480I-689J-1345D01*
G02X63424Y110393I-350J193D01*
G03X62509Y110812I-1002J-980D01*
G02X62150Y111324I25J399D01*
G03X62202Y111580I-1450J428D01*
G01Y111581D01*
X62212Y111665D01*
Y114891D01*
G02X62827Y115228I400J0D01*
G03X64984Y116392I755J1181D01*
G01X64986Y116590D01*
X66002D01*
X66091Y116500D01*
X122920D01*
X131500Y125080D01*
Y160840D01*
X123760Y168580D01*
X79424D01*
X74174Y173830D01*
Y186400D01*
X74200D01*
X65600Y195000D01*
Y200559D01*
G03Y204041I-2507J1741D01*
G01Y208898D01*
G03X65671Y211246I-900J1202D01*
G01X65600Y211306D01*
Y211594D01*
X65671Y211654D01*
G03X65600Y214002I-971J1146D01*
G01Y216805D01*
G03Y219319I-822J1257D01*
G01Y241507D01*
X65741Y241551D01*
G03X66551Y242049I-560J1818D01*
G02X67127I288J-277D01*
G03X69947Y242135I1371J1319D01*
G02X70568Y242120I304J-259D01*
G03X70625Y244515I1506J1162D01*
G02X70004Y244530I-304J259D01*
G03X67127Y244687I-1506J-1162D01*
G02X66551I-288J277D01*
G03X65741Y245185I-1370J-1320D01*
G01X65600Y245229D01*
Y263892D01*
X65767Y263920D01*
G03X66953Y264825I-267J1580D01*
G02X67612Y264925I363J-168D01*
G03X67617Y264920I1134J1129D01*
G02Y264380I-295J-270D01*
G03X69880Y262117I1183J-1080D01*
G02X70420I270J-295D01*
G03X72683Y264380I1080J1183D01*
G02Y264920I295J270D01*
G03X70420Y267183I-1183J1080D01*
G02X69880I-270J295D01*
G03X67347Y266675I-1080J-1183D01*
G02X66688Y266575I-363J168D01*
G03X65767Y267080I-1188J-1075D01*
G01X65600Y267108D01*
Y283972D01*
G02X66063Y284367I400J0D01*
G03Y287333I237J1483D01*
G02X65600Y287728I-63J395D01*
G01Y290898D01*
G02X66000Y291298I400J0D01*
G03Y294102I0J1402D01*
G02X65600Y294502I0J400D01*
G01Y301669D01*
G02X66111Y302053I400J0D01*
G03Y304747I389J1347D01*
G02X65600Y305131I-111J384D01*
G01Y309323D01*
G03Y311727I-900J1202D01*
G01Y320325D01*
G02X66189Y320677I400J-1D01*
G03X67983Y320959I711J1323D01*
G02X68544Y320975I289J-277D01*
G03X70437Y320957I956J1025D01*
G02X71014Y320913I268J-297D01*
G03X73126Y320844I1086J887D01*
G02X73727Y320826I293J-273D01*
G03X75694Y320513I1160J954D01*
G02X76285Y320315I216J-337D01*
G03X76898Y322014I1315J486D01*
G02X76317Y322238I-200J346D01*
G03X73741Y322751I-1430J-458D01*
G02X73139Y322741I-305J258D01*
G03X71163Y322843I-1039J-941D01*
G02X70586Y322887I-268J297D01*
G03X68544Y323025I-1086J-887D01*
G02X67983Y323041I-272J293D01*
G03X66189Y323323I-1083J-1041D01*
G02X65600Y323675I-189J353D01*
G01Y335300D01*
X63656Y337244D01*
G02X63708Y337854I282J283D01*
G03X61754Y339808I-808J1146D01*
G02X61144Y339756I-327J230D01*
G01X57300Y343600D01*
Y361960D01*
G02X57827Y362339I400J0D01*
G03X58951Y362443I444J1330D01*
G02X59542Y362141I194J-350D01*
G03X60254Y363533I1392J166D01*
G02X59663Y363835I-194J350D01*
G03X57596Y364898I-1392J-166D01*
G01X57551Y364873D01*
X57300D01*
Y365197D01*
X57485Y365394D01*
X57558Y365402D01*
G03Y368188I-163J1393D01*
G01X57485Y368196D01*
X57300Y368393D01*
Y374301D01*
G02X57722Y374700I400J0D01*
G03Y377500I78J1400D01*
G02X57300Y377899I-22J399D01*
G01Y386498D01*
G02X57500Y386698I200J0D01*
G03Y389502I0J1402D01*
G02X57300Y389702I0J200D01*
G01Y392400D01*
X60136Y395236D01*
G37*
G36*
G01X1621909Y313809D02*
X1621769Y313917D01*
G03X1603195Y312900I-8700J-11225D01*
G01X1598354D01*
X1596987Y314267D01*
Y322920D01*
X1590280Y329627D01*
X1590204D01*
X1589675Y330156D01*
X1589886Y330367D01*
X1589984Y330354D01*
G03X1589192Y330710I193J1489D01*
G02X1588930Y330008I-262J-302D01*
G01X1581455D01*
X1581400Y330117D01*
G03X1578900I-1250J-634D01*
G01X1578845Y330008D01*
X1570738D01*
G02X1570417Y330646I0J400D01*
G03X1570307Y332569I-1206J896D01*
G02Y333115I292J273D01*
G03X1568115I-1096J1027D01*
G02Y332569I-292J-273D01*
G03X1568005Y330646I1096J-1027D01*
G02X1567684Y330008I-321J-238D01*
G01X1561290D01*
G03X1561120Y330227I-1266J-808D01*
G02Y330773I292J273D01*
G03X1558928I-1096J1027D01*
G02Y330227I-292J-273D01*
G03X1558758Y330008I1096J-1027D01*
G01X1549529D01*
G02X1549190Y330619I0J400D01*
G03X1548799Y332513I-1190J742D01*
G02X1548685Y333048I228J328D01*
G03X1546435Y334975I-1287J775D01*
G02X1545895Y334999I-257J307D01*
G03X1545738Y332881I-991J-991D01*
G02X1546275Y332825I238J-321D01*
G03X1546614Y332542I1122J999D01*
G02X1546759Y332014I-209J-341D01*
G03X1546810Y330619I1241J-653D01*
G02X1546471Y330008I-339J-211D01*
G01X1540107D01*
X1539909Y330200D01*
X1539903Y330275D01*
G03X1536909I-1497J-118D01*
G01X1536903Y330200D01*
X1536705Y330008D01*
X1531354D01*
X1525984Y324638D01*
Y313634D01*
G02X1525605Y313235I-400J0D01*
G03X1524377Y311310I72J-1400D01*
G01X1524427Y311187D01*
X1503800Y290560D01*
Y275662D01*
G03Y273190I661J-1236D01*
G01Y264500D01*
X1507300Y261000D01*
X1565529D01*
G02X1565855Y260369I-1J-400D01*
G03X1568145I1145J-809D01*
G02X1568471Y261000I327J231D01*
G01X1574100D01*
X1575198Y262098D01*
X1575295D01*
X1578023Y264827D01*
G02X1578653Y264744I283J-283D01*
G03X1580568Y266659I1214J701D01*
G02X1580485Y267289I200J347D01*
G01X1581535Y268338D01*
X1592095D01*
X1594298Y266135D01*
Y248815D01*
X1548898Y203415D01*
Y197982D01*
G03Y195432I795J-1275D01*
G01Y192653D01*
G02X1548427Y192260I-400J0D01*
G03Y189500I-249J-1380D01*
G02X1548898Y189107I71J-393D01*
G01Y160598D01*
X1547800Y159500D01*
X1532400D01*
X1532393Y159693D01*
G03X1523295I-4549J-162D01*
G01X1523288Y159500D01*
X1501305D01*
X1501266Y159517D01*
G03X1500140I-563J-1284D01*
G01X1500101Y159500D01*
X1496452D01*
X1496431Y159676D01*
G03X1493447I-1492J-176D01*
G01X1493426Y159500D01*
X1489025D01*
G03X1487575I-725J-1200D01*
G01X1429338D01*
X1429031Y159807D01*
X1415631Y146407D01*
X1325627D01*
X1325595Y146418D01*
G03X1324605I-495J-1418D01*
G01X1324573Y146407D01*
X1321027D01*
X1320995Y146418D01*
G03X1320005I-495J-1418D01*
G01X1319973Y146407D01*
X1294654D01*
G02X1294377Y147095I0J400D01*
G03X1294824Y147980I-1042J1082D01*
G02X1295225Y148328I397J-52D01*
G03X1295402Y151323I14J1502D01*
G02X1295045Y151728I43J398D01*
G03Y151781I-1502J27D01*
G02X1295387Y152184I400J7D01*
G03X1293834Y154353I-215J1486D01*
G02X1293119Y154358I-356J182D01*
G03X1291848Y152194I-1347J-664D01*
G02X1292056Y151966I10J-200D01*
G03X1292050Y151918I1487J-210D01*
G02X1291670Y151562I-398J44D01*
G03X1291497Y148578I64J-1501D01*
G02X1291833Y148182I-64J-395D01*
G03X1292293Y147095I1502J-5D01*
G02X1292016Y146407I-277J-288D01*
G01X1279254D01*
G03X1278984Y146779I-1254J-626D01*
G02X1279005Y147368I281J285D01*
G03X1277030Y147389I-975J1142D01*
G02X1277038Y146800I-266J-298D01*
G03X1276746Y146407I962J-1020D01*
G01X1264429D01*
G02X1264038Y146890I0J400D01*
G03X1261100I-1469J311D01*
G02X1260709Y146407I-391J-83D01*
G01X1259564D01*
X1234566Y171405D01*
G02X1234650Y172034I283J282D01*
G03X1232599Y174085I-748J1303D01*
G02X1231970Y174001I-347J199D01*
G01X1227948Y178023D01*
X1228038Y178159D01*
G03X1228080Y178227I-1257J823D01*
G01X1228106Y178272D01*
X1228280Y178375D01*
X1228453Y178272D01*
X1228479Y178227D01*
G03X1230965Y178057I1300J753D01*
G02X1231595I315J-246D01*
G03X1233703Y180165I1185J923D01*
G02Y180795I246J315D01*
G03X1231595Y182903I-923J1185D01*
G02X1230965I-315J246D01*
G03X1228595I-1185J-923D01*
G02X1227965I-315J246D01*
G03X1227877Y183006I-1185J-923D01*
G02X1227905Y183580I292J273D01*
G03X1225817Y183682I-991J1128D01*
G02X1225789Y183108I-292J-273D01*
G03X1226027Y180679I991J-1129D01*
G01X1226072Y180653D01*
X1226175Y180480D01*
X1226072Y180306D01*
X1226027Y180280D01*
G03X1225959Y180238I755J-1299D01*
G01X1225823Y180148D01*
X1217289Y188682D01*
X1216669D01*
X1216667Y188684D01*
X817266D01*
X776483Y147902D01*
X603774D01*
X567037Y184638D01*
X566818D01*
X566817Y184640D01*
X407362D01*
X400146Y191856D01*
X379699D01*
G02X379398Y192519I0J400D01*
G03X377136I-1131J988D01*
G02X376835Y191856I-301J-263D01*
G01X359419D01*
G02X359118Y192519I0J400D01*
G03X356856I-1131J988D01*
G02X356555Y191856I-301J-263D01*
G01X318725D01*
G02X318437Y192534I0J400D01*
G03X316419I-1009J973D01*
G02X316131Y191856I-288J-278D01*
G01X158647D01*
G02X158272Y192393I1J400D01*
G03X156041Y193936I-1318J479D01*
G02X155487Y193969I-260J304D01*
G03X153301Y193819I-1033J-948D01*
G02X152714Y193741I-329J228D01*
G03X151930Y194067I-905J-1071D01*
G02X151572Y194542I35J398D01*
G03X150013Y193248I-1572J308D01*
G02X150415Y192809I4J-400D01*
G03X150446Y192348I1395J-138D01*
G02X150057Y191856I-389J-92D01*
G01X116256D01*
X115214Y192898D01*
X115402Y193085D01*
Y196285D01*
X120115Y200998D01*
X128615D01*
X128786Y201170D01*
X148222D01*
G02X148577Y200586I0J-400D01*
G03X151423I1423J-736D01*
G02X151778Y201170I355J184D01*
G01X160790D01*
G02X161189Y200746I0J-400D01*
G03X164387I1599J-96D01*
G02X164786Y201170I399J24D01*
G01X273114D01*
X273147Y201010D01*
G03X276091I1472J299D01*
G01X276124Y201170D01*
X276723D01*
G02X276991Y200474I-1J-400D01*
G03X279007I1008J-1114D01*
G02X279275Y201170I269J296D01*
G01X279975D01*
X280009Y201012D01*
G03X282749I1370J297D01*
G01X282783Y201170D01*
X286735D01*
X286769Y201012D01*
G03X289509I1370J297D01*
G01X289543Y201170D01*
X293495D01*
X293529Y201012D01*
G03X296269I1370J297D01*
G01X296303Y201170D01*
X307014D01*
X307048Y201012D01*
G03X309788I1370J297D01*
G01X309822Y201170D01*
X322796D01*
X322830Y201012D01*
G03X325570I1370J296D01*
G01X325604Y201170D01*
X329539D01*
X329569Y201006D01*
G03X332327I1379J252D01*
G01X332357Y201170D01*
X381272D01*
X381305Y201010D01*
G03X384249I1472J299D01*
G01X384282Y201170D01*
X402953D01*
X403363Y200760D01*
G02X403356Y200188I-283J-283D01*
G03X405480Y198064I1036J-1088D01*
G02X406052Y198071I289J-276D01*
G01X412387Y191736D01*
X571206D01*
X601642Y161300D01*
X603484D01*
X603635Y161148D01*
X746223D01*
X746268Y161011D01*
G03X748292Y160231I1332J439D01*
G02X748889Y159889I197J-348D01*
G03X756156Y161256I3752J56D01*
G01X771650Y176750D01*
Y187150D01*
X768100Y190700D01*
Y206500D01*
X768550Y206950D01*
X771450D01*
X774800Y210300D01*
X778400D01*
X778800Y210700D01*
Y212400D01*
X779500Y213100D01*
X782700D01*
X783900Y211900D01*
Y204100D01*
X786300Y201700D01*
X790512D01*
G02X790912Y201298I0J-400D01*
G03X794116I1602J-8D01*
G02X794516Y201700I400J2D01*
G01X796120D01*
X796156Y201545D01*
G03X797607Y200309I1561J362D01*
G02X797941Y199739I-28J-399D01*
G03X799456Y200594I1359J-639D01*
G02X799142Y201175I41J398D01*
G03X799278Y201545I-1424J734D01*
G01X799314Y201700D01*
X802156D01*
G03X804112I978J1269D01*
G01X817442D01*
X817495Y201581D01*
G03X820425I1465J649D01*
G01X820478Y201700D01*
X922325D01*
G02X922725Y201302I0J-400D01*
G03X925729I1502J7D01*
G02X926129Y201700I400J-2D01*
G01X929185D01*
G02X929585Y201302I0J-400D01*
G03X932389I1402J7D01*
G02X932789Y201700I400J-2D01*
G01X935945D01*
G02X936345Y201302I0J-400D01*
G03X939149I1402J7D01*
G02X939549Y201700I400J-2D01*
G01X942705D01*
G02X943105Y201302I0J-400D01*
G03X945909I1402J7D01*
G02X946309Y201700I400J-2D01*
G01X956224D01*
G02X956624Y201302I0J-400D01*
G03X959428I1402J7D01*
G02X959828Y201700I400J-2D01*
G01X972006D01*
G02X972406Y201302I0J-400D01*
G03X975210I1402J6D01*
G02X975610Y201700I400J-2D01*
G01X978755D01*
G02X979154Y201291I-1J-400D01*
G03X981958I1402J-33D01*
G02X982357Y201700I400J9D01*
G01X1030483D01*
G02X1030883Y201302I0J-400D01*
G03X1033887I1502J7D01*
G02X1034287Y201700I400J-2D01*
G01X1060484D01*
X1060485Y201698D01*
X1106589D01*
G02X1106957Y201142I0J-400D01*
G03X1109539I1291J-546D01*
G02X1109907Y201698I368J156D01*
G01X1124163D01*
G02X1124415Y200988I0J-400D01*
G03X1126185I885J-1088D01*
G02X1126437Y201698I252J310D01*
G01X1173480D01*
G03X1175958I1239J849D01*
G01X1180240D01*
G03X1182718I1239J849D01*
G01X1186835D01*
X1186890Y201586D01*
G03X1189588I1349J661D01*
G01X1189643Y201698D01*
X1195691D01*
G02X1196091Y201311I0J-400D01*
G03X1198893I1401J45D01*
G02X1199293Y201698I400J-13D01*
G01X1225172D01*
G03X1225404Y201373I1328J702D01*
G02Y200827I-292J-273D01*
G03X1227692Y200714I1096J-1027D01*
G01X1227673Y200739D01*
X1227659Y200777D01*
G02X1227989Y200986I188J68D01*
G01X1228590Y200385D01*
X1250458Y187500D01*
X1266287Y171671D01*
G02X1266224Y171054I-283J-283D01*
G03X1268304Y168974I826J-1254D01*
G02X1268921Y169037I334J-220D01*
G01X1276860Y161098D01*
X1293743D01*
G02X1294112Y160545I0J-400D01*
G03X1296888I1388J-575D01*
G02X1297257Y161098I369J153D01*
G01X1298227D01*
G02X1298580Y160511I-1J-400D01*
G03X1301234I1327J-703D01*
G02X1301587Y161098I354J187D01*
G01X1328439D01*
G02X1328807Y160543I-1J-400D01*
G03X1331393I1293J-543D01*
G02X1331761Y161098I369J155D01*
G01X1333439D01*
G02X1333807Y160543I-1J-400D01*
G03X1336393I1293J-543D01*
G02X1336761Y161098I369J155D01*
G01X1338439D01*
G02X1338807Y160543I-1J-400D01*
G03X1341393I1293J-543D01*
G02X1341761Y161098I369J155D01*
G01X1343439D01*
G02X1343807Y160543I-1J-400D01*
G03X1346393I1293J-543D01*
G02X1346761Y161098I369J155D01*
G01X1348439D01*
G02X1348807Y160543I-1J-400D01*
G03X1351393I1293J-543D01*
G02X1351761Y161098I369J155D01*
G01X1353439D01*
G02X1353807Y160543I-1J-400D01*
G03X1356393I1293J-543D01*
G02X1356761Y161098I369J155D01*
G01X1358439D01*
G02X1358807Y160543I-1J-400D01*
G03X1361393I1293J-543D01*
G02X1361761Y161098I369J155D01*
G01X1363439D01*
G02X1363807Y160543I-1J-400D01*
G03X1366393I1293J-543D01*
G02X1366761Y161098I369J155D01*
G01X1368439D01*
G02X1368807Y160543I-1J-400D01*
G03X1371393I1293J-543D01*
G02X1371761Y161098I369J155D01*
G01X1373439D01*
G02X1373807Y160543I-1J-400D01*
G03X1376393I1293J-543D01*
G02X1376761Y161098I369J155D01*
G01X1378439D01*
G02X1378807Y160543I-1J-400D01*
G03X1381393I1293J-543D01*
G02X1381761Y161098I369J155D01*
G01X1383439D01*
G02X1383807Y160543I-1J-400D01*
G03X1386393I1293J-543D01*
G02X1386761Y161098I369J155D01*
G01X1388439D01*
G02X1388807Y160543I-1J-400D01*
G03X1391277Y160760I1292J-543D01*
G01X1391261Y160785D01*
X1391244Y160843D01*
G02X1391436Y161098I192J55D01*
G01X1391505D01*
X1394856Y164449D01*
Y225485D01*
X1395036Y225503D01*
G03X1395374Y225578I-154J1494D01*
G02X1395864Y225377I131J-378D01*
G03X1398542Y226737I1347J664D01*
G02X1398831Y227317I354J185D01*
G03X1399932Y228264I-231J1383D01*
G02X1400591Y228427I380J-124D01*
G03X1400233Y229871I974J1008D01*
G02X1399574Y229708I-380J124D01*
G03X1397333Y228099I-974J-1008D01*
G02X1397022Y227531I-361J-171D01*
G03X1396718Y227460I188J-1490D01*
G02X1396228Y227661I-131J378D01*
G03X1395035Y228491I-1347J-664D01*
G01X1394856Y228510D01*
Y243272D01*
X1374584Y263544D01*
G02X1374866Y264227I283J283D01*
G03X1375828Y264611I-2J1402D01*
G02X1376399Y264588I274J-291D01*
G03X1377522Y264088I1123J1011D01*
G01X1381031D01*
G03X1382147Y264581I-1J1512D01*
G02X1382733Y264586I295J-270D01*
G03X1382771Y266549I1020J962D01*
G02X1382185Y266576I-280J285D01*
G03X1381032Y267112I-1155J-976D01*
G01X1377522D01*
G03X1376422Y266636I1J-1512D01*
G02X1375850Y266626I-291J275D01*
G03X1373462Y265631I-986J-997D01*
G02X1372779Y265349I-400J1D01*
G01X1370998Y267130D01*
Y313697D01*
X1371183Y313894D01*
X1371256Y313902D01*
G03Y316888I-166J1493D01*
G01X1371183Y316896D01*
X1370998Y317093D01*
Y317497D01*
X1371183Y317694D01*
X1371256Y317702D01*
G03X1371785Y320527I-166J1493D01*
G02X1371755Y321218I185J354D01*
G03X1371173Y323791I-755J1182D01*
G01X1370998Y323813D01*
Y324482D01*
X1383602Y337085D01*
Y337502D01*
X1384200Y338100D01*
Y357901D01*
G02X1384622Y358300I400J0D01*
G03Y361100I78J1400D01*
G02X1384200Y361499I-22J399D01*
G01Y381157D01*
G02X1384585Y381556I400J-1D01*
G03Y384358I-54J1401D01*
G02X1384200Y384757I15J400D01*
G01Y386343D01*
X1384186Y386358D01*
Y390873D01*
X1384305Y390925D01*
G03Y393675I-605J1375D01*
G01X1384186Y393727D01*
Y397301D01*
X1384373Y397498D01*
X1384447Y397506D01*
G03X1385273Y397890I-146J1394D01*
G02X1385827I277J-288D01*
G03X1387812Y399871I973J1010D01*
G02X1387801Y400413I288J277D01*
G03X1385779Y402353I-1049J930D01*
G02X1385225I-277J288D01*
G03X1384439Y402732I-972J-1011D01*
G01X1384367Y402742D01*
X1384186Y402939D01*
Y405034D01*
X1384200Y405048D01*
Y409158D01*
X1384491Y409449D01*
G03X1386446Y409551I925J1053D01*
G02X1387039Y409546I294J-271D01*
G03X1386950Y411302I1046J933D01*
G01X1386923Y411265D01*
X1386758Y411177D01*
X1386644Y411238D01*
G02X1386598Y411556I95J176D01*
G01X1399800Y424758D01*
Y428286D01*
G02X1400451Y428597I400J0D01*
G03X1402488Y428728I947J1178D01*
G02X1403047Y428744I288J-278D01*
G03X1403462Y431071I951J1031D01*
G02X1402910Y431440I-152J369D01*
G01Y433110D01*
G02X1403462Y433479I400J0D01*
G03X1403047Y435806I536J1296D01*
G02X1402488Y435822I-271J294D01*
G03X1400451Y435953I-1090J-1047D01*
G02X1399800Y436264I-251J311D01*
G01Y438769D01*
G02X1400390Y439121I400J0D01*
G03Y445729I1778J3304D01*
G02X1399800Y446081I-190J352D01*
G01Y447402D01*
X1396607Y450595D01*
X1396121D01*
X1396115Y450602D01*
X1391271D01*
G02X1391025Y451317I0J400D01*
G03X1389175I-925J1183D01*
G02X1388929Y450602I-246J-315D01*
G01X1386271D01*
G02X1386025Y451317I0J400D01*
G03X1384175I-925J1183D01*
G02X1383929Y450602I-246J-315D01*
G01X1383585D01*
X1383579Y450595D01*
X1383043D01*
X1381019Y448571D01*
X1380883Y448663D01*
G03X1378823Y446922I-783J-1163D01*
G01X1378880Y446796D01*
X1378635Y446552D01*
X1376816D01*
G02X1376435Y447073I0J400D01*
G03X1373765I-1335J427D01*
G02X1373384Y446552I-381J-121D01*
G01X1371816D01*
G02X1371435Y447073I0J400D01*
G03X1368765I-1335J427D01*
G02X1368384Y446552I-381J-121D01*
G01X1366816D01*
G02X1366435Y447073I0J400D01*
G03X1363765I-1335J427D01*
G02X1363384Y446552I-381J-121D01*
G01X1362185D01*
X1362034Y446400D01*
X1355171D01*
X1353671Y447900D01*
Y459035D01*
X1353580Y459126D01*
Y459275D01*
X1339619Y473235D01*
X1338353Y474502D01*
X1338204D01*
X1336906Y475800D01*
X1323655D01*
G02X1323362Y476472I1J400D01*
G03X1321208Y478564I-1102J1020D01*
G02X1320664Y478550I-280J286D01*
G03X1318765Y476488I-926J-1053D01*
G02X1318488Y475800I-278J-288D01*
G01X1303242D01*
G02X1302842Y476206I0J400D01*
G03X1299638I-1602J22D01*
G02X1299238Y475800I-400J-6D01*
G01X1272272D01*
X1272201Y475814D01*
X1272184Y475820D01*
G03X1271083Y475814I-543J-1400D01*
G01X1271047Y475800D01*
X1258958D01*
G03X1257322I-818J-1260D01*
G01X1256481D01*
G03X1254579I-951J-1030D01*
G01X713247D01*
X698842Y490206D01*
Y493447D01*
X698644Y493644D01*
X698545Y493743D01*
Y494300D01*
X697021Y495824D01*
X697124Y495963D01*
G03X694604Y496933I-1124J837D01*
G02X694206Y496570I-398J37D01*
G01X692451D01*
G02X692146Y497229I0J400D01*
G03X689731Y499004I-1147J970D01*
G02X689143Y498907I-337J215D01*
G03X687474Y496422I-940J-1171D01*
G02X687563Y495790I-194J-350D01*
G01X681627Y489854D01*
G02X680979Y489973I-283J283D01*
G03X678611Y490283I-1279J-573D01*
G02X677989I-311J252D01*
G03X675983Y490461I-1089J-883D01*
G02X675423Y490498I-261J303D01*
G03X675343Y488419I-1123J-998D01*
G02X675905Y488413I278J-288D01*
G03X677989Y488517I995J987D01*
G02X678611I311J-252D01*
G03X679127Y488121I1088J884D01*
G02X679246Y487473I-164J-365D01*
G01X678632Y486859D01*
X678502Y486928D01*
G03X677870Y487100I-701J-1328D01*
G03X676759Y486683I-71J-1500D01*
G02X676242Y486670I-266J299D01*
G03X675644Y486962I-942J-1170D01*
G03X673685Y486126I-564J-1392D01*
G01X673634Y486000D01*
X669528D01*
G03X669472I-28J-1400D01*
G01X667844D01*
G02X667546Y486666I0J400D01*
G03X665454I-1046J934D01*
G02X665156Y486000I-298J-266D01*
G01X657935D01*
G02X657549Y486505I0J400D01*
G03X657120Y488003I-1449J395D01*
G02X657093Y488564I271J294D01*
G03X657220Y488728I-1042J938D01*
G01X657299Y488847D01*
X657662Y488752D01*
X657672Y488609D01*
G03X658073Y489694I1398J100D01*
G02X657402Y489870I-285J281D01*
G03X655043Y488524I-1352J-370D01*
G02X655039Y487963I-287J-278D01*
G03X654651Y486505I1061J-1063D01*
G02X654265Y486000I-386J-105D01*
G01X641875D01*
G03X640425I-725J-1200D01*
G01X630323D01*
X630298Y486006D01*
X630252Y486016D01*
G03X629608I-322J-1466D01*
G01X629562Y486006D01*
X629537Y486000D01*
X627845D01*
X627812Y486012D01*
G03X626788I-512J-1412D01*
G01X626755Y486000D01*
X606792D01*
G02X606470Y486636I1J400D01*
G03X603882I-1294J945D01*
G02X603560Y486000I-323J-236D01*
G01X69500D01*
X67450Y488050D01*
X67050D01*
X61253Y493847D01*
G02X61240Y494399I283J283D01*
G03X59259Y496380I-1038J943D01*
G02X58707Y496393I-269J296D01*
G01X54698Y500402D01*
G02X54753Y501014I283J283D01*
G03X55164Y501438I-852J1237D01*
G02X55836I336J-216D01*
G03X58364I1264J812D01*
G02X59036I336J-216D01*
G03X61112Y503514I1264J812D01*
G02Y504186I216J336D01*
G03Y506714I-812J1264D01*
G02Y507386I216J336D01*
G03X59488I-812J1264D01*
G02Y506714I-216J-336D01*
G03X59036Y506262I812J-1264D01*
G02X58364I-336J216D01*
G03X55836I-1264J-812D01*
G02X55164I-336J216D01*
G03X53088Y504186I-1264J-812D01*
G02Y503514I-216J-336D01*
G03X52664Y503103I813J-1263D01*
G02X52052Y503048I-329J228D01*
G01X30100Y525000D01*
X12037D01*
X11843Y524806D01*
X11709Y524887D01*
G03X9646Y522824I-777J-1286D01*
G01X9727Y522690D01*
X8526Y521489D01*
G02X8409Y521209I-400J3D01*
G01X5736Y518536D01*
G02X5163Y518544I-283J283D01*
G01Y518420D01*
G02X4467Y518152I-400J1D01*
G03Y516134I-1113J-1009D01*
G02X5163Y515866I296J-269D01*
G01Y511242D01*
G02X4603Y510876I-400J0D01*
G03Y508124I-603J-1376D01*
G02X5163Y507758I160J-366D01*
G01Y483396D01*
X5048Y483342D01*
G03X4465Y482853I642J-1358D01*
G02X3813I-326J232D01*
G03X1512Y480936I-1225J-870D01*
G02X1422Y480308I-286J-279D01*
G03X912Y479836I738J-1308D01*
G02X248I-332J223D01*
G03X-215Y480280I-1247J-837D01*
G02X-194Y480974I209J341D01*
G03X-1685Y481020I-705J1326D01*
G02X-1706Y480326I-209J-341D01*
G03X248Y478164I706J-1326D01*
G02X912I332J-223D01*
G03X3117Y477843I1248J836D01*
G02X3736Y477702I255J-308D01*
G03X4909Y476840I1364J628D01*
G01X4981Y476831D01*
X5163Y476634D01*
Y470602D01*
X4970Y470404D01*
X4894Y470398D01*
G03X4252Y470186I106J-1398D01*
G02X3684Y470340I-213J338D01*
G03X3213Y468421I-1334J-690D01*
G02X3788Y468295I230J-328D01*
G03X4894Y467602I1212J705D01*
G01X4970Y467596D01*
X5163Y467398D01*
Y461885D01*
X4202Y460924D01*
G02X3611Y460953I-282J283D01*
G03X1497Y458839I-1161J-953D01*
G02X1526Y458248I-254J-309D01*
G01X709Y457431D01*
X660Y457417D01*
G03X-430Y456327I448J-1538D01*
G01X-444Y456278D01*
X-2400Y454322D01*
G02X-2510Y454046I-400J0D01*
G01X-2400Y453936D01*
Y438483D01*
G02X-2944Y438109I-400J-1D01*
G03X-7748Y431286I-1544J-4015D01*
G01X-7701Y431158D01*
X-7766Y431010D01*
X-7797Y430981D01*
G03X1166Y422600I4174J-4519D01*
G01X11600D01*
X13100Y421100D01*
X29900D01*
X39200Y411800D01*
Y356100D01*
X33600Y350500D01*
X33455D01*
X22216Y339261D01*
G02X21661Y339251I-283J283D01*
G03X18100Y334695I-1976J-2125D01*
G01Y315935D01*
G03Y311073I1585J-2431D01*
G01Y269795D01*
X17937Y269765D01*
G03Y264255I513J-2755D01*
G01X18100Y264225D01*
Y247369D01*
G02X17628Y246976I-400J0D01*
G03Y241464I-508J-2756D01*
G02X18100Y241071I72J-393D01*
G01Y230423D01*
G03X17399Y226205I1585J-2431D01*
G02X17167Y225567I-315J-247D01*
G03X16439Y222800I333J-1567D01*
G02Y222200I-265J-300D01*
G03X17660Y219406I1061J-1200D01*
G02X18100Y219008I40J-398D01*
G01Y213602D01*
G02X17700Y213202I-400J0D01*
G03X16639Y210400I0J-1602D01*
G02Y209800I-265J-300D01*
G03X17370Y207032I1061J-1200D01*
G02X17578Y206366I-82J-391D01*
G03X18100Y201939I2107J-1996D01*
G01Y185887D01*
G03X21079Y171447I128J-7501D01*
G01X21202Y171498D01*
X37616Y155084D01*
X37610Y154994D01*
G03X38565Y153501I1499J-93D01*
G03X38836Y153424I544J1400D01*
G01X39000Y153394D01*
Y99400D01*
X34616Y95016D01*
X34408D01*
X34353Y95061D01*
G03X32447I-953J-1161D01*
G01X32392Y95016D01*
X31908D01*
X31853Y95061D01*
G03X31072Y95392I-953J-1161D01*
G01X17100Y81420D01*
Y81376D01*
X16848Y81125D01*
Y63905D01*
G02X16167Y63621I-400J0D01*
G03X13886Y63423I-1056J-1068D01*
G02X13204Y63473I-326J232D01*
G03X13014Y63761I-1341J-678D01*
G02X13027Y64290I306J257D01*
G03X13057Y66298I-1102J1021D01*
G02Y66824I302J263D01*
G03X10793I-1132J987D01*
G02Y66298I-302J-263D01*
G03X10775Y64344I1132J-988D01*
G02X10762Y63815I-306J-257D01*
G03X13089Y61924I1102J-1021D01*
G02X13771Y61874I326J-232D01*
G03X16167Y61485I1340J679D01*
G02X16848Y61201I281J-284D01*
G01Y60755D01*
X13789Y57696D01*
X13729Y57684D01*
G03X12742Y56993I296J-1473D01*
G02X12073Y56971I-342J208D01*
G03X10879Y57568I-1148J-804D01*
G02X10471Y58031I-13J400D01*
G03X9104Y56769I-1483J236D01*
G02X9532Y56325I31J-399D01*
G03X10280Y54922I1393J-158D01*
G02X10378Y54285I-185J-354D01*
G01X5198Y49105D01*
Y42705D01*
X2795Y40302D01*
X422D01*
G02X166Y41009I0J400D01*
G03X413Y45401I-1916J2311D01*
G03X-3514Y49834I-2333J1889D01*
G02X-4117Y50258I-212J339D01*
G03X-8519Y53518I-2933J642D01*
G03X-8518Y48281I-1468J-2619D01*
G03X-5456Y48356I1468J2619D01*
G02X-4853Y47932I212J-339D01*
G03X-4083Y45209I2933J-641D01*
G03X-3666Y41009I2333J-1889D01*
G02X-3922Y40302I-256J-307D01*
G01X-18869D01*
G02X-19253Y40812I0J400D01*
G03X-19833Y42374I-1347J388D01*
G02X-19817Y43054I219J335D01*
G03X-21206Y45489I-709J1209D01*
G02X-21800Y45839I-194J350D01*
G01Y47140D01*
G02X-21245Y47508I400J-1D01*
G03X-19619Y49692I545J1292D01*
G02X-19574Y50247I309J254D01*
G03X-19723Y52467I-926J1053D01*
G02Y53133I222J333D01*
G03Y55467I-777J1167D01*
G02Y56133I222J333D01*
G03Y58467I-777J1167D01*
G02Y59133I222J333D01*
G03X-21200Y61515I-776J1168D01*
G02X-21800Y61861I-200J346D01*
G01Y587583D01*
X-19647Y589736D01*
X-13129D01*
X-13086Y589714D01*
G03X-11814I636J1251D01*
G01X-11771Y589736D01*
X-72D01*
X-47Y589565D01*
G03X2925I1486J218D01*
G01X2950Y589736D01*
X15628D01*
X15643Y589552D01*
G03X15653Y589464I1497J126D01*
G01X15666Y589376D01*
X15503Y589180D01*
X15437Y589165D01*
G03X15352Y586257I333J-1465D01*
G02X15633Y585797I-112J-384D01*
G03X15638Y585205I1475J-284D01*
G02X15484Y584968I-196J-41D01*
G03X15377Y582059I316J-1468D01*
G02X15662Y581634I-113J-384D01*
G03X15670Y581261I1494J-155D01*
G01X15683Y581173D01*
X15522Y580978D01*
X15456Y580962D01*
G03X15342Y578070I344J-1462D01*
G02X15615Y577628I-122J-381D01*
G03Y577172I1485J-228D01*
G02X15342Y576730I-395J-61D01*
G03X15373Y573860I458J-1430D01*
G02X15655Y573415I-113J-384D01*
G03X16007Y572196I1484J-232D01*
G02Y571670I-302J-263D01*
G03X18271I1132J-987D01*
G02Y572196I302J263D01*
G03X17566Y574623I-1132J987D01*
G02X17284Y575068I113J384D01*
G03X17285Y575528I-1484J233D01*
G02X17558Y575970I395J61D01*
G03Y578830I-458J1430D01*
G02X17285Y579272I122J381D01*
G03X17286Y579719I-1485J227D01*
G01X17273Y579808D01*
X17434Y580003D01*
X17500Y580019D01*
G03X17579Y582922I-344J1462D01*
G02X17294Y583347I113J384D01*
G03X17270Y583808I-1494J153D01*
G02X17424Y584045I196J41D01*
G03X17526Y586956I-316J1468D01*
G02X17245Y587416I112J384D01*
G03X17256Y587919I-1475J284D01*
G01X17243Y588007D01*
X17406Y588203D01*
X17472Y588218D01*
G03X18112Y590827I-333J1465D01*
G02X18089Y591415I259J305D01*
G01X26799Y600125D01*
X41958D01*
G02X42231Y599433I0J-400D01*
G03X44149I959J-1023D01*
G02X44422Y600125I273J292D01*
G01X54875D01*
X61500Y593500D01*
Y536621D01*
G03X63159Y534150I1000J-1121D01*
G01X63287Y534213D01*
X93500Y504000D01*
X383831D01*
X383856Y503828D01*
G03X386632I1388J199D01*
G01X386657Y504000D01*
X617400D01*
X651600Y538200D01*
X714450D01*
X719175Y533475D01*
Y530125D01*
X744800Y504500D01*
X762930D01*
X762964Y504487D01*
G03X764036I536J1403D01*
G01X764070Y504500D01*
X1034318D01*
G02X1034636Y503857I0J-400D01*
G03X1036864I1114J-851D01*
G02X1037182Y504500I318J243D01*
G01X1266182D01*
G02X1266329Y504472I0J-400D01*
G01X1269572D01*
G02X1269718Y504500I147J-372D01*
G01X1325900D01*
X1330362Y508962D01*
G02X1331035Y508768I283J-283D01*
G03X1331524Y507958I1465J332D01*
G02X1331545Y507369I-260J-304D01*
G03X1334070Y505991I1055J-1069D01*
G02X1334596Y506285I391J-83D01*
G03X1334522Y509086I504J1415D01*
G02X1333976Y509381I-153J369D01*
G03X1332342Y510594I-1476J-281D01*
G02X1331900Y510991I-42J398D01*
G01Y561688D01*
G02X1332461Y562054I400J0D01*
G03X1333999Y562327I565J1283D01*
G02X1334553I277J-288D01*
G03X1336499I973J1010D01*
G02X1337053I277J-288D01*
G03X1338999I973J1010D01*
G02X1339553I277J-288D01*
G03X1341499I973J1010D01*
G02X1342053I277J-288D01*
G03X1342865Y561944I973J1010D01*
G02X1343217Y561509I-46J-397D01*
G03X1343603Y560403I1396J-133D01*
G02Y559849I-288J-277D01*
G03Y557903I1010J-973D01*
G02Y557349I-288J-277D01*
G03Y555403I1010J-973D01*
G02Y554849I-288J-277D01*
G03X1345866Y553247I1010J-972D01*
G02X1346551Y553297I357J-180D01*
G03X1346447Y554729I1149J803D01*
G02X1345762Y554679I-357J180D01*
G03X1345623Y554849I-1152J-800D01*
G02Y555403I288J277D01*
G03Y557349I-1010J973D01*
G02Y557903I288J277D01*
G03Y559849I-1010J973D01*
G02Y560403I288J277D01*
G03X1344774Y562769I-1010J973D01*
G02X1344422Y563204I46J397D01*
G03X1343852Y564470I-1396J133D01*
G02X1343869Y565127I236J323D01*
G03X1342166Y567346I-769J1173D01*
G02X1341634I-266J298D01*
G03X1339650Y567229I-934J-1046D01*
G02X1339050I-300J265D01*
G03X1337012Y567294I-1050J-929D01*
G02X1336462Y567280I-282J284D01*
G03X1334553Y567247I-937J-1043D01*
G02X1333999I-277J288D01*
G03X1332461Y567520I-973J-1010D01*
G02X1331900Y567886I-161J366D01*
G01Y623000D01*
X1333224Y624324D01*
X1392200D01*
Y624184D01*
X1393160Y623224D01*
Y604440D01*
X1400300Y597300D01*
X1409400D01*
X1413300Y593400D01*
X1425600D01*
X1435575Y603375D01*
Y623041D01*
X1436858Y624324D01*
X1440476D01*
G02X1440859Y623808I0J-400D01*
G03X1443367Y622623I1341J-408D01*
G02X1444033I333J-222D01*
G03X1446367I1167J777D01*
G02X1447033I333J-222D01*
G03X1449388Y622656I1167J777D01*
G02X1450080Y622633I339J-212D01*
G03X1452629Y623785I1234J665D01*
G02X1453004Y624324I375J139D01*
G01X1453276D01*
G02X1453659Y623808I0J-400D01*
G03X1456167Y622623I1341J-408D01*
G02X1456833I333J-222D01*
G03X1459167I1167J777D01*
G02X1459833I333J-222D01*
G03X1462341Y623808I1167J777D01*
G02X1462724Y624324I383J116D01*
G01X1550349D01*
G02X1550738Y623830I0J-400D01*
G03X1553658I1460J-351D01*
G02X1554047Y624324I389J94D01*
G01X1555709D01*
G02X1556101Y623847I-1J-400D01*
G03X1558832Y622737I1474J-288D01*
G02X1559499Y622740I334J-219D01*
G03X1562224Y623851I1248J836D01*
G02X1562617Y624324I393J73D01*
G01X1564697D01*
G02X1565080Y623810I0J-400D01*
G03X1567689Y622439I1440J-428D01*
G02X1568315Y622436I312J-251D01*
G03X1570931Y623806I1180J929D01*
G02X1571313Y624324I382J118D01*
G01X1839260D01*
X1839600Y623984D01*
Y605900D01*
X1849350Y596150D01*
X1858750D01*
X1861000Y593900D01*
X1874300D01*
X1874350Y593950D01*
X1875750D01*
X1879416Y597616D01*
G02X1879565Y597710I283J-283D01*
G01X1881170Y599315D01*
G02X1881264Y599464I377J-134D01*
G01X1883700Y601900D01*
Y605300D01*
X1885500Y607100D01*
Y623311D01*
X1886513Y624324D01*
X1966869D01*
X1974067Y617126D01*
Y598981D01*
G02X1973527Y598607I-400J0D01*
G03Y595793I-527J-1407D01*
G02X1974067Y595419I140J-374D01*
G01Y578037D01*
G02X1973464Y577693I-400J1D01*
G03Y575107I-764J-1293D01*
G02X1974067Y574763I203J-345D01*
G01Y566893D01*
G02X1973485Y566537I-400J0D01*
G03Y563863I-685J-1337D01*
G02X1974067Y563507I182J-356D01*
G01Y554220D01*
G02X1973452Y553883I-400J0D01*
G03X1971735Y551683I-752J-1183D01*
G02X1971721Y551089I-275J-291D01*
G03X1973464Y548657I979J-1139D01*
G02X1974067Y548313I203J-345D01*
G01Y538493D01*
G02X1973485Y538137I-400J0D01*
G03Y535463I-685J-1337D01*
G02X1974067Y535107I182J-356D01*
G01Y495567D01*
X1973000Y494500D01*
X1971323D01*
G02X1971097Y495230I0J400D01*
G03X1970868Y500661I-1806J2644D01*
G02X1970940Y501389I197J348D01*
G03X1969487Y501751I-440J1331D01*
G02X1969208Y501075I-289J-276D01*
G03X1967485Y495230I83J-3201D01*
G02X1967259Y494500I-226J-330D01*
G01X1937936D01*
G02X1937549Y495001I0J400D01*
G03X1931784Y496960I-2952J775D01*
G01X1927567D01*
G03X1921941I-2813J-1185D01*
G01X1920988D01*
X1920948Y497000D01*
X1917706D01*
G03X1912666Y493708I-2795J-1224D01*
G02X1912654Y493154I-295J-271D01*
G01X1912000Y492500D01*
Y474000D01*
X1919000Y467000D01*
Y465500D01*
X1917500Y464000D01*
X1909000D01*
X1906000Y467000D01*
X1882698D01*
X1882681Y467181D01*
G03X1879889I-1396J-132D01*
G01X1879872Y467000D01*
X1870013D01*
G02X1869625Y467496I0J400D01*
G03X1866709I-1458J359D01*
G02X1866321Y467000I-388J-96D01*
G01X1862688D01*
G03X1859912I-1388J-200D01*
G01X1858868D01*
G03X1856092I-1388J-200D01*
G01X1846735D01*
X1846702Y467159D01*
G03X1844885Y468200I-1372J-289D01*
G02X1844358Y468590I-127J379D01*
G03X1841711Y467659I-1501J40D01*
G02X1841407Y467000I-305J-259D01*
G01X1839307D01*
G02X1839003Y467659I1J400D01*
G03X1836355Y468627I-1146J971D01*
G02X1835865Y468236I-400J-1D01*
G03X1834178Y467159I-315J-1366D01*
G01X1834145Y467000D01*
X1833714D01*
X1833693Y467176D01*
G03X1830909I-1392J-171D01*
G01X1830888Y467000D01*
X1824265D01*
X1824244Y467176D01*
G03X1821627Y467686I-1392J-171D01*
G02X1820927I-350J194D01*
G03X1818310Y467176I-1225J-681D01*
G01X1818289Y467000D01*
X1811667D01*
X1811646Y467176D01*
G03X1809029Y467686I-1392J-171D01*
G02X1808329I-350J194D01*
G03X1805712Y467176I-1225J-681D01*
G01X1805691Y467000D01*
X1799068D01*
X1799047Y467176D01*
G03X1796430Y467686I-1392J-171D01*
G02X1795730I-350J194D01*
G03X1795113Y468268I-1225J-681D01*
G01X1795000Y468323D01*
Y472615D01*
X1794996Y472618D01*
Y474804D01*
X1795190Y475002D01*
X1795265Y475007D01*
G03X1795994Y477536I-101J1399D01*
G02X1795968Y478160I236J322D01*
G03X1796477Y479131I-993J1140D01*
G01X1796486Y479215D01*
Y479310D01*
G03X1795170Y480799I-1511J-10D01*
G01X1794996Y480822D01*
Y487164D01*
G02X1795549Y487533I400J-1D01*
G03X1796124Y487418I578J1397D01*
G01X1801125D01*
G03X1802627Y488761I0J1512D01*
G01X1802636Y488845D01*
Y488940D01*
G03X1802041Y490132I-1511J-10D01*
G02X1802027Y490756I243J318D01*
G03X1802042Y490769I-911J1066D01*
G02X1802639Y490684I261J-303D01*
G03X1805196Y490741I1261J816D01*
G02X1805859Y490781I345J-202D01*
G03X1806073Y490556I1117J848D01*
G02X1806059Y489932I-257J-306D01*
G03X1806975Y487218I916J-1202D01*
G01X1811975D01*
G03X1813477Y488561I0J1512D01*
G01X1813486Y488645D01*
Y488740D01*
G03X1812891Y489932I-1511J-10D01*
G02X1812877Y490556I243J318D01*
G03X1810803Y490861I-902J1074D01*
G02X1810469Y490242I-335J-219D01*
G01X1808481D01*
G02X1808147Y490861I1J400D01*
G03X1805792Y492382I-1172J769D01*
G02X1805127Y492366I-338J214D01*
G03X1802866Y492589I-1227J-866D01*
G02X1802265Y492646I-276J290D01*
G03X1799953Y491061I-1140J-816D01*
G02X1799619Y490442I-335J-219D01*
G01X1797631D01*
G02X1797297Y491061I1J400D01*
G03X1795558Y493112I-1172J769D01*
G02X1794996Y493478I-162J366D01*
G01Y494122D01*
X1795000Y494126D01*
Y496501D01*
G02X1795622Y496834I400J0D01*
G03X1795373Y498956I778J1167D01*
G01X1795344Y498924D01*
X1795277Y498897D01*
G02X1795000Y499082I-77J185D01*
G01Y499100D01*
X1791850Y502250D01*
X1739888D01*
G02X1739529Y502826I0J400D01*
G03X1736944Y502634I-1349J661D01*
G02X1736841Y502330I-165J-114D01*
G03X1736680Y502268I458J-1430D01*
G01X1736640Y502250D01*
X1735632D01*
G02X1735232Y502650I0J400D01*
G03X1732428I-1402J0D01*
G02X1732028Y502250I-400J0D01*
G01X1730501D01*
G02X1730101Y502639I0J400D01*
G03X1727299I-1401J-39D01*
G02X1726899Y502250I-400J11D01*
G01X1726604D01*
X1726551Y502289D01*
G03X1724598Y502250I-951J-1289D01*
G01X1720989D01*
X1720937Y502370D01*
G03X1718587Y500626I-1377J-600D01*
G02X1718611Y500038I-259J-305D01*
G01X1714298Y495725D01*
X1677775D01*
X1674879Y492829D01*
G02X1674746Y492741I-283J283D01*
G01X1673318Y491313D01*
G02X1673230Y491180I-371J150D01*
G01X1673076Y491026D01*
G02X1672406Y491207I-283J282D01*
G03X1670665Y489502I-1356J-357D01*
G02X1670838Y488835I-110J-385D01*
G01X1669806Y487803D01*
X1669820Y487770D01*
X1656700Y474650D01*
Y474260D01*
X1648713Y466273D01*
X1648665D01*
X1648653Y466213D01*
X1647688Y465248D01*
Y454298D01*
G02X1647112Y453939I-400J0D01*
G03X1645326Y451595I-661J-1349D01*
G02X1645330Y451069I-299J-265D01*
G03X1645360Y449078I1139J-979D01*
G02X1645371Y448552I-296J-269D01*
G03X1647128Y446214I1154J-962D01*
G02X1647688Y445848I160J-366D01*
G01Y445602D01*
G02X1647118Y445240I-400J0D01*
G03X1645480Y442759I-638J-1360D01*
G02X1645508Y442190I-266J-298D01*
G03X1647122Y439965I1031J-950D01*
G02X1647688Y439601I166J-364D01*
G01Y432349D01*
G02X1647270Y431950I-400J1D01*
G03X1647268Y428950I-70J-1500D01*
G02X1647686Y428551I18J-400D01*
G01Y427859D01*
X1634097Y414270D01*
X1634044Y414256D01*
G03X1633044Y413256I356J-1356D01*
G01X1633030Y413203D01*
X1631373Y411546D01*
Y406689D01*
G02X1630926Y406292I-400J0D01*
G03Y403308I-176J-1492D01*
G02X1631373Y402911I47J-397D01*
G01Y402684D01*
X1631135D01*
X1631100Y402698D01*
G03X1629450Y400277I-550J-1398D01*
G02X1629433Y399715I-293J-272D01*
G03X1629703Y397484I967J-1015D01*
G02X1629663Y396770I-199J-347D01*
G03X1629651Y393835I637J-1470D01*
G02X1629681Y393119I-162J-365D01*
G03X1630853Y390368I719J-1319D01*
G02X1631373Y389987I120J-382D01*
G01Y383034D01*
G02X1630768Y382691I-400J0D01*
G03X1629356Y380043I-767J-1291D01*
G02X1629507Y379446I-172J-361D01*
G03X1629862Y377201I1293J-946D01*
G02X1629911Y376593I-234J-325D01*
G03X1630957Y374199I989J-993D01*
G02X1631373Y373800I16J-400D01*
G01Y369467D01*
G02X1630810Y369102I-400J0D01*
G03X1629131Y366675I-610J-1372D01*
G02X1629140Y366121I-284J-282D01*
G03X1629147Y364068I1100J-1023D01*
G02X1629168Y363543I-291J-275D01*
G03X1629262Y361551I1169J-943D01*
G02X1629291Y361026I-286J-279D01*
G03X1629370Y359087I1185J-923D01*
G02X1629371Y358547I-295J-271D01*
G03X1629472Y356559I1037J-944D01*
G02X1629485Y355975I-267J-298D01*
G03X1630867Y353435I1049J-1075D01*
G02X1631356Y353045I89J-390D01*
G01Y347373D01*
G02X1630650Y347115I-400J0D01*
G03Y345177I-1147J-969D01*
G02X1631356Y344919I306J-258D01*
G01Y344116D01*
G03Y342176I1147J-970D01*
G01Y341373D01*
G02X1630650Y341115I-400J0D01*
G03Y339177I-1147J-969D01*
G02X1631356Y338919I306J-258D01*
G01Y330151D01*
G02X1630969Y329751I-400J0D01*
G03Y326949I46J-1401D01*
G02X1631356Y326549I-13J-400D01*
G01Y323256D01*
X1621909Y313809D01*
G37*
G36*
G01X-20621Y661811D02*
G02X-19685Y662747I936J0D01*
G01X1972600D01*
Y637600D01*
X-20412D01*
G02X-20621Y638189I726J589D01*
G01Y661811D01*
G37*
G36*
G01X73172Y185478D02*
Y172950D01*
X79622Y166500D01*
X123800D01*
X127850Y162450D01*
Y126350D01*
X120979Y119479D01*
X93156D01*
G02X92895Y120182I0J400D01*
G03X90931I-982J1136D01*
G02X90670Y119479I-261J-303D01*
G01X79304D01*
G02X78986Y120121I0J400D01*
G03X76594I-1196J909D01*
G02X76276Y119479I-318J-242D01*
G01X69806D01*
G03X67502I-1152J-799D01*
G01X66916D01*
Y122619D01*
G02X67598Y122903I400J0D01*
G03X67357Y124579I986J997D01*
G02X66672Y124554I-350J193D01*
G03X64105Y124501I-1267J-824D01*
G02X63486Y124414I-344J204D01*
G03X62629Y124793I-963J-1019D01*
G02X62277Y125309I30J399D01*
G03X62333Y125581I-1446J440D01*
G01X62342Y125665D01*
Y129100D01*
G02X62963Y129433I400J-1D01*
G03X65126Y130792I774J1169D01*
G02X65557Y131244I396J54D01*
G03X66844Y131777I130J1506D01*
G02X67470Y131759I306J-258D01*
G03X67819Y133770I1122J841D01*
G02X67198Y134103I-221J333D01*
G01Y136324D01*
G02X67828Y136652I400J0D01*
G03X67525Y138660I804J1148D01*
G02X66891Y138664I-315J246D01*
G03X65653Y139261I-1204J-914D01*
G02X65254Y139750I-9J400D01*
G03X62997Y141146I-1366J314D01*
G02X62342Y141454I-255J309D01*
G01Y143401D01*
G02X62995Y143711I400J0D01*
G03X62731Y145606I883J1089D01*
G02X62075Y145609I-327J230D01*
G03X59320Y144750I-1244J-859D01*
G01Y139750D01*
G03X62176Y139060I1511J0D01*
G02X62833Y139141I356J-182D01*
G03X63855Y138662I1056J923D01*
G02X64231Y138155I-9J-400D01*
G03X64176Y137752I1456J-404D01*
G01Y132747D01*
G03X64201Y132475I1511J2D01*
G02X63792Y132003I-393J-72D01*
G03X62706Y131553I-56J-1401D01*
G02X62082Y131599I-294J271D01*
G03X59320Y130750I-1251J-849D01*
G01Y125750D01*
G03X60789Y124239I1512J0D01*
G02X61165Y123741I-12J-400D01*
G03X63278Y122213I1359J-346D01*
G02X63894Y121876I216J-337D01*
G01Y119479D01*
X53080D01*
Y123760D01*
G03X50359Y124656I-1511J-10D01*
G02X49786Y124586I-320J240D01*
G03X48789Y124898I-887J-1086D01*
G02X48368Y125391I-32J399D01*
G03X48402Y125581I-1468J361D01*
G01X48412Y125665D01*
Y130760D01*
G03X48411Y130790I-1511J-35D01*
G02X48831Y131200I400J10D01*
G03X49935Y131655I69J1400D01*
G02X50511Y131671I296J-270D01*
G03X53071Y132581I1058J1079D01*
G01X53080Y132665D01*
Y137760D01*
G03X50364Y138662I-1511J-10D01*
G02X49768Y138614I-319J241D01*
G03X48784Y139002I-968J-1014D01*
G02X48386Y139475I-5J400D01*
G03X48402Y139581I-1486J278D01*
G01X48412Y139665D01*
Y144760D01*
G03X45830Y145818I-1512J-10D01*
G02X45270Y145812I-283J283D01*
G03X44836Y143504I-970J-1012D01*
G02X45388Y143135I152J-369D01*
G01Y141020D01*
G02X44814Y140661I-400J1D01*
G03X45319Y138555I-614J-1261D01*
G02X45902Y138615I319J-241D01*
G03X46990Y138241I998J1135D01*
G02X47411Y137788I25J-399D01*
G03X49467Y136367I1389J-188D01*
G02X50057Y136016I190J-352D01*
G01Y134235D01*
G02X49489Y133872I-400J0D01*
G03X47499Y132640I-589J-1272D01*
G02X47057Y132253I-400J11D01*
G03X45754Y131736I-158J-1503D01*
G02X45173Y131709I-303J261D01*
G03X44814Y129439I-973J-1010D01*
G02X45388Y129080I174J-360D01*
G01Y127265D01*
G02X44836Y126896I-400J0D01*
G03X45310Y124628I-536J-1296D01*
G02X45871Y124643I288J-278D01*
G03X47084Y124250I1029J1107D01*
G02X47525Y123774I49J-397D01*
G03X49489Y122228I1375J-274D01*
G02X50058Y121865I169J-363D01*
G01Y120485D01*
G02X49467Y120133I-400J0D01*
G03X47523Y119479I-667J-1233D01*
G01X41538D01*
X41050Y119967D01*
Y156400D01*
X23938Y173512D01*
X24074Y173684D01*
X24117Y173739D01*
G03X20350Y185582I-5889J4647D01*
G01Y201541D01*
X20494Y201583D01*
G03X21531Y206609I-809J2787D01*
G02X21569Y207254I254J309D01*
G03X21900Y207539I-870J1345D01*
G02X22500I300J-265D01*
G03X24761Y209800I1200J1061D01*
G02Y210400I265J300D01*
G03X22500Y212661I-1061J1200D01*
G02X21900I-300J265D01*
G03X20740Y213202I-1201J-1061D01*
G02X20350Y213601I10J400D01*
G01Y219199D01*
G02X20544Y219399I200J0D01*
G03X21700Y219939I-44J1601D01*
G02X22300I300J-265D01*
G03X24561Y222200I1200J1061D01*
G02Y222800I265J300D01*
G03X22300Y225061I-1061J1200D01*
G02X21700I-300J265D01*
G03X21571Y225191I-1200J-1061D01*
G02X21578Y225792I267J297D01*
G03X20494Y230779I-1893J2200D01*
G01X20350Y230821D01*
Y242093D01*
G02X21027Y242381I400J0D01*
G03X25497Y243189I1943J2019D01*
G02X26215Y243195I360J-173D01*
G03X26193Y245661I2505J1255D01*
G02X25475Y245655I-360J173D01*
G03X21027Y246419I-2505J-1255D01*
G02X20350Y246707I-277J288D01*
G01Y252721D01*
X20474Y252772D01*
G03Y255552I-570J1390D01*
G01X20350Y255603D01*
Y256389D01*
X20467Y256443D01*
G03Y259357I-667J1457D01*
G01X20350Y259411D01*
Y264951D01*
G03X20977Y265799I-1899J2060D01*
G02X21695Y265805I360J-173D01*
G03X21673Y268271I2505J1255D01*
G02X20955Y268265I-360J173D01*
G03X20350Y269069I-2505J-1255D01*
G01Y310675D01*
X20494Y310717D01*
G03Y316291I-809J2787D01*
G01X20350Y316333D01*
Y334297D01*
X20494Y334339D01*
G03X22544Y337624I-809J2787D01*
G01X22526Y337726D01*
X40350Y355550D01*
Y411650D01*
X40202Y411799D01*
Y412215D01*
X30315Y422102D01*
X29898D01*
X19507Y432493D01*
X19551Y432613D01*
G03X18000Y437604I-4039J1481D01*
G01Y440037D01*
G02X18497Y440425I400J0D01*
G03Y443145I339J1360D01*
G02X18000Y443533I-97J388D01*
G01Y458100D01*
X18600Y458700D01*
X36306D01*
X36316Y458511D01*
G03X43053Y455397I4196J233D01*
G01X44141Y454309D01*
Y454227D01*
X44223D01*
X58900Y439550D01*
Y412228D01*
G02X58272Y411900I-400J0D01*
G03X56198Y410162I-801J-1151D01*
G02X55949Y409611I-363J-168D01*
G03X55227Y409137I434J-1448D01*
G01X53262Y406804D01*
G02X52633Y406826I-306J258D01*
G03X52380Y404909I-1133J-826D01*
G02X52969Y404812I251J-311D01*
G03X55420Y404675I1275J812D01*
G01X55422Y404678D01*
X55438Y404696D01*
X56227Y405632D01*
X56228D01*
X57539Y407189D01*
G03X57885Y407994I-1157J974D01*
G01X57894Y408078D01*
Y408173D01*
G03X57721Y408866I-1511J-9D01*
G02X57941Y409428I354J185D01*
G03X58272Y409598I-469J1321D01*
G02X58900Y409270I228J-328D01*
G01Y396200D01*
X55800Y393100D01*
Y391235D01*
G02X55295Y390849I-400J0D01*
G03Y387951I-395J-1449D01*
G02X55800Y387565I105J-386D01*
G01Y373499D01*
G02X55422Y373100I-400J0D01*
G03X54619Y370609I78J-1400D01*
G02X54645Y370009I-251J-311D01*
G03X55528Y367599I971J-1011D01*
G01X55604Y367594D01*
X55800Y367396D01*
Y343399D01*
X58594Y340605D01*
G02X58551Y340002I-283J-283D01*
G03X58090Y339432I902J-1201D01*
G02X57410Y339356I-363J168D01*
G03X56302Y339902I-1110J-856D01*
G02X55902Y340302I0J400D01*
G03X53096Y339555I-1502J-2D01*
G02X52807Y338961I-347J-198D01*
G03X54151Y338469I218J-1486D01*
G02X54313Y338801I150J132D01*
G03X54480Y338800I92J1499D01*
G02X54900Y338423I21J-399D01*
G03X57552Y337868I1400J77D01*
G02X58233Y337922I357J-180D01*
G03X60654Y337899I1219J878D01*
G02X61257Y337942I320J-240D01*
G01X64400Y334799D01*
Y318402D01*
G02X64000Y318002I-400J0D01*
G03X62904Y315473I0J-1502D01*
G02Y314927I-292J-273D01*
G03X64174Y312408I1096J-1027D01*
G01X64186Y312409D01*
X64400D01*
Y312004D01*
X64259Y311961D01*
G03Y309089I441J-1436D01*
G01X64400Y309046D01*
Y267726D01*
X64402Y267724D01*
Y266667D01*
G03X64300Y266561I1102J-1163D01*
G02X64000I-150J133D01*
G03X61680Y266645I-1200J-1061D01*
G02X61120I-280J286D01*
G03X58546Y264823I-1122J-1144D01*
G01X58555Y264804D01*
X58596Y264627D01*
X58479Y264551D01*
G03X58422Y264495I109J-168D01*
G02X58390Y264450I-1321J906D01*
G03X58370Y264418I159J-122D01*
G01X58305Y264284D01*
X58126Y264314D01*
X58111Y264319D01*
G03X56343Y261807I-511J-1518D01*
G02X56323Y261287I-314J-248D01*
G03X56311Y259126I1177J-1087D01*
G02X56300Y258578I-296J-268D01*
G03X56670Y256053I1144J-1122D01*
G02X56692Y255366I-193J-350D01*
G03X56437Y253039I808J-1266D01*
G02X56414Y252453I-283J-282D01*
G03X56274Y250157I1043J-1216D01*
G02Y249617I-295J-270D01*
G03X55944Y248012I1183J-1080D01*
G02X55508Y247485I-378J-131D01*
G03X53773Y246456I-233J-1585D01*
G02X53319Y246203I-375J139D01*
G03X54506Y244076I-315J-1571D01*
G02X54960Y244329I375J-139D01*
G03X56315Y244682I314J1571D01*
G02X56835I260J-304D01*
G03X59270Y245113I1040J1218D01*
G02X59742Y245297I348J-197D01*
G03X59923Y245282I123J381D01*
G02X60009Y245293I284J-1881D01*
G02X60354Y244635I41J-398D01*
G03X63184Y242095I1447J-1234D01*
G02X63771Y242090I291J-274D01*
G03X64400Y241633I1409J1278D01*
G01Y219625D01*
X64264Y219579D01*
G03Y216545I514J-1517D01*
G01X64400Y216499D01*
Y214381D01*
X64256Y214339D01*
G03X63517Y211720I444J-1539D01*
G02Y211180I-295J-270D01*
G03X64256Y208561I1183J-1080D01*
G01X64400Y208519D01*
Y205631D01*
G02X63895Y205245I-400J0D01*
G03Y199355I-802J-2945D01*
G02X64400Y198969I105J-386D01*
G01Y194250D01*
X73172Y185478D01*
G37*
G36*
G01X69331Y-21500D02*
G02X68939Y-21021I0J400D01*
G03X67139Y-19409I-1375J276D01*
G02X66627Y-19118I-122J381D01*
G03X65505Y-17993I-1463J-338D01*
G01X65350Y-17957D01*
Y-15565D01*
G02X65815Y-15171I400J-1D01*
G03Y-12207I246J1482D01*
G02X65350Y-11813I-65J395D01*
G01Y10563D01*
G03X65376Y11998I-1191J739D01*
G01X65350Y12045D01*
Y12399D01*
G02X65761Y12799I400J0D01*
G03Y15601I39J1401D01*
G02X65350Y16001I-11J400D01*
G01Y16420D01*
X65391Y16474D01*
G03X65350Y18355I-1191J915D01*
G01Y23150D01*
X63287Y25213D01*
X63350Y25341D01*
G03X61341Y27350I-1350J659D01*
G01X61213Y27287D01*
X60787Y27713D01*
X60850Y27841D01*
G03X58841Y29850I-1350J659D01*
G01X58713Y29787D01*
X57600Y30900D01*
Y78500D01*
X59482Y80382D01*
X59620Y80283D01*
G03X61925Y81974I880J1217D01*
G02X62305Y82500I380J126D01*
G01X78500D01*
X84282Y88282D01*
X84322Y88298D01*
G03X85189Y89165I-536J1403D01*
G01X85190Y89166D01*
X85206Y89206D01*
X91500Y95500D01*
X615600D01*
X618900Y92200D01*
Y89416D01*
G03Y87940I1192J-738D01*
G01Y70325D01*
X618886Y70290D01*
G03Y69266I1306J-512D01*
G01X618900Y69231D01*
Y51650D01*
G03Y50106I1170J-772D01*
G01Y48500D01*
X632494Y34906D01*
X632426Y34776D01*
G03X643530Y30052I5367J-2797D01*
G02X644229Y30165I379J-127D01*
G03X644475Y32226I1201J902D01*
G02X643822Y32501I-254J309D01*
G03X643717Y33218I-6030J-517D01*
G02X644108Y33700I391J82D01*
G01X657000D01*
X658000Y32700D01*
Y32227D01*
X657975Y32182D01*
G03X658000Y30775I1225J-682D01*
G01Y26400D01*
X659485Y24915D01*
G02X659313Y24247I-282J-283D01*
G03X660011Y21533I387J-1347D01*
G02X660500Y21143I89J-390D01*
G01Y19200D01*
X667300Y12400D01*
Y430D01*
X664006Y-2864D01*
Y-16342D01*
G02X663405Y-16688I-400J0D01*
G03X661845Y-16789I-705J-1212D01*
G02X661264Y-16688I-244J317D01*
G03X660974Y-18643I-1264J-812D01*
G02X661559Y-18715I259J-304D01*
G03X663405Y-19112I1141J815D01*
G02X664006Y-19458I201J-346D01*
G01Y-20694D01*
X663200Y-21500D01*
X658552D01*
G02X658165Y-21001I0J400D01*
G03X655449I-1358J349D01*
G02X655062Y-21500I-387J-99D01*
G01X438162D01*
G02X437769Y-21025I0J400D01*
G03X435015I-1377J265D01*
G02X434622Y-21500I-393J-75D01*
G01X424667D01*
G02X424273Y-21031I0J400D01*
G03X421511I-1381J242D01*
G02X421117Y-21500I-394J-69D01*
G01X411298D01*
G02X410904Y-21032I0J400D01*
G03X408140I-1382J238D01*
G02X407746Y-21500I-394J-68D01*
G01X69331D01*
G37*
G36*
G01X98100Y192800D02*
X95600Y195300D01*
Y202736D01*
G02X96050Y203132I400J-1D01*
G03Y206312I199J1590D01*
G02X95600Y206708I-50J397D01*
G01Y213800D01*
X96027Y214227D01*
X96081Y214240D01*
G03X98580Y216739I-806J3305D01*
G01X98593Y216793D01*
X101300Y219500D01*
Y221398D01*
G03Y226202I-1800J2402D01*
G01Y237724D01*
G03Y242876I-1542J2576D01*
G01Y291525D01*
G02X101889Y291877I400J-1D01*
G03X104095Y293055I711J1323D01*
G03X101773Y298429I-1773J2423D01*
G02X101300Y298823I-73J393D01*
G01Y301813D01*
G02X101912Y302153I400J1D01*
G03X102099Y302045I1594J2544D01*
G03X104901I1401J55D01*
G03X105824Y306600I-1401J2655D01*
G03X101912Y311047I-2324J1899D01*
G02X101300Y311387I-212J339D01*
G01Y313700D01*
X101997Y314397D01*
G02X102553Y314407I283J-283D01*
G03X106460Y318958I2047J2195D01*
G01Y376460D01*
X95100Y387820D01*
Y427700D01*
X97200Y429800D01*
X126110D01*
G02X126474Y429234I0J-400D01*
G03X126398Y429034I1456J-668D01*
G02X125878Y428774I-383J115D01*
G03X123812Y427786I-550J-1505D01*
G03X117549Y422941I-371J-5991D01*
G03X116303Y418333I4693J-3741D01*
G03X116435Y416365I1060J-917D01*
G02X116505Y415846I-265J-300D01*
G03X116354Y412813I2511J-1645D01*
G03X117331Y409175I2746J-1213D01*
G02X117366Y408557I-236J-323D01*
G03X119919Y403392I2033J-2209D01*
G03X121471Y402615I2062J2181D01*
G02X121690Y401942I-68J-394D01*
G03X123526Y402275I1150J-1115D01*
G02X123496Y402981I172J361D01*
G03X121460Y408529I-1515J2592D01*
G03X121167Y408773I-2063J-2180D01*
G02X121132Y409391I236J323D01*
G03X121762Y412988I-2032J2210D01*
G03X121850Y413210I-2745J1216D01*
G03X126656Y415132I392J5989D01*
G02X127274Y415094I293J-272D01*
G03X129500Y413025I6288J4533D01*
G01Y405650D01*
X133410Y401740D01*
Y400806D01*
X133401Y400777D01*
G03Y399815I1528J-481D01*
G01X133410Y399786D01*
Y205270D01*
X130140Y202000D01*
X119700D01*
X114400Y196700D01*
Y193500D01*
X113700Y192800D01*
X98100D01*
G37*
G36*
G01X96304Y507600D02*
X95896Y508008D01*
X96076Y508189D01*
X96131Y508203D01*
G03X88894Y515842I-1448J5876D01*
G02X88228Y515676I-383J117D01*
G01X65500Y538404D01*
Y621977D01*
X68100Y624577D01*
X355022D01*
G02X355164Y624551I0J-400D01*
G01X358464D01*
G02X358606Y624577I142J-374D01*
G01X385178D01*
G02X385555Y624043I0J-400D01*
G03X388385I1415J-504D01*
G02X388762Y624577I377J134D01*
G01X398132D01*
G02X398507Y624040I-1J-400D01*
G03X401141I1317J-481D01*
G02X401516Y624577I376J137D01*
G01X411632D01*
G02X412007Y624040I-1J-400D01*
G03X414641I1317J-481D01*
G02X415016Y624577I376J137D01*
G01X425638D01*
G02X426012Y624036I0J-400D01*
G03X428636I1312J-495D01*
G02X429010Y624577I374J141D01*
G01X444000D01*
Y624548D01*
X450999D01*
X451000Y624547D01*
Y624577D01*
X451552D01*
G02X451909Y623997I0J-400D01*
G03X454591I1341J-677D01*
G02X454948Y624577I357J180D01*
G01X455212D01*
G02X455569Y623997I0J-400D01*
G03X458251I1341J-677D01*
G02X458608Y624577I357J180D01*
G01X657823D01*
X664000Y618400D01*
Y603800D01*
X667500Y600300D01*
Y589076D01*
X667499Y589064D01*
G03Y588736I1392J-164D01*
G01X667500Y588724D01*
Y571100D01*
X667600Y571000D01*
Y564100D01*
X664400Y560900D01*
X620100D01*
X617700Y558500D01*
Y556538D01*
G03Y555062I1192J-738D01*
G01Y510300D01*
X617251Y509851D01*
X617050Y510052D01*
X617051Y510136D01*
G03X614228Y510871I-1502J21D01*
G02X613524I-352J191D01*
G03X610881I-1321J-714D01*
G02X610178I-352J190D01*
G03X607535I-1321J-714D01*
G02X606831I-352J191D01*
G03X604188I-1321J-714D01*
G02X603485I-352J190D01*
G03Y509443I-1322J-714D01*
G02X604188I351J-190D01*
G03X606831I1322J714D01*
G02X607535I352J-191D01*
G03X610178I1321J714D01*
G02X610881I352J-190D01*
G03X613524I1321J714D01*
G02X614228I352J-191D01*
G03X615222Y508691I1321J714D01*
G02X615418Y508018I-87J-390D01*
G01X615000Y507600D01*
X116144D01*
G02X115944Y507800I0J200D01*
G03X115574Y508787I-1501J0D01*
G02Y509313I302J263D01*
G03X113310I-1132J987D01*
G02Y508787I-302J-263D01*
G03X112940Y507800I1131J-987D01*
G02X112740Y507600I-200J0D01*
G01X96304D01*
G37*
G36*
G01X133422Y202900D02*
G02X133139Y203583I0J400D01*
G01X134412Y204855D01*
Y366148D01*
X169350D01*
X170119Y365379D01*
Y210689D01*
X171283Y209525D01*
X193925D01*
X232100Y247700D01*
X261257Y247681D01*
X262768D01*
G02X263081Y247032I0J-400D01*
G03X265277I1098J-872D01*
G02X265590Y247681I313J249D01*
G01X266517D01*
X266569Y247559D01*
G03X269149I1290J550D01*
G01X269201Y247681D01*
X269828D01*
G02X270141Y247032I0J-400D01*
G03X272337I1098J-872D01*
G02X272650Y247681I313J249D01*
G01X273277D01*
X273329Y247559D01*
G03X275909I1290J550D01*
G01X275961Y247681D01*
X276588D01*
G02X276901Y247032I0J-400D01*
G03X279097I1098J-872D01*
G02X279410Y247681I313J249D01*
G01X280037D01*
X280089Y247559D01*
G03X282669I1290J550D01*
G01X282721Y247681D01*
X286797D01*
X286849Y247559D01*
G03X289429I1290J550D01*
G01X289481Y247681D01*
X293557D01*
X293609Y247559D01*
G03X296189I1290J550D01*
G01X296241Y247681D01*
X300317D01*
X300369Y247559D01*
G03X302949I1290J550D01*
G01X303001Y247681D01*
X307076D01*
X307128Y247559D01*
G03X309708I1290J550D01*
G01X309760Y247681D01*
X310387D01*
G02X310700Y247032I0J-400D01*
G03X312896I1098J-872D01*
G02X313209Y247681I313J249D01*
G01X313836D01*
X313888Y247559D01*
G03X316468I1290J550D01*
G01X316520Y247681D01*
X320596D01*
X320648Y247559D01*
G03X323228I1290J550D01*
G01X323280Y247681D01*
X323907D01*
G02X324220Y247032I0J-400D01*
G03X326416I1098J-872D01*
G02X326729Y247681I313J249D01*
G01X327356D01*
X327408Y247559D01*
G03X329988I1290J550D01*
G01X330040Y247681D01*
X330667D01*
G02X330980Y247032I0J-400D01*
G03X333176I1098J-872D01*
G02X333489Y247681I313J249D01*
G01X334116D01*
X334168Y247559D01*
G03X336748I1290J550D01*
G01X336800Y247681D01*
X340876D01*
X340928Y247559D01*
G03X343508I1290J550D01*
G01X343560Y247681D01*
X344187D01*
G02X344500Y247032I0J-400D01*
G03X346696I1098J-872D01*
G02X347009Y247681I313J249D01*
G01X347636D01*
X347688Y247559D01*
G03X350268I1290J550D01*
G01X350320Y247681D01*
X350946D01*
G02X351259Y247032I0J-400D01*
G03X353455I1098J-872D01*
G02X353768Y247681I313J249D01*
G01X354395D01*
X354447Y247559D01*
G03X357027I1290J550D01*
G01X357079Y247681D01*
X357706D01*
G02X358019Y247032I0J-400D01*
G03X360215I1098J-872D01*
G02X360528Y247681I313J249D01*
G01X361155D01*
X361207Y247559D01*
G03X363787I1290J550D01*
G01X363839Y247681D01*
X364466D01*
G02X364779Y247032I0J-400D01*
G03X366975I1098J-872D01*
G02X367288Y247681I313J249D01*
G01X367915D01*
X367967Y247559D01*
G03X370547I1290J550D01*
G01X370599Y247681D01*
X371226D01*
G02X371539Y247032I0J-400D01*
G03X373735I1098J-872D01*
G02X374048Y247681I313J249D01*
G01X374675D01*
X374727Y247559D01*
G03X377307I1290J550D01*
G01X377359Y247681D01*
X377986D01*
G02X378299Y247032I0J-400D01*
G03X380495I1098J-872D01*
G02X380808Y247681I313J249D01*
G01X382081D01*
X385500Y251100D01*
X407938D01*
X408939Y250099D01*
Y245807D01*
G02X408354Y245452I-400J0D01*
G03Y242966I-648J-1243D01*
G02X408939Y242611I185J-355D01*
G01Y241907D01*
G02X408354Y241552I-400J0D01*
G03Y239066I-648J-1243D01*
G02X408939Y238711I185J-355D01*
G01Y238007D01*
G02X408354Y237652I-400J0D01*
G03Y235166I-648J-1243D01*
G02X408939Y234811I185J-355D01*
G01Y234107D01*
G02X408354Y233752I-400J0D01*
G03Y231266I-648J-1243D01*
G02X408939Y230911I185J-355D01*
G01Y230208D01*
G02X408354Y229853I-400J0D01*
G03Y227367I-648J-1243D01*
G02X408939Y227012I185J-355D01*
G01Y226307D01*
G02X408354Y225952I-400J0D01*
G03Y223466I-648J-1243D01*
G02X408939Y223111I185J-355D01*
G01Y218507D01*
G02X408354Y218152I-400J0D01*
G03Y215666I-648J-1243D01*
G02X408939Y215311I185J-355D01*
G01Y205739D01*
X406100Y202900D01*
X401478D01*
G02X401078Y203291I0J400D01*
G03X398274I-1402J-31D01*
G02X397874Y202900I-400J9D01*
G01X394718D01*
G02X394318Y203291I0J400D01*
G03X391514I-1402J-31D01*
G02X391114Y202900I-400J9D01*
G01X367679D01*
G02X367279Y203291I0J400D01*
G03X364475I-1402J-31D01*
G02X364075Y202900I-400J9D01*
G01X347400D01*
G02X347000Y203291I0J400D01*
G03X344196I-1402J-31D01*
G02X343796Y202900I-400J9D01*
G01X340639D01*
G02X340240Y203291I1J400D01*
G03X337436I-1402J-33D01*
G02X337037Y202900I-400J9D01*
G01X293321D01*
G02X292921Y203291I0J400D01*
G03X290117I-1402J-31D01*
G02X289717Y202900I-400J9D01*
G01X286561D01*
G02X286161Y203291I0J400D01*
G03X283357I-1402J-31D01*
G02X282957Y202900I-400J9D01*
G01X273041D01*
G02X272641Y203291I0J400D01*
G03X269837I-1402J-31D01*
G02X269437Y202900I-400J9D01*
G01X133422D01*
G37*
G36*
G01X134412Y368152D02*
Y402155D01*
X132799Y403767D01*
G02X133082Y404450I283J283D01*
G01X151350D01*
X152003Y403797D01*
X152015Y403736D01*
G03X153128Y402623I1377J264D01*
G01X153189Y402611D01*
X157350Y398450D01*
Y398400D01*
X165550D01*
X168925Y395025D01*
Y369345D01*
X167732Y368152D01*
X134412D01*
G37*
G36*
G01X172492Y210800D02*
X171892Y211400D01*
X171900Y363100D01*
X172500Y363700D01*
X214318D01*
X215661Y362500D01*
X247906Y330255D01*
X266064D01*
G02X266462Y329889I0J-400D01*
G03X269256I1397J120D01*
G02X269654Y330255I398J-34D01*
G01X273086D01*
X273219Y330122D01*
X273217Y330037D01*
G03X274647Y328607I1402J-28D01*
G01X274732Y328609D01*
X277281Y326060D01*
G02X277209Y325437I-283J-283D01*
G03X279276Y323370I790J-1277D01*
G02X279899Y323442I340J-211D01*
G01X280201Y323140D01*
G03X282310Y321031I1178J-931D01*
G01X283267Y320074D01*
X283278Y320011D01*
G03X284510Y318779I1481J249D01*
G01X284573Y318768D01*
X284902Y318439D01*
G02X284650Y317758I-283J-282D01*
G03X286057Y316890I109J-1398D01*
G02X286427Y317441I370J151D01*
G01X287038D01*
G03X289240I1101J868D01*
G01X289851D01*
G02X290221Y316890I0J-400D01*
G03X292817I1298J-530D01*
G02X293187Y317441I370J151D01*
G01X293798D01*
G03X296000I1101J868D01*
G01X296611D01*
G02X296981Y316890I0J-400D01*
G03X299577I1298J-530D01*
G02X299947Y317441I370J151D01*
G01X300558D01*
G03X302760I1101J868D01*
G01X303371D01*
G02X303741Y316890I0J-400D01*
G03X306337I1298J-530D01*
G02X306707Y317441I370J151D01*
G01X307317D01*
G03X309519I1101J868D01*
G01X310130D01*
G02X310500Y316890I0J-400D01*
G03X313096I1298J-530D01*
G02X313466Y317441I370J151D01*
G01X313929D01*
X314032Y317338D01*
X314037Y317332D01*
G03X314201Y317168I1141J977D01*
G01X314207Y317163D01*
X314242Y317128D01*
X314950Y316420D01*
G02X314781Y315754I-283J-283D01*
G03X316523Y314012I397J-1345D01*
G02X317189Y314182I384J-113D01*
G01X317465Y313906D01*
G02X317487Y313365I-283J-282D01*
G03X319463Y311389I1071J-905D01*
G02X320004Y311367I259J-305D01*
G01X320288Y311083D01*
X320580D01*
Y310859D01*
X320575Y310836D01*
G03X323334Y310641I1363J-327D01*
G02X323732Y311078I398J37D01*
G01X325082D01*
X325097Y311076D01*
G03X325539I221J1384D01*
G01X325554Y311078D01*
X326904D01*
G02X327302Y310641I0J-400D01*
G03X330094I1396J-132D01*
G02X330492Y311078I398J37D01*
G01X331842D01*
X331857Y311076D01*
G03X332299I221J1384D01*
G01X332314Y311078D01*
X333664D01*
G02X334062Y310641I0J-400D01*
G03X336603Y311318I1396J-132D01*
G01X336506Y311455D01*
X336959Y311908D01*
G02X337596Y311810I282J-283D01*
G03X338524Y313826I1242J650D01*
G02X338035Y314216I-89J390D01*
G01Y314604D01*
G02X338524Y314994I400J0D01*
G03X339546Y317570I314J1366D01*
G02X339465Y318198I202J345D01*
G01X340794Y319527D01*
Y320726D01*
G02X341421Y321055I400J0D01*
G03Y323363I797J1154D01*
G02X340794Y323692I-227J329D01*
G01Y324627D01*
G02X341421Y324956I400J0D01*
G03X343167Y327142I798J1153D01*
G02X343155Y327719I271J294D01*
G01X343530Y328094D01*
G02X344209Y327867I283J-282D01*
G03X345791Y329449I1389J193D01*
G02X345564Y330128I55J396D01*
G01X346078Y330642D01*
X346116Y330657D01*
G03X346901Y331442I-518J1303D01*
G01X346916Y331480D01*
X348182Y332746D01*
X348313Y332675D01*
G03X350212Y334574I665J1234D01*
G01X350141Y334705D01*
X350577Y335141D01*
G02X351192Y335080I282J-283D01*
G03X353137Y337025I1165J780D01*
G02X353076Y337640I222J333D01*
G01X353657Y338221D01*
G02X354339Y337909I283J-283D01*
G03X356908Y338580I1398J-100D01*
G02X357242Y339200I334J220D01*
G01X357826D01*
X357883Y339095D01*
G03X360435Y340239I1234J665D01*
G01X360391Y340358D01*
X360849Y340816D01*
G02X361435Y340794I283J-283D01*
G03X363412Y342771I1062J915D01*
G02X363390Y343357I261J303D01*
G01X363801Y343768D01*
G02X364482Y343524I283J-283D01*
G03X366013Y345055I1395J136D01*
G02X365769Y345736I39J398D01*
G01X365889Y345856D01*
X367462D01*
G02X367860Y345490I-1J-400D01*
G03X370654I1397J119D01*
G02X371052Y345856I399J-34D01*
G01X374222D01*
G02X374620Y345490I-1J-400D01*
G03X377414I1397J119D01*
G02X377812Y345856I399J-34D01*
G01X380256D01*
X382526Y348126D01*
X382597Y348119D01*
G03X383444Y348276I180J1390D01*
G01X383489Y348300D01*
X403687D01*
G02X404046Y347724I0J-400D01*
G03X406566I1260J-615D01*
G02X406925Y348300I359J176D01*
G01X409169D01*
X410933Y350064D01*
X411021Y350060D01*
G03X412486Y351525I65J1400D01*
G01X412482Y351613D01*
X413780Y352911D01*
X425692D01*
Y352709D01*
G03X428496I1402J-13D01*
G01Y352911D01*
X432452D01*
Y352709D01*
G03X435256I1402J-13D01*
G01Y352911D01*
X439211D01*
Y352709D01*
G03X442015I1402J-13D01*
G01Y352911D01*
X445971D01*
Y352709D01*
G03X448775I1402J-13D01*
G01Y352911D01*
X449485D01*
X449938Y352458D01*
G02X449899Y351859I-283J-282D01*
G03X451865Y349893I854J-1112D01*
G02X452464Y349932I317J-244D01*
G01X452907Y349489D01*
X452851Y349364D01*
G03X453000Y347970I1282J-568D01*
G01Y342100D01*
X452970Y342070D01*
Y337042D01*
X452821Y337003D01*
G03X452213Y336682I379J-1453D01*
G02X451687I-263J302D01*
G03X449670Y336643I-987J-1132D01*
G02X449060Y336717I-274J291D01*
G03X448830Y334807I-1260J-817D01*
G02X449440Y334733I274J-291D01*
G03X451687Y334418I1260J817D01*
G02X452213I263J-302D01*
G03X452821Y334097I987J1132D01*
G01X452970Y334058D01*
Y326163D01*
X452408Y325601D01*
G03X449995Y325450I-1141J-1125D01*
G02X449481Y325344I-318J243D01*
G03X447633Y325149I-787J-1395D01*
G02X447113Y325140I-265J299D01*
G03X447155Y322704I-1019J-1236D01*
G02X447675Y322713I265J-299D01*
G03X448331Y322389I1019J1236D01*
G02X448523Y321716I-90J-390D01*
G01X439307Y312500D01*
X409800D01*
X408400Y311100D01*
Y297689D01*
G02X407819Y297333I-400J0D01*
G03X405894Y296965I-725J-1429D01*
G02X405294I-300J265D01*
G03Y294843I-1200J-1061D01*
G02X405894I300J-265D01*
G03X407819Y294475I1200J1061D01*
G02X408400Y294119I181J-356D01*
G01Y280695D01*
G02X407819Y280339I-400J0D01*
G03X405894Y279971I-725J-1429D01*
G02X405294I-300J265D01*
G03X402794Y279846I-1200J-1061D01*
G02X402144Y279847I-325J234D01*
G03X402142Y277978I-1302J-933D01*
G02X402792Y277977I325J-234D01*
G03X405294Y277849I1302J933D01*
G02X405894I300J-265D01*
G03X407819Y277481I1200J1061D01*
G02X408400Y277125I181J-356D01*
G01Y266859D01*
G02X407919Y266468I-400J1D01*
G03X406394Y265960I-325J-1569D01*
G02X405794I-300J265D01*
G03Y263838I-1200J-1061D01*
G02X406394I300J-265D01*
G03X407919Y263330I1200J1061D01*
G02X408400Y262939I81J-392D01*
G01Y253100D01*
X407600Y252300D01*
X384675D01*
X381359Y248984D01*
X381067D01*
G02X380697Y249534I1J400D01*
G03X378097I-1300J526D01*
G02X377727Y248984I-371J-150D01*
G01X377112D01*
G03X374922I-1095J-875D01*
G01X374307D01*
G02X373937Y249534I1J400D01*
G03X371337I-1300J526D01*
G02X370967Y248984I-371J-150D01*
G01X370478D01*
G03X368036I-1221J-875D01*
G01X367655D01*
G02X367281Y249526I0J400D01*
G03X364473I-1404J534D01*
G02X364099Y248984I-374J-142D01*
G01X363718D01*
G03X361276I-1221J-875D01*
G01X360895D01*
G02X360521Y249526I0J400D01*
G03X357713I-1404J534D01*
G02X357339Y248984I-374J-142D01*
G01X356832D01*
G03X354642I-1095J-875D01*
G01X354135D01*
G02X353761Y249526I0J400D01*
G03X350953I-1404J534D01*
G02X350579Y248984I-374J-142D01*
G01X350073D01*
G03X347883I-1095J-875D01*
G01X347376D01*
G02X347002Y249526I0J400D01*
G03X344194I-1404J534D01*
G02X343820Y248984I-374J-142D01*
G01X343313D01*
G03X341123I-1095J-875D01*
G01X340508D01*
G02X340138Y249534I1J400D01*
G03X337538I-1300J526D01*
G02X337168Y248984I-371J-150D01*
G01X336553D01*
G03X334363I-1095J-875D01*
G01X333748D01*
G02X333378Y249534I1J400D01*
G03X330778I-1300J526D01*
G02X330408Y248984I-371J-150D01*
G01X329793D01*
G03X327603I-1095J-875D01*
G01X326988D01*
G02X326618Y249534I1J400D01*
G03X324018I-1300J526D01*
G02X323648Y248984I-371J-150D01*
G01X323033D01*
G03X320843I-1095J-875D01*
G01X320336D01*
G02X319962Y249526I0J400D01*
G03X317154I-1404J534D01*
G02X316780Y248984I-374J-142D01*
G01X316399D01*
G03X313957I-1221J-875D01*
G01X309639D01*
G03X307197I-1221J-875D01*
G01X306709D01*
G02X306339Y249534I1J400D01*
G03X303739I-1300J526D01*
G02X303369Y248984I-371J-150D01*
G01X302754D01*
G03X300564I-1095J-875D01*
G01X299949D01*
G02X299579Y249534I1J400D01*
G03X296979I-1300J526D01*
G02X296609Y248984I-371J-150D01*
G01X295994D01*
G03X293804I-1095J-875D01*
G01X293189D01*
G02X292819Y249534I1J400D01*
G03X290219I-1300J526D01*
G02X289849Y248984I-371J-150D01*
G01X289234D01*
G03X287044I-1095J-875D01*
G01X286429D01*
G02X286059Y249534I1J400D01*
G03X283459I-1300J526D01*
G02X283089Y248984I-371J-150D01*
G01X282474D01*
G03X280284I-1095J-875D01*
G01X279669D01*
G02X279299Y249534I1J400D01*
G03X276699I-1300J526D01*
G02X276329Y248984I-371J-150D01*
G01X275714D01*
G03X273524I-1095J-875D01*
G01X272909D01*
G02X272539Y249534I1J400D01*
G03X269939I-1300J526D01*
G02X269569Y248984I-371J-150D01*
G01X268954D01*
G03X266764I-1095J-875D01*
G01X265849D01*
G02X265479Y249534I1J400D01*
G03X262879I-1300J526D01*
G02X262509Y248984I-371J-150D01*
G01X262102D01*
X262086Y249000D01*
X231800D01*
X193600Y210800D01*
X172492D01*
G37*
G36*
G01X323553Y312293D02*
X323546Y312300D01*
X320487D01*
X319891Y312896D01*
X319876Y312938D01*
G03X319035Y313778I-1318J-478D01*
G01X318994Y313793D01*
X314950Y317836D01*
X314344Y318442D01*
X309823D01*
X309789Y318601D01*
G03X307047I-1371J-292D01*
G01X307013Y318442D01*
X303064D01*
X303030Y318601D01*
G03X300288I-1371J-292D01*
G01X300254Y318442D01*
X299693D01*
G02X299410Y319126I-1J400D01*
G03X297148I-1131J1134D01*
G02X296865Y318442I-282J-284D01*
G01X296304D01*
X296270Y318601D01*
G03X293528I-1371J-292D01*
G01X293494Y318442D01*
X292787D01*
G02X292520Y319141I0J400D01*
G03X290518I-1001J1119D01*
G02X290251Y318442I-267J-299D01*
G01X289544D01*
X289510Y318601D01*
G03X286863Y318890I-1371J-292D01*
G02X286216Y318774I-364J166D01*
G01X285814Y319176D01*
X285927Y319316D01*
G03X283683Y321307I-1168J944D01*
G01X282880Y322110D01*
X282881Y322194D01*
G03X281364Y323711I-1502J15D01*
G01X281280Y323710D01*
X280960Y324030D01*
G02X281273Y324712I282J283D01*
G03X279981Y326004I106J1398D01*
G02X279299Y325691I-399J-31D01*
G01X278714Y326276D01*
G02X278775Y326892I282J283D01*
G03X276831Y328836I-776J1168D01*
G02X276215Y328775I-333J221D01*
G01X275780Y329210D01*
X275852Y329341D01*
G03X273951Y331242I-1233J668D01*
G01X273820Y331170D01*
X273697Y331293D01*
X273021D01*
G02X272626Y331752I0J400D01*
G03X269852I-1387J208D01*
G02X269457Y331293I-395J-59D01*
G01X268423D01*
X268387Y331308D01*
G03X267331I-528J-1299D01*
G01X267295Y331293D01*
X265961D01*
G02X265566Y331752I0J400D01*
G03X262792I-1387J208D01*
G02X262397Y331293I-395J-59D01*
G01X262158D01*
X262151Y331300D01*
X248464D01*
X214564Y365200D01*
X174500D01*
X174490Y365210D01*
X172770D01*
X169960Y368020D01*
Y389872D01*
X172478Y392390D01*
Y404733D01*
X174358Y406613D01*
X223387D01*
X266722Y363278D01*
X275976D01*
X276772Y362482D01*
G03X277321Y361933I1227J678D01*
G01X277942Y361312D01*
G02X277734Y360637I-283J-282D01*
G03X279376Y358995I265J-1377D01*
G02X280051Y359203I393J-75D01*
G01X280388Y358866D01*
G02Y358301I-283J-282D01*
G03X282371Y356318I991J-992D01*
G02X282936I282J-283D01*
G01X283431Y355823D01*
X283402Y355712D01*
G03X285111Y354003I1357J-352D01*
G01X285222Y354032D01*
X287779Y351475D01*
G02X287639Y350819I-283J-283D01*
G03X289449Y349009I500J-1310D01*
G02X290105Y349149I373J-143D01*
G01X290475Y348779D01*
G02X290482Y348503I-141J-142D01*
G03X292831Y347066I1037J-943D01*
G01X292880Y347195D01*
X293542D01*
G02X293843Y346532I0J-400D01*
G03X295955I1056J-923D01*
G02X296256Y347195I301J263D01*
G01X296918D01*
X296967Y347066D01*
G03X299591I1312J494D01*
G01X299640Y347195D01*
X300302D01*
G02X300603Y346532I0J-400D01*
G03X302715I1056J-923D01*
G02X303016Y347195I301J263D01*
G01X303678D01*
X303727Y347066D01*
G03X306351I1312J494D01*
G01X306400Y347195D01*
X307061D01*
G02X307362Y346532I0J-400D01*
G03X309474I1056J-923D01*
G02X309775Y347195I301J263D01*
G01X310334D01*
X310381Y347061D01*
G03X313215I1417J499D01*
G01X313262Y347195D01*
X316805D01*
X320774Y343226D01*
G02X320795Y342684I-283J-282D01*
G03X322913Y340566I1143J-975D01*
G02X323455Y340545I260J-304D01*
G01X323944Y340056D01*
X323930Y339957D01*
G03X326602Y339198I1388J-196D01*
G01X326655Y339318D01*
X327278D01*
G02X327593Y338672I0J-400D01*
G03X329803I1105J-863D01*
G02X330118Y339318I315J246D01*
G01X330741D01*
X330794Y339198D01*
G03X333362I1284J562D01*
G01X333415Y339318D01*
X334038D01*
G02X334353Y338672I0J-400D01*
G03X336563I1105J-863D01*
G02X336878Y339318I315J246D01*
G01X337501D01*
X337554Y339198D01*
G03X339206Y338407I1284J562D01*
G01X339318Y338437D01*
X339792Y337963D01*
Y337575D01*
G02X339269Y337194I-400J0D01*
G03Y334526I-431J-1334D01*
G02X339792Y334145I123J-381D01*
G01Y333675D01*
G02X339269Y333294I-400J0D01*
G03Y330626I-431J-1334D01*
G02X339792Y330245I123J-381D01*
G01Y319942D01*
X337958Y318107D01*
X337034Y317183D01*
Y317170D01*
X336700Y316836D01*
Y313204D01*
X335789Y312293D01*
X333484D01*
X333480Y312489D01*
G03X330676I-1402J-29D01*
G01X330672Y312293D01*
X326724D01*
X326720Y312489D01*
G03X323916I-1402J-29D01*
G01X323912Y312293D01*
X323553D01*
G37*
G36*
G01X327010Y340490D02*
X322914Y344586D01*
X323027Y344726D01*
G03X321055Y346698I-1089J883D01*
G02X320788Y346712I-126J156D01*
G01X318500Y349000D01*
X316977D01*
G02X316577Y349424I-1J400D01*
G03X313779I-1399J85D01*
G02X313379Y349000I-399J-24D01*
G01X310217D01*
G02X309817Y349424I-1J400D01*
G03X307019I-1399J85D01*
G02X306619Y349000I-399J-24D01*
G01X293500D01*
X289488Y353012D01*
X289511Y353118D01*
G03X287848Y354781I-1372J291D01*
G01X287742Y354758D01*
X285181Y357319D01*
G02X285308Y357970I283J283D01*
G03X283469Y359809I-549J1290D01*
G02X282818Y359682I-368J156D01*
G01X282464Y360036D01*
G02X282452Y360307I141J142D01*
G03X280477Y362282I-1073J902D01*
G02X280206Y362294I-129J153D01*
G01X279402Y363098D01*
X279401Y363179D01*
G03X278018Y364562I-1402J-19D01*
G01X277937Y364563D01*
X275500Y367000D01*
X265500D01*
X242676Y389824D01*
Y400654D01*
X247522Y405500D01*
X431400D01*
X432400Y406500D01*
X445200D01*
X446500Y405200D01*
X450880D01*
X451975Y404105D01*
Y395281D01*
X451950Y395256D01*
Y391363D01*
G02X451373Y391004I-400J0D01*
G03Y388490I-620J-1257D01*
G02X451950Y388131I177J-359D01*
G01Y383563D01*
G02X451373Y383204I-400J0D01*
G03Y380690I-620J-1257D01*
G02X451950Y380331I177J-359D01*
G01Y375762D01*
G02X451373Y375403I-400J0D01*
G03Y372889I-620J-1257D01*
G02X451950Y372530I177J-359D01*
G01Y371863D01*
G02X451373Y371504I-400J0D01*
G03Y368990I-620J-1257D01*
G02X451950Y368631I177J-359D01*
G01Y364063D01*
G02X451373Y363704I-400J0D01*
G03Y361190I-620J-1257D01*
G02X451950Y360831I177J-359D01*
G01Y357950D01*
X448500Y354500D01*
X445401D01*
X445394Y354693D01*
G03X442592I-1401J-46D01*
G01X442585Y354500D01*
X412828D01*
G02X412442Y355002I1J400D01*
G03X410995Y353961I-1356J358D01*
G01X411070Y353956D01*
X411264Y353761D01*
X410854Y353351D01*
X410851D01*
X407500Y350000D01*
X384096D01*
X384042Y350114D01*
G03X381512I-1265J-605D01*
G01X381458Y350000D01*
X380854D01*
G02X380531Y350635I0J400D01*
G03X378618Y350294I-1134J825D01*
G02X378679Y349679I-222J-333D01*
G01X377500Y348500D01*
X377200D01*
Y348754D01*
X377227Y348801D01*
G03X374698Y349035I-1210J708D01*
G02X374321Y348500I-377J-135D01*
G01X373677D01*
G03X371597I-1040J-940D01*
G01X370953D01*
G02X370576Y349035I0J400D01*
G03X367938I-1319J474D01*
G02X367561Y348500I-377J-135D01*
G01X367348D01*
X367345Y348497D01*
X366923D01*
X366865Y348555D01*
G03X364834Y348497I-988J-995D01*
G01X364297D01*
X362964Y347164D01*
Y346989D01*
X362747D01*
X362731Y346991D01*
G03X361115Y345374I-234J-1382D01*
G01X361132Y345272D01*
X360590Y344730D01*
G02X360043Y344713I-283J283D01*
G03X358064Y342734I-926J-1053D01*
G02X358047Y342187I-300J-264D01*
G01X357759Y341899D01*
G02X357090Y342077I-283J283D01*
G03X354484Y341080I-1353J-368D01*
G02X354127Y340500I-357J-180D01*
G01X353824D01*
X353814Y340490D01*
X353558D01*
X353499Y340574D01*
G03X351160Y340490I-1142J-814D01*
G01X350583D01*
G02X350227Y341072I0J400D01*
G03X347729I-1249J637D01*
G02X347373Y340490I-356J-182D01*
G01X346795D01*
G03X344401I-1197J-730D01*
G01X343823D01*
G02X343467Y341072I0J400D01*
G03X340969I-1249J637D01*
G02X340613Y340490I-356J-182D01*
G01X340035D01*
G03X337641I-1197J-730D01*
G01X337063D01*
G02X336707Y341072I0J400D01*
G03X334209I-1249J637D01*
G02X333853Y340490I-356J-182D01*
G01X333275D01*
G03X330881I-1197J-730D01*
G01X330303D01*
G02X329947Y341072I0J400D01*
G03X327449I-1249J637D01*
G02X327093Y340490I-356J-182D01*
G01X327010D01*
G37*
G36*
G01X604050Y162150D02*
X572500Y193700D01*
X413200D01*
X410382Y196518D01*
Y203966D01*
X410402Y205785D01*
Y252102D01*
X410383Y262938D01*
G02X410864Y263330I400J0D01*
G03X412388Y263838I324J1569D01*
G02X412988I300J-265D01*
G03X415389Y263839I1200J1061D01*
G02X415989I300J-265D01*
G03X418390Y263837I1201J1060D01*
G02X418988I299J-265D01*
G03X421274Y263721I1200J1062D01*
G02X421854Y263681I271J-294D01*
G03X424225Y263565I1238J1016D01*
G02X424788Y263567I283J-283D01*
G03X424778Y265842I1123J1142D01*
G02X424215Y265840I-283J283D01*
G03X422006Y265875I-1123J-1143D01*
G02X421426Y265915I-271J294D01*
G03X418988Y265961I-1239J-1016D01*
G02X418390I-299J265D01*
G03X415989Y265959I-1200J-1062D01*
G02X415389I-300J265D01*
G03X412988Y265960I-1201J-1060D01*
G02X412388I-300J265D01*
G03X410858Y266467I-1201J-1061D01*
G02X410376Y266857I-82J391D01*
G01X410358Y276979D01*
G02X410864Y277365I400J0D01*
G03X412456Y277813I424J1545D01*
G02X413039I291J-273D01*
G03Y280007I1168J1097D01*
G02X412456I-291J273D01*
G03X410859Y280453I-1167J-1097D01*
G02X410352Y280838I-107J385D01*
G01X410329Y293983D01*
G02X410842Y294367I400J1D01*
G03X412494Y294843I452J1537D01*
G02X413094I300J-265D01*
G03Y296965I1200J1061D01*
G02X412494I-300J265D01*
G03X410836Y297439I-1200J-1061D01*
G02X410322Y297822I-114J383D01*
G01X410300Y310300D01*
X410900Y310900D01*
X443600D01*
X444098Y310402D01*
Y307485D01*
X444100Y307484D01*
Y307000D01*
X445600Y305500D01*
X468561D01*
X468612Y305374D01*
G03X471214I1301J522D01*
G01X471264Y305499D01*
X471265D01*
Y305500D01*
X475332D01*
X476608Y306776D01*
G02X476880Y306786I141J-141D01*
G03X478857Y308763I912J1065D01*
G02X478867Y309035I151J131D01*
G01X479224Y309392D01*
G02X479876Y309262I283J-283D01*
G03X480526Y311041I1296J535D01*
G02X479942Y311396I-184J355D01*
G01Y312097D01*
G02X480526Y312452I400J0D01*
G03Y314940I646J1244D01*
G02X479942Y315295I-184J355D01*
G01Y315885D01*
G02X480517Y316245I400J0D01*
G03Y318947I655J1351D01*
G02X479942Y319307I-175J360D01*
G01Y319785D01*
G02X480517Y320145I400J0D01*
G03Y322847I655J1351D01*
G02X479942Y323207I-175J360D01*
G01Y323685D01*
G02X480517Y324045I400J0D01*
G03Y326747I655J1351D01*
G02X479942Y327107I-175J360D01*
G01Y327558D01*
X479902Y327598D01*
Y327709D01*
X476102Y331508D01*
Y341689D01*
G02X476788Y341968I400J0D01*
G03Y343926I1004J979D01*
G02X476102Y344205I-286J279D01*
G01Y345449D01*
G02X476773Y345743I400J0D01*
G03Y347951I1019J1104D01*
G02X476102Y348245I-271J294D01*
G01Y349349D01*
G02X476773Y349643I400J0D01*
G03Y351851I1019J1104D01*
G02X476102Y352145I-271J294D01*
G01Y353389D01*
G02X476788Y353668I400J0D01*
G03X478126Y356009I1004J979D01*
G02X477939Y356680I96J388D01*
G01X480511Y359252D01*
X480635Y359201D01*
G03X482325Y359698I537J1295D01*
G01X486779D01*
G03X488155Y359112I1153J798D01*
G01X488256Y359128D01*
X489104Y358280D01*
X490787Y356596D01*
X491146Y356237D01*
X490968Y356059D01*
X490918Y356044D01*
G03X492318Y353600I394J-1397D01*
G02X492994Y353311I276J-289D01*
G01Y351515D01*
X492988Y351508D01*
Y351171D01*
X492655D01*
X492603Y351293D01*
G03X492304Y349757I-1291J-546D01*
G02X492988Y349474I284J-282D01*
G01Y348120D01*
G02X492304Y347837I-400J-1D01*
G03Y345857I-992J-990D01*
G02X492988Y345574I284J-282D01*
G01Y344290D01*
G02X492312Y344000I-400J0D01*
G03Y341894I-1000J-1053D01*
G02X492988Y341604I276J-290D01*
G01Y341196D01*
X493148Y341036D01*
Y340552D01*
X494566Y339134D01*
G02X494374Y338461I-283J-283D01*
G03X496057Y336778I318J-1365D01*
G02X496730Y336970I390J-91D01*
G01X497400Y336300D01*
X498400D01*
X498405Y336295D01*
X498893D01*
X500448Y334740D01*
G02X500451Y334177I-283J-283D01*
G03X502433Y332195I1001J-981D01*
G02X502996Y332192I280J-286D01*
G01X503088Y332100D01*
G02X503475Y331599I0J-400D01*
G03X506189I1357J-352D01*
G02X506576Y332100I387J101D01*
G01X507338D01*
G03X509086I874J1096D01*
G01X509848D01*
G02X510235Y331599I0J-400D01*
G03X512949I1357J-352D01*
G02X513336Y332100I387J101D01*
G01X514098D01*
G03X515846I874J1096D01*
G01X516505D01*
G02X516893Y331605I0J-400D01*
G03X519811I1459J-358D01*
G02X520199Y332100I388J95D01*
G01X520779D01*
G03X522466Y331944I952J1096D01*
G01X522599Y332022D01*
X523694Y330927D01*
X523707Y330875D01*
G03X524739Y329843I1404J372D01*
G01X524791Y329830D01*
X525155Y329466D01*
G02X524924Y328787I-283J-282D01*
G03X526551Y327160I187J-1440D01*
G02X527230Y327391I397J-52D01*
G01X527551Y327070D01*
G02X527532Y326487I-283J-283D01*
G03X529582Y324437I959J-1091D01*
G02X530165Y324456I300J-264D01*
G01X530553Y324068D01*
X530509Y323948D01*
G03X532373Y322084I1362J-502D01*
G01X532493Y322128D01*
X534936Y319685D01*
G02X534779Y319022I-282J-283D01*
G03X536677Y317124I472J-1426D01*
G02X537340Y317281I380J-125D01*
G01X537462Y317159D01*
G02X537485Y316618I-283J-283D01*
G03X539602Y314501I1146J-971D01*
G02X540143Y314478I258J-306D01*
G01X540552Y314069D01*
X540533Y313966D01*
G03X542281Y312218I1478J-270D01*
G01X542384Y312237D01*
X544876Y309745D01*
G02X544770Y309104I-283J-282D01*
G03X546648Y307226I621J-1257D01*
G02X547289Y307332I359J-177D01*
G01X547686Y306935D01*
G03X549678Y304699I1085J-1039D01*
G01X549817Y304804D01*
X550647Y303974D01*
X550650Y303895D01*
G03X552099Y302446I1501J52D01*
G01X552178Y302443D01*
X552390Y302231D01*
G02X552116Y301549I-283J-282D01*
G03X553653Y300012I35J-1502D01*
G02X554335Y300286I400J-9D01*
G01X554905Y299716D01*
G02X554891Y299136I-282J-283D01*
G03X556871Y297156I940J-1040D01*
G02X557451Y297170I297J-268D01*
G01X558489Y296132D01*
Y296111D01*
X624686Y229914D01*
Y224298D01*
X624800Y224184D01*
Y223200D01*
X629419Y218581D01*
X690500D01*
G02X690899Y218164I0J-400D01*
G03X690952Y217702I1501J-62D01*
G02X690628Y217201I-386J-106D01*
G03X690664Y214228I233J-1484D01*
G02X691011Y213825I-53J-396D01*
G01Y213802D01*
G02X690664Y213406I-400J0D01*
G03X690654Y210429I197J-1489D01*
G02X690999Y210047I-55J-396D01*
G03X691000Y210022I1501J48D01*
G02X690655Y209605I-399J-21D01*
G03X690790Y206617I206J-1488D01*
G02X691171Y206214I-19J-400D01*
G01Y206213D01*
G02X690790Y205817I-400J4D01*
G03X692363Y204304I71J-1500D01*
G02X692744Y204700I400J-4D01*
G03Y207700I-71J1500D01*
G02X692363Y208103I19J400D01*
G03X692361Y208195I-1502J13D01*
G02X692706Y208612I399J21D01*
G03X692707Y211588I-205J1488D01*
G02X692362Y211970I55J396D01*
G03X692354Y212077I-1501J-58D01*
G02X692549Y212298I199J21D01*
G03X692710Y215289I-35J1502D01*
G02X692363Y215692I53J396D01*
G03X692309Y216115I-1502J23D01*
G02X692633Y216616I386J106D01*
G03X693901Y218164I-233J1484D01*
G02X694300Y218581I399J17D01*
G01X696719D01*
X698700Y216600D01*
Y199200D01*
X700400Y197500D01*
X708475D01*
G03X709925I725J1200D01*
G01X715636D01*
G03X717858Y198036I921J1057D01*
G01X717874Y198074D01*
X726051Y206251D01*
X748118D01*
G02X748475Y205670I0J-400D01*
G03X750699Y204027I1251J-633D01*
G02X751253I277J-288D01*
G03X753199I973J1010D01*
G02X753753I277J-288D01*
G03X755977Y205670I973J1010D01*
G02X756334Y206251I357J181D01*
G01X765300D01*
X766900Y204651D01*
Y190300D01*
X770400Y186800D01*
Y177400D01*
X755446Y162446D01*
X755304Y162588D01*
G03X749664Y162228I-2663J-2643D01*
G01X749604Y162150D01*
X748815D01*
G03X746385I-1215J-700D01*
G01X604050D01*
G37*
G36*
G01X630799Y219601D02*
X625687Y224713D01*
Y231013D01*
X556583Y300117D01*
G02X556648Y300736I283J283D01*
G03X554571Y302813I-817J1260D01*
G02X553952Y302748I-336J218D01*
G01X553475Y303225D01*
X553529Y303350D01*
G03X551554Y305325I-1378J597D01*
G01X551429Y305271D01*
X550096Y306604D01*
X550082Y306628D01*
G03X549503Y307207I-1311J-732D01*
G01X549479Y307221D01*
X548932Y307768D01*
G02X549116Y308438I283J283D01*
G03X547412Y310142I-345J1359D01*
G02X546742Y309958I-387J99D01*
G01X546515Y310185D01*
G02X546502Y310737I283J283D01*
G03X544381Y312858I-1111J1010D01*
G02X543829Y312871I-269J296D01*
G01X543450Y313250D01*
X543475Y313358D01*
G03X541673Y315160I-1464J338D01*
G01X541565Y315135D01*
X539082Y317618D01*
G02X539202Y318266I283J283D01*
G03X537350Y320118I-571J1281D01*
G02X536702Y319998I-365J163D01*
G01X536354Y320346D01*
G02X536340Y320613I142J141D01*
G03X534368Y322585I-1089J883D01*
G01X534228Y322472D01*
X533324Y323376D01*
X533323Y323458D01*
G03X531883Y324898I-1452J-12D01*
G01X531801Y324899D01*
X531431Y325269D01*
G02X531749Y325950I283J283D01*
G03X530474Y327225I122J1397D01*
G02X529793Y326907I-398J-35D01*
G01X529231Y327469D01*
G02X529293Y328085I283J283D01*
G03X527280Y330098I-802J1211D01*
G02X526664Y330036I-333J221D01*
G01X526300Y330400D01*
X526375Y330532D01*
G03X524396Y332511I-1264J715D01*
G01X524264Y332436D01*
X523422Y333278D01*
X523190D01*
X523162Y333444D01*
G03X520300I-1431J-248D01*
G01X520272Y333278D01*
X516382D01*
X516352Y333443D01*
G03X513595Y333462I-1380J-247D01*
G01X513564Y333300D01*
X509620D01*
X509589Y333462D01*
G03X506835I-1377J-266D01*
G01X506804Y333300D01*
X503516D01*
X501759Y335057D01*
G02X501914Y335719I282J283D01*
G03X500075Y337558I-462J1377D01*
G02X499413Y337403I-379J127D01*
G01X498816Y338000D01*
X497600D01*
X495777Y339823D01*
G02X495765Y340094I141J142D01*
G03X494456Y342378I-1073J902D01*
G02X493989Y342772I-67J394D01*
G01Y343120D01*
G02X494456Y343514I400J0D01*
G03Y346278I236J1382D01*
G02X493989Y346672I-67J394D01*
G01Y347020D01*
G02X494456Y347414I400J0D01*
G03Y350178I236J1382D01*
G02X493989Y350572I-67J394D01*
G01Y351093D01*
X493996Y351100D01*
Y354804D01*
X493708Y355092D01*
X493954Y355404D01*
G03X493293Y356499I738J1192D01*
G02X492612Y356188I-399J-28D01*
G01X492033Y356767D01*
G02X492093Y357382I283J283D01*
G03X490147Y359328I-781J1165D01*
G02X489532Y359268I-332J223D01*
G01X489097Y359703D01*
X489168Y359833D01*
G03X486575Y360850I-1236J663D01*
G01X486536Y360700D01*
X485749D01*
G02X485483Y361399I0J400D01*
G03X483621I-931J1048D01*
G02X483355Y360700I-266J-299D01*
G01X482568D01*
X482529Y360850D01*
G03X479801Y360204I-1357J-353D01*
G01X479823Y360098D01*
X479305Y359580D01*
G02X478749Y359571I-283J283D01*
G03X476768Y357590I-957J-1024D01*
G02X476759Y357034I-292J-273D01*
G01X476450Y356725D01*
G02X475778Y356916I-283J283D01*
G03X474636Y355212I-1365J-320D01*
G02X475100Y354817I64J-395D01*
G01Y354475D01*
G02X474636Y354080I-400J0D01*
G03Y351312I-223J-1384D01*
G02X475100Y350917I64J-395D01*
G01Y350575D01*
G02X474636Y350180I-400J0D01*
G03Y347412I-223J-1384D01*
G02X475100Y347017I64J-395D01*
G01Y346776D01*
G02X474640Y346381I-400J0D01*
G03Y343411I-227J-1485D01*
G02X475100Y343016I60J-395D01*
G01Y342775D01*
G02X474636Y342380I-400J0D01*
G03Y339612I-223J-1384D01*
G02X475100Y339217I64J-395D01*
G01Y338875D01*
G02X474636Y338480I-400J0D01*
G03Y335712I-223J-1384D01*
G02X475100Y335317I64J-395D01*
G01Y331094D01*
X477069Y329125D01*
G02X477009Y328510I-283J-283D01*
G03X478343Y326058I783J-1163D01*
G02X478900Y325690I157J-368D01*
G01Y321204D01*
G02X478343Y320836I-400J0D01*
G03Y318258I-551J-1289D01*
G02X478900Y317890I157J-368D01*
G01Y317304D01*
G02X478343Y316936I-400J0D01*
G03Y314358I-551J-1289D01*
G02X478900Y313990I157J-368D01*
G01Y313512D01*
G02X478351Y313141I-400J0D01*
G03X476941Y310509I-559J-1394D01*
G02X476997Y309897I-227J-329D01*
G01X473700Y306600D01*
X471125D01*
G03X468701I-1212J-704D01*
G01X446400D01*
X445100Y307900D01*
Y314800D01*
X455200Y324900D01*
Y324938D01*
X455671Y325409D01*
Y331288D01*
G02X456245Y331648I400J0D01*
G03Y334352I655J1352D01*
G02X455671Y334712I-174J360D01*
G01Y339349D01*
X455795Y339400D01*
G03Y341994I-532J1297D01*
G01X455671Y342045D01*
Y349507D01*
G02X456374Y349768I400J0D01*
G03Y351726I1139J979D01*
G02X455671Y351987I-303J261D01*
G01Y400908D01*
X462042Y407279D01*
X466240D01*
X466264Y407106D01*
G03X469042I1389J190D01*
G01X469066Y407279D01*
X537081D01*
G02X537451Y406728I0J-400D01*
G03X540152Y406189I1299J-528D01*
G02X540835Y406468I400J-4D01*
G01X551643Y395660D01*
G02X551527Y395013I-282J-283D01*
G03X553517Y393023I624J-1366D01*
G02X554164Y393139I364J-166D01*
G01X557717Y389586D01*
X557727Y389521D01*
G03X558986Y388262I1485J226D01*
G01X559051Y388252D01*
X559720Y387583D01*
Y387580D01*
X633400Y313900D01*
Y295617D01*
G02X632972Y295218I-400J0D01*
G03X634320Y293332I-103J-1498D01*
G02X634989Y293511I386J-104D01*
G01X638219Y290281D01*
X638220Y290199D01*
G03X639611Y288808I1402J11D01*
G01X639693Y288807D01*
X646496Y282004D01*
G02X646481Y281424I-283J-283D01*
G03X646410Y279261I1006J-1116D01*
G02X646406Y278700I-287J-278D01*
G03X648546Y278686I1063J-1061D01*
G02X648550Y279247I287J278D01*
G03X648603Y279302I-1055J1069D01*
G02X649183Y279317I297J-268D01*
G01X655500Y273000D01*
Y255342D01*
G02X655068Y254943I-400J0D01*
G03Y251949I-118J-1497D01*
G02X655500Y251550I32J-399D01*
G01Y226100D01*
X649001Y219601D01*
X630799D01*
G37*
G36*
G01X652300Y219600D02*
X652175Y219725D01*
Y220425D01*
X657090Y225340D01*
Y248382D01*
G02X657537Y248780I400J1D01*
G03X658864Y249391I163J1392D01*
G02X659505Y249422I332J-223D01*
G03X659424Y251093I1083J890D01*
G02X658783Y251062I-332J223D01*
G03X657537Y251564I-1083J-890D01*
G02X657090Y251962I-47J397D01*
G01Y274507D01*
G03X656163Y276901I-990J993D01*
G01X656086Y276904D01*
X644855Y288135D01*
G02X644846Y288691I283J283D01*
G03X642864Y290673I-1023J959D01*
G02X642308Y290682I-273J292D01*
G01X636220Y296770D01*
Y300488D01*
G02X636837Y300823I400J-1D01*
G03Y303177I763J1177D01*
G02X636220Y303512I-217J336D01*
G01Y305488D01*
G02X636837Y305823I400J-1D01*
G03Y308177I763J1177D01*
G02X636220Y308512I-217J336D01*
G01Y310463D01*
G02X636829Y310804I400J0D01*
G03X636562Y312984I732J1196D01*
G02X636220Y313124I-142J141D01*
G01Y313410D01*
X588390Y361240D01*
Y366090D01*
X591990Y369690D01*
X634730D01*
X642840Y377800D01*
X714070D01*
X722270Y386000D01*
Y405790D01*
X723500Y407020D01*
X761380D01*
X762750Y408390D01*
X786970D01*
X786985Y408375D01*
X803659D01*
G02X804038Y407847I0J-400D01*
G03X806696I1329J-447D01*
G02X807075Y408375I379J128D01*
G01X816270D01*
X817880Y406765D01*
Y369432D01*
X816700Y368252D01*
X786076D01*
X785643Y368685D01*
Y370910D01*
X785791Y370950D01*
G03Y373850I-391J1450D01*
G01X785643Y373890D01*
Y399277D01*
X781810Y403110D01*
X744790D01*
X740820Y399140D01*
Y377623D01*
G03Y375303I954J-1160D01*
G01Y316757D01*
G03Y314319I692J-1219D01*
G01Y300197D01*
X740699Y300145D01*
G03Y297567I551J-1289D01*
G01X740820Y297515D01*
Y254885D01*
G02X740194Y254556I-400J1D01*
G03Y252244I-794J-1156D01*
G02X740820Y251915I226J-330D01*
G01Y249049D01*
G02X740216Y248705I-400J0D01*
G03X738748Y246317I-716J-1205D01*
G02X738816Y245696I-214J-338D01*
G01X730200Y237080D01*
X729344D01*
X729298Y237216D01*
G03X726640I-1329J-446D01*
G01X726594Y237080D01*
X701190D01*
X698790Y234680D01*
Y234410D01*
X698766Y234366D01*
G03Y233034I1234J-666D01*
G01X698790Y232990D01*
Y220200D01*
X698190Y219600D01*
X652300D01*
G37*
G36*
G01X1729480Y208880D02*
G02X1730095Y208820I283J-283D01*
G03X1732656Y209731I1165J780D01*
G02X1733144Y210158I398J37D01*
G03X1733484Y210120I337J1473D01*
G01X1738484D01*
G03X1738825Y210158I4J1511D01*
G02X1739313Y209731I90J-390D01*
G03X1741971Y208989I1396J-131D01*
G02X1742679Y209011I360J-175D01*
G03X1745301Y209752I1221J689D01*
G02X1745790Y210157I400J15D01*
G03X1746125Y210120I332J1474D01*
G01X1751125D01*
G03X1751502Y210167I3J1511D01*
G02X1752001Y209807I100J-387D01*
G03X1754449Y208970I1399J93D01*
G02X1755026Y208992I299J-266D01*
G03X1757402Y209967I974J1008D01*
G02X1757995Y210308I400J-9D01*
G03X1758725Y210120I730J1323D01*
G01X1763725D01*
G03X1764066Y210158I4J1511D01*
G02X1764554Y209731I90J-390D01*
G03X1767197Y208959I1396J-131D01*
G02X1767896Y208981I356J-183D01*
G03X1770501Y209752I1204J719D01*
G02X1770990Y210157I400J15D01*
G03X1771325Y210120I332J1474D01*
G01X1776325D01*
G03X1776666Y210158I4J1511D01*
G02X1777154Y209731I90J-390D01*
G03X1779797Y208959I1396J-131D01*
G02X1780496Y208981I356J-183D01*
G03X1783101Y209752I1204J719D01*
G02X1783590Y210157I400J15D01*
G03X1783925Y210120I332J1474D01*
G01X1788925D01*
G03X1789266Y210158I4J1511D01*
G02X1789754Y209731I90J-390D01*
G03X1792397Y208959I1396J-131D01*
G02X1793096Y208981I356J-183D01*
G03X1793053Y210341I1204J719D01*
G02X1792354Y210319I-356J183D01*
G03X1790892Y210978I-1204J-719D01*
G02X1790422Y211426I-74J393D01*
G03X1790427Y211462I-1494J226D01*
G01X1790436Y211546D01*
Y211641D01*
G03X1788926Y213142I-1511J-10D01*
G01X1783925D01*
G03X1782419Y211506I0J-1511D01*
G02X1781949Y211080I-399J-33D01*
G03X1780453Y210341I-249J-1380D01*
G02X1779754Y210319I-356J183D01*
G03X1778292Y210978I-1204J-719D01*
G02X1777822Y211426I-74J393D01*
G03X1777827Y211462I-1494J226D01*
G01X1777836Y211546D01*
Y211641D01*
G03X1776326Y213142I-1511J-10D01*
G01X1771325D01*
G03X1769819Y211506I0J-1511D01*
G02X1769349Y211080I-399J-33D01*
G03X1767853Y210341I-249J-1380D01*
G02X1767154Y210319I-356J183D01*
G03X1765692Y210978I-1204J-719D01*
G02X1765222Y211426I-74J393D01*
G03X1765227Y211462I-1494J226D01*
G01X1765236Y211546D01*
Y211641D01*
G03X1763726Y213142I-1511J-10D01*
G01X1758725D01*
G03X1757214Y211613I0J-1511D01*
G02X1756633Y211251I-400J-5D01*
G03X1754951Y210930I-633J-1251D01*
G02X1754374Y210908I-299J266D01*
G03X1753117Y211273I-974J-1008D01*
G02X1752636Y211653I-81J392D01*
G03X1751126Y213142I-1511J-22D01*
G01X1746125D01*
G03X1744619Y211506I0J-1511D01*
G02X1744149Y211080I-399J-33D01*
G03X1742638Y210311I-249J-1380D01*
G02X1741930Y210289I-360J175D01*
G03X1740451Y210978I-1221J-689D01*
G02X1739981Y211426I-74J393D01*
G03X1739986Y211462I-1494J226D01*
G01X1739996Y211546D01*
Y211641D01*
G03X1738485Y213142I-1511J-11D01*
G01X1734708D01*
G02X1734425Y213825I0J400D01*
G01X1747528Y226928D01*
X1755638D01*
X1759845Y231136D01*
G03X1756803Y234178I-1521J1521D01*
G01X1755245Y232621D01*
G02X1754604Y232727I-282J283D01*
G03X1752299Y233037I-1257J-621D01*
G02X1751600Y233303I-299J266D01*
G01Y235998D01*
G02X1752123Y236378I400J-1D01*
G03X1753617Y236798I431J1334D01*
G02X1754246Y236771I304J-260D01*
G03X1755554Y236100I1309J941D01*
G01X1760554D01*
G03X1761862Y236771I-1J1612D01*
G02X1762491Y236798I325J-233D01*
G03Y238626I1063J914D01*
G02X1761862Y238653I-304J260D01*
G03X1760555Y239324I-1309J-941D01*
G01X1755554D01*
G03X1754246Y238653I1J-1612D01*
G02X1753617Y238626I-325J233D01*
G03X1751341Y238415I-1063J-914D01*
G02X1750712Y238333I-346J201D01*
G01X1745265Y243780D01*
X1737306D01*
X1728885Y235359D01*
G02X1728203Y235621I-283J283D01*
G03X1722634Y232416I-3597J-191D01*
G02X1722416Y231681I-219J-335D01*
G01X1720708D01*
G02X1720347Y232252I1J400D01*
G03X1717813I-1267J600D01*
G02X1717452Y231681I-362J-171D01*
G01X1711158D01*
X1703007Y223530D01*
X1695994D01*
X1693978Y225546D01*
X1668379D01*
X1657591Y236334D01*
Y255439D01*
G02X1657982Y255838I400J-1D01*
G03X1658830Y258331I-33J1402D01*
G02X1658748Y258865I251J312D01*
G03X1657757Y261180I-1248J835D01*
G01X1657591Y261209D01*
Y263088D01*
X1657765Y263111D01*
G03X1658616Y265675I-198J1489D01*
G02X1658585Y266214I279J286D01*
G03X1658523Y268056I-1087J885D01*
G02X1658539Y268617I293J272D01*
G03X1657757Y271180I-1041J1083D01*
G01X1657591Y271209D01*
Y273191D01*
X1657757Y273220D01*
G03X1658539Y275783I-259J1480D01*
G02X1658523Y276344I277J289D01*
G03Y278256I-1025J956D01*
G02X1658539Y278817I293J272D01*
G03X1657757Y281380I-1041J1083D01*
G01X1657591Y281409D01*
Y283391D01*
X1657757Y283420D01*
G03X1658408Y286095I-259J1480D01*
G02X1658395Y286721I242J318D01*
G03X1657755Y289179I-895J1079D01*
G01X1657591Y289209D01*
Y291308D01*
X1657756Y291337D01*
G03Y294295I-262J1479D01*
G01X1657591Y294324D01*
Y303087D01*
X1657767Y303108D01*
G03Y305892I-167J1392D01*
G01X1657591Y305913D01*
Y416073D01*
X1660830Y419312D01*
Y449376D01*
G02X1661297Y449770I400J0D01*
G03X1662670Y452250I252J1481D01*
G02X1662665Y452776I299J266D01*
G03X1662633Y454762I-1143J975D01*
G02X1662622Y455287I296J269D01*
G03X1662571Y457273I-1152J964D01*
G02X1662581Y457828I293J272D01*
G01X1667441Y462688D01*
Y462689D01*
X1668379Y463627D01*
X1668488Y463600D01*
G03X1670303Y465415I355J1460D01*
G01X1670276Y465524D01*
X1676980Y472227D01*
X1677120Y472114D01*
G03X1679022Y472244I881J1091D01*
G02X1679576Y472270I291J-275D01*
G03X1680457Y474726I924J1055D01*
G02X1680162Y475409I-12J400D01*
G01X1682171Y477418D01*
X1760360D01*
G02X1760640Y476733I0J-400D01*
G03X1760518Y474712I1060J-1078D01*
G02X1760360Y474094I-312J-249D01*
G03X1762094Y473534I540J-1294D01*
G02X1762435Y474144I341J210D01*
G01X1765831D01*
G02X1766157Y473512I0J-400D01*
G03X1767903Y473966I1143J-812D01*
G02X1767787Y474605I172J361D01*
G03X1768202Y475486I-1087J1050D01*
G01X1768212Y475570D01*
Y475665D01*
G03X1767760Y476733I-1512J-10D01*
G02X1768040Y477418I280J285D01*
G01X1788080D01*
G02X1788456Y476882I0J-400D01*
G03X1790698Y475348I1318J-479D01*
G01X1790838Y475472D01*
X1791399Y474911D01*
Y467121D01*
X1793520Y465000D01*
X1905000D01*
X1907500Y462500D01*
X1918000D01*
X1920500Y465000D01*
Y467500D01*
X1914500Y473500D01*
Y478260D01*
G02X1914944Y478657I400J-1D01*
G03Y481443I156J1393D01*
G02X1914500Y481840I-44J398D01*
G01Y492323D01*
G02X1914901Y492723I400J0D01*
G03X1917930Y495329I10J3052D01*
G01X1917955Y495500D01*
X1921710D01*
X1921735Y495329D01*
G03X1927773I3019J446D01*
G01X1927798Y495500D01*
X1931553D01*
X1931578Y495329D01*
G03X1935867Y493000I3019J446D01*
G01X1967706D01*
G02X1967847Y492974I-1J-400D01*
G01X1971070D01*
G02X1971212Y493000I142J-374D01*
G01X1974000D01*
X1974578Y492422D01*
Y441748D01*
G02X1968475Y434502I-7353J0D01*
G01X1934349D01*
G02X1934072Y435190I1J400D01*
G03X1931933Y436977I-972J1010D01*
G02X1931267I-333J222D01*
G03X1928933I-1167J-777D01*
G02X1928267I-333J222D01*
G03X1926128Y435190I-1167J-777D01*
G02X1925851Y434502I-278J-288D01*
G01X1922390D01*
X1922342Y434454D01*
X1922115D01*
G02X1921949Y434765I0J200D01*
G03X1919515Y436523I-1249J835D01*
G02X1918885I-315J246D01*
G03X1916515I-1185J-923D01*
G02X1915885I-315J246D01*
G03X1913318Y435011I-1185J-923D01*
G02X1912951Y434454I-368J-157D01*
G01X1912140D01*
G02X1911776Y435020I0J400D01*
G03X1909333Y436377I-1277J579D01*
G02X1908667I-333J222D01*
G03X1906224Y435020I-1166J-778D01*
G02X1905860Y434454I-364J-166D01*
G01X1683454D01*
X1680050Y431050D01*
Y306520D01*
G02X1679534Y306138I-400J1D01*
G03X1678004Y303673I-434J-1438D01*
G02Y303127I-292J-273D01*
G03Y301073I1096J-1027D01*
G02Y300527I-292J-273D01*
G03X1677968Y298513I1096J-1027D01*
G02Y297987I-302J-263D01*
G03Y296013I1132J-987D01*
G02Y295487I-302J-263D01*
G03Y293513I1132J-987D01*
G02Y292987I-302J-263D01*
G03Y291013I1132J-987D01*
G02Y290487I-302J-263D01*
G03X1678131Y288352I1132J-987D01*
G02Y287741I-258J-305D01*
G03X1677968Y285606I969J-1148D01*
G02Y285080I-302J-263D01*
G03Y283106I1132J-987D01*
G02Y282580I-302J-263D01*
G03X1678030Y280539I1132J-987D01*
G02Y279978I-285J-280D01*
G03Y277869I1070J-1055D01*
G02X1678046Y277325I-285J-281D01*
G03X1678090Y275427I1054J-925D01*
G02Y274873I-288J-277D01*
G03X1678075Y272944I1010J-972D01*
G02X1678059Y272383I-293J-272D01*
G03X1679534Y269862I1041J-1083D01*
G02X1680050Y269480I116J-383D01*
G01Y268800D01*
X1683603Y265247D01*
X1870547D01*
G02X1870920Y264704I0J-400D01*
G03X1872211Y262669I1403J-537D01*
G02X1872396Y262470I-15J-199D01*
G01Y244966D01*
G02X1871746Y244655I-400J1D01*
G03X1859222Y238650I-4822J-6005D01*
G01Y232150D01*
G03X1874624I7701J0D01*
G01Y238650D01*
G03X1874563Y239622I-7701J5D01*
G02X1875242Y239956I397J51D01*
G01X1880699Y234499D01*
X1880698Y234415D01*
G03X1881151Y233325I1502J-15D01*
G02X1881181Y232786I-280J-286D01*
G03X1883570Y230968I1163J-950D01*
G02X1884179Y231019I326J-232D01*
G01X1885596Y229602D01*
X1901323D01*
G02X1901682Y229027I0J-400D01*
G03X1901928Y227350I1350J-659D01*
G02X1901925Y226805I-294J-271D01*
G03X1901927Y224745I1095J-1029D01*
G02X1901919Y224188I-291J-274D01*
G03X1903981Y224099I990J-993D01*
G02X1904020Y224655I305J258D01*
G03X1904124Y226794I-1000J1121D01*
G02X1904127Y227339I294J271D01*
G03X1904382Y229027I-1095J1029D01*
G02X1904741Y229602I359J175D01*
G01X1921964D01*
X1932708Y218858D01*
Y217448D01*
G03Y215966I1190J-741D01*
G01Y201063D01*
G02X1932135Y200703I-400J1D01*
G03Y197997I-652J-1353D01*
G02X1932708Y197637I173J-361D01*
G01Y193568D01*
X1932707Y193556D01*
G03Y193244I1393J-156D01*
G01X1932708Y193232D01*
Y188105D01*
X1932549Y188072D01*
G03Y185328I288J-1372D01*
G01X1932708Y185295D01*
Y176824D01*
G02X1932032Y176535I-400J1D01*
G03X1929983Y176412I-967J-1015D01*
G02X1929368Y176409I-309J254D01*
G03X1929274Y176511I-1150J-966D01*
G02X1929280Y177087I281J285D01*
G03X1927193Y177111I-1031J1092D01*
G02X1927187Y176535I-281J-285D01*
G03X1929419Y174541I1031J-1092D01*
G02X1930033Y174571I319J-241D01*
G03X1932032Y174505I1032J949D01*
G02X1932708Y174216I276J-290D01*
G01Y151126D01*
X1922904Y141322D01*
G02X1922306Y141360I-282J283D01*
G03X1920338Y139392I-1107J-861D01*
G02X1920376Y138794I-245J-316D01*
G01X1911785Y130203D01*
X1911682Y130221D01*
G03X1910059Y128598I-242J-1381D01*
G01X1910077Y128495D01*
X1897680Y116098D01*
X1897592Y116101D01*
G03X1896035Y114544I-56J-1501D01*
G01X1896038Y114456D01*
X1888302Y106720D01*
X1888173Y106785D01*
G03X1886156Y104768I-676J-1341D01*
G01X1886221Y104639D01*
X1882452Y100870D01*
X1882384Y100862D01*
G03X1881158Y99636I166J-1392D01*
G01X1881150Y99568D01*
X1880629Y99047D01*
G02X1879948Y99361I-282J283D01*
G03X1878659Y98072I-1398J109D01*
G02X1878973Y97391I31J-399D01*
G01X1876824Y95242D01*
X1869190D01*
X1865923Y91975D01*
G02X1865310Y92032I-283J283D01*
G03X1863362Y90084I-1157J-791D01*
G02X1863419Y89471I-226J-330D01*
G01X1854706Y80758D01*
Y76146D01*
X1854692Y76132D01*
Y66457D01*
X1839515Y51280D01*
Y42199D01*
G02X1838986Y41821I-400J1D01*
G03Y38979I-486J-1421D01*
G02X1839515Y38601I129J-379D01*
G01Y20400D01*
X1842243Y17672D01*
X1875514D01*
G03X1878070I1278J789D01*
G01X1881820D01*
G02X1882077Y16965I0J-400D01*
G03X1884005I964J-1151D01*
G02X1884262Y17672I257J307D01*
G01X1897737D01*
X1897748Y17483D01*
G03X1897805Y17030I3197J172D01*
G02X1897250Y16586I-392J-79D01*
G03Y10738I-1305J-2924D01*
G02X1897805Y10294I163J-365D01*
G03Y9038I3140J-628D01*
G02X1897250Y8594I-392J-79D01*
G03Y2746I-1305J-2924D01*
G02X1897805Y2302I163J-365D01*
G03Y1046I3140J-628D01*
G02X1897250Y602I-392J-79D01*
G03Y-5246I-1305J-2924D01*
G02X1897805Y-5690I163J-365D01*
G03X1902327Y-9206I3140J-628D01*
G02X1902900Y-9567I173J-361D01*
G01Y-11300D01*
X1905300Y-13700D01*
X1917470D01*
X1918524Y-14754D01*
Y-20816D01*
X1917640Y-21700D01*
X1894897D01*
G02X1894515Y-21181I0J400D01*
G03X1891647I-1434J446D01*
G02X1891265Y-21700I-382J-119D01*
G01X1887700D01*
Y-1200D01*
X1876600Y9900D01*
X1860500D01*
X1857300Y6700D01*
X1849700D01*
X1842255Y-745D01*
G02X1842025Y-858I-282J283D01*
G01X1840311Y-2572D01*
Y-21289D01*
X1839900Y-21700D01*
X1436700D01*
Y-1400D01*
X1429400Y5900D01*
X1427900D01*
X1425600Y8200D01*
X1423500D01*
X1422900Y8800D01*
X1415100D01*
X1414500Y8200D01*
X1412435D01*
G02X1412049Y8705I0J400D01*
G03X1410548Y7599I-1449J395D01*
G02X1410816Y6916I-14J-400D01*
G01X1409300Y5400D01*
X1400300D01*
X1392200Y-2700D01*
Y-21700D01*
X1332000D01*
X1331700Y-21400D01*
Y2500D01*
X1331600Y2600D01*
Y32900D01*
X1324292Y40208D01*
X1324435Y40351D01*
X1324437Y40352D01*
G03X1324547Y40470I-1042J1082D01*
G02X1324853I153J-130D01*
G03X1327149Y42407I1147J969D01*
G02X1327161Y42936I306J258D01*
G03X1324961Y44982I-1103J1020D01*
G02X1324402Y44958I-292J274D01*
G03X1323400Y45341I-1002J-1119D01*
G02X1323200Y45541I0J200D01*
G01Y49000D01*
G02X1323711Y49384I400J0D01*
G03Y52270I416J1443D01*
G02X1323200Y52654I-111J384D01*
G01Y62655D01*
X1323205Y62677D01*
G03Y63323I-1364J323D01*
G01X1323200Y63345D01*
Y65817D01*
X1323143Y65874D01*
Y66199D01*
G02X1323533Y66598I400J-1D01*
G03Y69402I-33J1402D01*
G02X1323143Y69801I10J400D01*
G01Y69906D01*
G02X1323363Y70105I200J0D01*
G03X1323533Y72902I137J1395D01*
G02X1323143Y73301I10J400D01*
G01Y73406D01*
G02X1323363Y73605I200J0D01*
G03X1322854Y76244I137J1395D01*
G01X1322724Y76176D01*
X1302700Y96200D01*
X1299200D01*
X1296500Y98900D01*
X1288800D01*
X1288693Y98793D01*
X1288594Y98807D01*
G03X1286894Y97107I-213J-1487D01*
G01X1286908Y97008D01*
X1285200Y95300D01*
X1035789D01*
G02X1035650Y95325I0J400D01*
G01X1032349D01*
G02X1032210Y95300I-139J375D01*
G01X766216D01*
X765475Y96041D01*
X765461Y96097D01*
G03X762837Y96700I-1461J-347D01*
G01X760600D01*
X759400Y95500D01*
Y95498D01*
X759198Y95296D01*
Y92585D01*
X759210Y92573D01*
Y92290D01*
X760598Y90902D01*
Y32298D01*
X757124Y28824D01*
G02X756988Y28735I-282J283D01*
G01Y28688D01*
X746860Y18560D01*
X746735Y18615D01*
G03X738625Y15200I-2442J-5537D01*
G01X735300D01*
X730500Y10400D01*
Y9496D01*
G03Y7446I957J-1025D01*
G01Y-11341D01*
G02X729834Y-11640I-400J0D01*
G03X727337Y-12837I-997J-1123D01*
G02X726809Y-13235I-399J-19D01*
G03X725340Y-13526I-481J-1423D01*
G02X724814I-263J302D01*
G03Y-15790I-987J-1132D01*
G02X725340I263J-302D01*
G03X726910Y-16042I987J1132D01*
G02X727413Y-16212I156J-369D01*
G03X729849Y-16451I1303J747D01*
G02X730373Y-16381I302J-263D01*
G03X730500Y-16458I841J1244D01*
G01Y-19536D01*
X728636Y-21400D01*
X711739D01*
G02X711565Y-21360I0J400D01*
G01X711525Y-21400D01*
X710929D01*
Y-21100D01*
X711009Y-21040D01*
G03X710202Y-18340I-902J1201D01*
G02X709828Y-17912I25J399D01*
G03X707990Y-16343I-1498J106D01*
G02X707500Y-15954I-90J390D01*
G01Y-385D01*
X704342Y2773D01*
G02X704588Y3454I283J283D01*
G03X702954Y5088I-138J1496D01*
G02X702273Y4842I-398J37D01*
G01X701167Y5948D01*
G02X701376Y6624I283J283D01*
G03X699624Y8376I-276J1476D01*
G02X698948Y8167I-393J74D01*
G01X698215Y8900D01*
X676017D01*
G02X675636Y9421I0J400D01*
G03X673327Y10857I-1336J426D01*
G02X672773I-277J288D01*
G03X670827I-973J-1010D01*
G02X670273I-277J288D01*
G03X668911Y11194I-973J-1010D01*
G02X668400Y11578I-111J384D01*
G01Y13400D01*
X661900Y19900D01*
Y24500D01*
X660110Y26290D01*
Y30433D01*
G03Y32567I-910J1067D01*
G01Y33384D01*
X660839Y34113D01*
X667360D01*
X668573Y32900D01*
X669626D01*
X669662Y32885D01*
G03X670792I565J1392D01*
G01X670828Y32900D01*
X694100D01*
X699453Y27547D01*
X699355Y27410D01*
G03X701310Y25455I1145J-810D01*
G01X701447Y25553D01*
X703000Y24000D01*
X709993D01*
G02X710392Y23626I0J-400D01*
G03X712786Y24704I1399J90D01*
G01X712645Y24845D01*
X713393Y25593D01*
G02X713995Y25551I283J-283D01*
G03X715958Y27514I1119J844D01*
G02X715916Y28116I241J319D01*
G01X730334Y42534D01*
G02X730889Y42544I283J-283D01*
G03X730912Y42522I980J1002D01*
G02X730922Y41933I-265J-299D01*
G03X732818Y41965I965J-1017D01*
G02X732808Y42554I265J299D01*
G03X732870Y44525I-965J1017D01*
G02X732880Y45080I293J272D01*
G01X736700Y48900D01*
Y54140D01*
G02X737255Y54508I400J-1D01*
G03Y57092I545J1292D01*
G02X736700Y57460I-155J369D01*
G01Y81579D01*
G03Y83821I-1000J1121D01*
G01Y87784D01*
X737352Y88435D01*
X737566Y88649D01*
G02X738248Y88385I283J-283D01*
G03X744586Y94723I6045J293D01*
G02X744322Y95405I19J399D01*
G01X761415Y112498D01*
X882156D01*
X882159Y112301D01*
G03X885163I1502J26D01*
G01X885166Y112498D01*
X888849D01*
X888852Y112301D01*
G03X891856I1502J26D01*
G01X891859Y112498D01*
X895562D01*
G03X895796Y112158I1259J616D01*
G02X895780Y111597I-293J-272D01*
G03X895753Y109457I1041J-1083D01*
G02X895759Y108900I-284J-282D01*
G03X895806Y106782I1088J-1035D01*
G02X895822Y106221I-277J-289D01*
G03X897872I1025J-956D01*
G02X897888Y106782I293J272D01*
G03X897915Y108922I-1041J1083D01*
G02X897909Y109479I284J282D01*
G03X897862Y111597I-1088J1035D01*
G02X897846Y112158I277J289D01*
G03X898080Y112498I-1025J956D01*
G01X900587D01*
X900636Y112369D01*
G03X900922Y111909I1311J496D01*
G02X900907Y111347I-292J-273D01*
G03X900844Y109245I1040J-1083D01*
G02X900838Y108696I-294J-271D01*
G03X900887Y106565I1083J-1041D01*
G02X900905Y106004I-275J-290D01*
G03X902953Y106014I1029J-953D01*
G02X902966Y106576I291J274D01*
G03X903024Y108674I-1045J1079D01*
G02X903030Y109223I294J271D01*
G03X902987Y111347I-1083J1041D01*
G02X902972Y111909I277J289D01*
G03X903258Y112369I-1025J956D01*
G01X903307Y112498D01*
X904298D01*
X912978Y121178D01*
X913133D01*
X920938Y128983D01*
X1238584D01*
X1238638Y128867D01*
G03X1241362I1362J633D01*
G01X1241416Y128983D01*
X1245361D01*
G03X1247141I890J1083D01*
G01X1248752D01*
X1248769Y128980D01*
G03X1249281I256J1480D01*
G01X1249298Y128983D01*
X1252315D01*
G02X1252694Y128457I-1J-400D01*
G03X1255423Y127921I1330J-444D01*
G02X1256105Y128177I399J-27D01*
G01X1263104Y121178D01*
X1265732D01*
X1265762Y121168D01*
G03X1266638I438J1332D01*
G01X1266668Y121178D01*
X1268185D01*
X1268228Y121157D01*
G03X1269572I672J1343D01*
G01X1269615Y121178D01*
X1270785D01*
X1270828Y121157D01*
G03X1272172I672J1343D01*
G01X1272215Y121178D01*
X1276927D01*
X1276937Y121177D01*
G03X1277263I163J1493D01*
G01X1277273Y121178D01*
X1292333D01*
G03X1295067I1367J622D01*
G01X1322256D01*
X1343799Y99634D01*
X1343814Y99584D01*
G03X1344841Y98557I1443J416D01*
G01X1344891Y98542D01*
X1347211Y96222D01*
X1347216Y96147D01*
G03X1348000Y94979I1399J92D01*
G01Y89199D01*
G02X1347467Y88822I-400J0D01*
G03Y86178I-467J-1322D01*
G02X1348000Y85801I133J-377D01*
G01Y84799D01*
G02X1347578Y84400I-400J0D01*
G03Y81600I-78J-1400D01*
G02X1348000Y81201I22J-399D01*
G01Y41431D01*
G03Y39097I945J-1167D01*
G01Y14500D01*
X1355800Y6700D01*
X1356221D01*
G02X1356527Y6043I0J-400D01*
G03X1356362Y4482I1073J-903D01*
G02X1355996Y3894I-353J-188D01*
G03X1354940Y1520I-46J-1401D01*
G02Y966I-288J-277D01*
G03X1355749Y-1395I1010J-973D01*
G02X1356091Y-1820I-57J-396D01*
G03X1356098Y-2096I1398J-103D01*
G02X1355765Y-2540I-397J-49D01*
G03X1355792Y-5312I224J-1384D01*
G02X1356125Y-5800I-56J-396D01*
G03X1356167Y-6591I1364J-324D01*
G02X1355812Y-7124I-377J-134D01*
G03X1355741Y-9918I77J-1400D01*
G02X1356096Y-10362I-42J-398D01*
G03X1356087Y-10490I1393J-162D01*
G02X1355723Y-10878I-400J10D01*
G03X1355749Y-13674I124J-1397D01*
G02X1356114Y-14151I-27J-399D01*
G03X1356106Y-14655I1375J-274D01*
G02X1355765Y-15117I-394J-66D01*
G03X1357333Y-16276I185J-1390D01*
G02X1357674Y-15814I394J66D01*
G03X1357587Y-13025I-184J1390D01*
G02X1357222Y-12548I27J399D01*
G03X1357249Y-12309I-1375J276D01*
G02X1357613Y-11921I400J-10D01*
G03X1357637Y-9130I-123J1397D01*
G02X1357282Y-8686I42J398D01*
G03X1357211Y-8057I-1393J161D01*
G02X1357566Y-7524I377J134D01*
G03X1357686Y-4736I-77J1400D01*
G02X1357353Y-4248I56J396D01*
G03X1357380Y-3752I-1364J323D01*
G02X1357713Y-3308I397J49D01*
G03X1358888Y-1829I-224J1384D01*
G02X1359323Y-1403I399J28D01*
G03X1360460Y966I127J1396D01*
G02Y1520I288J277D01*
G03X1358440I-1010J973D01*
G02Y966I-288J-277D01*
G03X1358085Y-327I1010J-973D01*
G02X1357840Y-567I-195J-46D01*
G03X1357690Y-536I-358J-1355D01*
G02X1357348Y-111I57J396D01*
G03X1356960Y966I-1398J105D01*
G02Y1520I288J277D01*
G03X1357188Y3151I-1010J973D01*
G02X1357554Y3739I353J188D01*
G03X1358833Y5808I46J1401D01*
G02X1359185Y6398I352J190D01*
G01X1365001D01*
G02X1365398Y5949I0J-400D01*
G03X1367800Y4805I1391J-173D01*
G02X1368378I289J-277D01*
G03X1370790Y5717I1011J971D01*
G02X1371171Y6099I399J-17D01*
G03X1372001Y6398I-72J1501D01*
G01X1372799D01*
G03X1374552Y6363I901J1202D01*
G01X1374603Y6398D01*
X1375005D01*
X1375047Y6377D01*
G03X1375148Y6331I631J1252D01*
G02X1375228Y5634I-150J-370D01*
G03X1376913Y5665I865J-1228D01*
G02X1376946Y6356I217J336D01*
G03X1377022Y6398I-640J1248D01*
G01X1378065D01*
G02X1378214Y6369I-1J-400D01*
G01X1378358D01*
G02X1378749Y5887I-1J-400D01*
G03X1379169Y4507I1470J-306D01*
G02X1379186Y3952I-279J-286D01*
G03X1379770Y1539I1114J-1008D01*
G02X1379849Y831I-141J-374D01*
G03X1381208Y983I828J-1253D01*
G02X1381129Y1691I141J374D01*
G03X1381350Y4018I-829J1253D01*
G02X1381333Y4573I279J286D01*
G03X1381684Y5910I-1114J1007D01*
G02X1382075Y6398I390J88D01*
G01X1383281D01*
G02X1383521Y6318I0J-400D01*
G01X1384118D01*
X1391600Y13800D01*
X1391800D01*
X1397000Y19000D01*
X1503648D01*
G03X1505152I752J1300D01*
G01X1507600D01*
X1508098Y19498D01*
X1508315D01*
X1510895Y22078D01*
G02X1511491Y22045I283J-282D01*
G03X1515849Y26403I2427J1931D01*
G02X1515816Y26999I249J313D01*
G01X1523602Y34785D01*
Y75902D01*
X1524800Y77100D01*
X1529400D01*
X1530763Y78463D01*
G02X1531435Y78271I283J-283D01*
G03X1533673Y77493I1365J319D01*
G02X1534211Y77455I248J-313D01*
G03X1534298Y79609I1089J1035D01*
G02X1533757Y79614I-268J297D01*
G03X1532100Y79805I-958J-1024D01*
G02X1531500Y80151I-200J346D01*
G01Y82700D01*
X1528600Y85600D01*
Y110200D01*
X1529800Y111400D01*
X1544000D01*
X1544798Y110602D01*
Y102485D01*
X1544800Y102484D01*
Y102400D01*
X1569398Y77802D01*
Y76405D01*
G03Y74387I1113J-1009D01*
G01Y21685D01*
X1571585Y19498D01*
X1571802D01*
X1572300Y19000D01*
X1648400D01*
X1652700Y23300D01*
Y36357D01*
X1652706Y36382D01*
G03Y37118I-1456J368D01*
G01X1652700Y37143D01*
Y37951D01*
X1656298D01*
G03X1656678Y37999I2J1511D01*
G02X1657174Y37674I101J-387D01*
G03X1659078Y36588I1385J216D01*
G02X1659608Y36337I148J-372D01*
G03X1662204Y37375I1336J424D01*
G02X1662563Y37950I360J175D01*
G01X1665748D01*
G03X1667250Y39293I0J1512D01*
G01X1667260Y39377D01*
Y39472D01*
G03X1665749Y40974I-1512J-10D01*
G01X1660748D01*
G03X1659245Y39625I0J-1512D01*
G02X1658784Y39274I-397J44D01*
G03X1658279Y39264I-225J-1384D01*
G02X1657802Y39611I-80J392D01*
G03X1656299Y40974I-1504J-149D01*
G01X1652700D01*
Y75701D01*
G02X1653079Y76100I400J0D01*
G03Y79100I-79J1500D01*
G02X1652700Y79499I21J399D01*
G01Y91489D01*
X1654355Y93144D01*
X1660132D01*
G02X1660524Y92668I-1J-400D01*
G03X1663276I1376J-268D01*
G02X1663668Y93144I393J76D01*
G01X1667250D01*
G02X1667618Y92588I0J-400D01*
G03X1670382I1382J-588D01*
G02X1670750Y93144I368J156D01*
G01X1691967D01*
X1691986Y93140D01*
G03X1692584I299J1472D01*
G01X1692603Y93144D01*
X1697482D01*
X1697501Y93140D01*
G03X1698099I299J1472D01*
G01X1698118Y93144D01*
X1729652D01*
G02X1730029Y92610I0J-400D01*
G03X1732365Y91173I1321J-470D01*
G02X1732931Y91186I289J-276D01*
G03X1735237Y92623I969J1013D01*
G02X1735618Y93144I381J121D01*
G01X1761174D01*
X1764118Y96088D01*
Y104508D01*
X1768849Y109239D01*
G02X1769513Y109077I283J-283D01*
G03X1772251Y109440I1337J422D01*
G01X1772259Y109631D01*
X1781359D01*
G02X1781757Y109192I0J-400D01*
G03X1784747I1495J-148D01*
G02X1785145Y109631I398J39D01*
G01X1788631D01*
X1791500Y112500D01*
Y153221D01*
G03Y154779I-1400J779D01*
G01Y157546D01*
X1791558Y157604D01*
X1786671Y162491D01*
G02X1786648Y163032I283J283D01*
G03X1784532Y165148I-1148J968D01*
G02X1783991Y165171I-258J306D01*
G01X1771487Y177675D01*
G02X1771593Y178317I283J283D01*
G03X1769649Y179113I-620J1257D01*
G02X1769271Y178582I-378J-131D01*
G01X1766431D01*
G02X1766041Y179069I1J400D01*
G03X1763305I-1368J305D01*
G02X1762915Y178582I-391J-87D01*
G01X1760077D01*
G02X1759699Y179113I0J400D01*
G03X1757051I-1324J461D01*
G02X1756673Y178582I-378J-131D01*
G01X1753733D01*
G02X1753343Y179069I1J400D01*
G03X1750607I-1368J305D01*
G02X1750217Y178582I-391J-87D01*
G01X1747479D01*
G02X1747101Y179113I0J400D01*
G03X1744453I-1324J461D01*
G02X1744075Y178582I-378J-131D01*
G01X1741135D01*
G02X1740745Y179069I1J400D01*
G03X1738009I-1368J305D01*
G02X1737619Y178582I-391J-87D01*
G01X1734880D01*
G02X1734502Y179113I0J400D01*
G03X1731854I-1324J461D01*
G02X1731476Y178582I-378J-131D01*
G01X1728453D01*
G02X1728064Y179075I0J400D01*
G03X1725694Y180376I-1364J325D01*
G02X1725007Y180655I-287J279D01*
G01Y204407D01*
X1729480Y208880D01*
G37*
G36*
G01X623048Y407496D02*
X613326Y417219D01*
Y417291D01*
X613325D01*
Y423309D01*
X613326D01*
Y423419D01*
X615157Y425250D01*
X615267D01*
X617214Y427198D01*
X631676D01*
X633623Y425251D01*
X752833D01*
X758892Y419192D01*
Y419151D01*
X761852Y416191D01*
Y415321D01*
G03Y413561I1217J-880D01*
G01Y412709D01*
G03Y410747I1137J-981D01*
G01Y408908D01*
X760965Y408022D01*
X723085D01*
X722560Y407496D01*
X623048D01*
G37*
G36*
G01X702500Y199000D02*
X699700Y201800D01*
Y219694D01*
X699792Y219785D01*
Y223551D01*
G02X700369Y223909I400J0D01*
G03X703075Y223931I1331J2691D01*
G03X707042Y225085I1375J2669D01*
G03X707353Y224977I612J1261D01*
G02X707510Y224764I-42J-195D01*
G03X710601Y221500I2990J-264D01*
G02X710807Y221315I6J-200D01*
G03X712761Y218728I2993J229D01*
G03X712725Y218306I2966J-466D01*
G03X713781Y212870I1666J-2497D01*
G03X716470Y213643I1319J475D01*
G03X717393Y215770I-2079J2166D01*
G03X716766Y221083I-1666J2497D01*
G03X716453Y222948I-2966J461D01*
G03X712380Y226840I-2753J1196D01*
G03X709040Y227123I-1880J-2340D01*
G02X708781Y227179I-98J175D01*
G03X707247Y227689I-1128J-832D01*
G03X703075Y229269I-2798J-1089D01*
G03X700369Y229291I-1375J-2669D01*
G02X699792Y229649I-177J358D01*
G01Y234265D01*
X701526Y236000D01*
X726797D01*
G03X729141I1172J770D01*
G01X730800D01*
X734684Y239884D01*
G02X735335Y239758I283J-282D01*
G03X735574Y239380I1289J551D01*
G02X735571Y238847I-300J-265D01*
G03X737663Y238836I1041J-939D01*
G02X737666Y239369I300J265D01*
G03X737175Y241598I-1041J939D01*
G02X737049Y242249I156J368D01*
G01X739303Y244503D01*
X739390Y244500D01*
G03X742406Y248252I110J3000D01*
G01X742400Y248276D01*
Y253294D01*
G03Y253506I-3000J106D01*
G01Y296083D01*
G03X743754Y300512I-1150J2773D01*
G02X744030Y301129I333J221D01*
G03X742894Y307018I-431J2971D01*
G02X742400Y307407I-94J389D01*
G01Y312667D01*
X742532Y312715D01*
G03Y318361I-1020J2823D01*
G01X742400Y318409D01*
Y374988D01*
G03Y377938I-626J1475D01*
G01Y398800D01*
X745708Y402108D01*
X781395D01*
X783941Y399563D01*
Y373063D01*
X783925Y373025D01*
G03Y371775I1475J-625D01*
G01X783941Y371737D01*
Y219141D01*
X778710Y213910D01*
X774420D01*
X770486Y209976D01*
X770388Y209989D01*
G03X768886Y209090I-189J-1389D01*
G01X768838Y208960D01*
X725960D01*
X722390Y205390D01*
G02X721722Y205568I-282J283D01*
G03X720000Y203846I-1353J-369D01*
G02X720178Y203178I-105J-386D01*
G01X716916Y199916D01*
X716813Y199935D01*
G03X715273Y199120I-256J-1378D01*
G01X715220Y199000D01*
X710577D01*
X710532Y199138D01*
G03X707868I-1332J-438D01*
G01X707823Y199000D01*
X702500D01*
G37*
G36*
G01X765800Y507700D02*
G02X765411Y508193I0J400D01*
G03X765082Y509527I-1461J347D01*
G02Y510053I302J263D01*
G03X764571Y512408I-1132J987D01*
G02X764508Y513100I166J364D01*
G03X763087Y512992I-802J1150D01*
G02X763129Y512298I-176J-359D01*
G03X762818Y510053I821J-1258D01*
G02Y509527I-302J-263D01*
G03X762588Y509172I1133J-986D01*
G02X761942Y509058I-363J169D01*
G01X760400Y510600D01*
Y558900D01*
X757700Y561600D01*
X720000D01*
X703900Y577700D01*
X699300D01*
X697900Y579100D01*
Y580648D01*
G03Y582152I-1300J752D01*
G01Y592900D01*
X709200Y604200D01*
Y619100D01*
X714593Y624493D01*
X726193D01*
G02X726573Y623968I0J-400D01*
G03X729427I1427J-468D01*
G02X729807Y624493I380J125D01*
G01X731207D01*
X731214Y624500D01*
X1044695D01*
G02X1045075Y623974I0J-400D01*
G03X1047925I1425J-474D01*
G02X1048305Y624500I380J126D01*
G01X1326000D01*
X1328100Y622400D01*
Y547256D01*
G02X1327907Y547056I-200J0D01*
G03X1326702Y546282I49J-1401D01*
G02X1326000Y546257I-358J179D01*
G03X1326070Y544861I-1293J-765D01*
G02X1326771Y544906I363J-168D01*
G03X1327907Y544254I1185J749D01*
G02X1328100Y544054I-7J-200D01*
G01Y513900D01*
X1321900Y507700D01*
X1289828D01*
G02X1289677Y508471I-1J400D01*
G03X1285129I-2274J5608D01*
G02X1284978Y507700I-150J-371D01*
G01X1281001D01*
G03X1278999I-1001J-1120D01*
G01X1039683D01*
G02X1039495Y508453I0J400D01*
G03X1041398Y511629I-1699J3176D01*
G01Y516529D01*
G03X1034196I-3601J0D01*
G01Y511629D01*
G03X1037097Y508096I3602J0D01*
G01X1037258Y508064D01*
Y507700D01*
X1036047D01*
X1036028Y507719D01*
G02X1035907Y507700I-122J381D01*
G01X1035388D01*
G03X1033012I-1188J-744D01*
G01X765800D01*
G37*
G36*
G01X733491Y-21500D02*
X731600Y-19609D01*
Y-16591D01*
X731731Y-16543D01*
G03Y-13725I-521J1409D01*
G01X731600Y-13677D01*
Y1901D01*
G02X732133Y2278I400J0D01*
G03X733531Y4648I467J1322D01*
G02X733473Y5181I266J299D01*
G03X732900Y7283I-1138J819D01*
G02X732705Y7832I161J366D01*
G03X732225Y9644I-1248J639D01*
G02X732161Y10261I219J335D01*
G01X734865Y12965D01*
X734889Y12978D01*
G03X735422Y13511I-689J1222D01*
G01X735435Y13535D01*
X736050Y14150D01*
X737876D01*
G02X738274Y13708I0J-400D01*
G03X748502Y17427I6019J-630D01*
G02X748497Y17997I278J287D01*
G01X752638Y22138D01*
X752777Y22035D01*
G03X754843Y22294I898J1204D01*
G02X755482Y22271I311J-252D01*
G03X755546Y24075I1232J859D01*
G02X754907Y24098I-311J252D01*
G03X754879Y24137I-1234J-856D01*
G01X754776Y24276D01*
X761600Y31100D01*
Y58531D01*
G02X762315Y58777I400J0D01*
G03Y60623I1185J923D01*
G02X761600Y60869I-315J246D01*
G01Y77013D01*
G02X762294Y77283I400J-1D01*
G03X764278Y79518I1106J1017D01*
G02X764254Y80149I234J325D01*
G03X762300Y82149I-903J1072D01*
G02X761600Y82414I-300J265D01*
G01Y91600D01*
X760200Y93000D01*
Y94500D01*
X761300Y95600D01*
X762497D01*
X762530Y95441D01*
G03X764905Y94551I1470J309D01*
G01X765044Y94656D01*
X765500Y94200D01*
X768633D01*
G02X768910Y93511I0J-400D01*
G03X770852I971J-1011D01*
G02X771129Y94200I277J289D01*
G01X771638D01*
G02X771972Y93581I-1J-400D01*
G03X774484I1256J-824D01*
G02X774818Y94200I335J219D01*
G01X778331D01*
G02X778665Y93581I-1J-400D01*
G03X781177I1256J-824D01*
G02X781511Y94200I335J219D01*
G01X785116D01*
G02X785393Y93511I0J-400D01*
G03X785347Y91535I971J-1011D01*
G02X785337Y90973I-290J-276D01*
G03X785292Y88873I1051J-1073D01*
G02Y88327I-292J-273D01*
G03X785348Y86216I1096J-1027D01*
G02X785363Y85655I-277J-288D01*
G03X787413I1025J-957D01*
G02X787428Y86216I292J273D01*
G03X787484Y88327I-1040J1084D01*
G02Y88873I292J273D01*
G03X787419Y90992I-1096J1027D01*
G02X787398Y91553I274J291D01*
G03X787335Y93511I-1034J947D01*
G02X787612Y94200I277J289D01*
G01X790050D01*
G02X790369Y93559I0J-400D01*
G03X790463Y91758I1119J-845D01*
G02X790447Y91197I-293J-272D01*
G03X790392Y89087I1041J-1083D01*
G02Y88541I-292J-273D01*
G03X790528Y86359I1096J-1027D01*
G02X790537Y85751I-256J-308D01*
G03X792409Y85736I928J-1051D01*
G02X792428Y86343I270J295D01*
G03X792584Y88541I-940J1171D01*
G02Y89087I292J273D01*
G03X792529Y91197I-1096J1027D01*
G02X792513Y91758I277J289D01*
G03X792607Y93559I-1025J956D01*
G02X792926Y94200I319J241D01*
G01X795063D01*
G02X795397Y93581I-1J-400D01*
G03X797909I1256J-824D01*
G02X798243Y94200I335J219D01*
G01X801756D01*
G02X802090Y93581I-1J-400D01*
G03X804602I1256J-824D01*
G02X804936Y94200I335J219D01*
G01X808449D01*
G02X808783Y93581I-1J-400D01*
G03X811295I1256J-824D01*
G02X811629Y94200I335J219D01*
G01X815142D01*
G02X815476Y93581I-1J-400D01*
G03X817988I1256J-824D01*
G02X818322Y94200I335J219D01*
G01X821927D01*
G02X822204Y93511I0J-400D01*
G03X822158Y91535I971J-1011D01*
G02X822148Y90973I-290J-276D01*
G03X822103Y88873I1051J-1073D01*
G02Y88327I-292J-273D01*
G03X822159Y86216I1096J-1027D01*
G02X822174Y85655I-277J-288D01*
G03X824224I1025J-957D01*
G02X824239Y86216I292J273D01*
G03X824295Y88327I-1040J1084D01*
G02Y88873I292J273D01*
G03X824230Y90992I-1096J1027D01*
G02X824209Y91553I274J291D01*
G03X824146Y93511I-1034J947D01*
G02X824423Y94200I277J289D01*
G01X826861D01*
G02X827180Y93559I0J-400D01*
G03X827274Y91758I1119J-845D01*
G02X827258Y91197I-293J-272D01*
G03X827203Y89087I1041J-1083D01*
G02Y88541I-292J-273D01*
G03X827339Y86359I1096J-1027D01*
G02X827348Y85751I-256J-308D01*
G03X829220Y85736I928J-1051D01*
G02X829239Y86343I270J295D01*
G03X829395Y88541I-940J1171D01*
G02Y89087I292J273D01*
G03X829340Y91197I-1096J1027D01*
G02X829324Y91758I277J289D01*
G03X829418Y93559I-1025J956D01*
G02X829737Y94200I319J241D01*
G01X831874D01*
G02X832208Y93581I-1J-400D01*
G03X834720I1256J-824D01*
G02X835054Y94200I335J219D01*
G01X838567D01*
G02X838901Y93581I-1J-400D01*
G03X841413I1256J-824D01*
G02X841747Y94200I335J219D01*
G01X845260D01*
G02X845594Y93581I-1J-400D01*
G03X848106I1256J-824D01*
G02X848440Y94200I335J219D01*
G01X851953D01*
G02X852287Y93581I-1J-400D01*
G03X854799I1256J-824D01*
G02X855133Y94200I335J219D01*
G01X858738D01*
G02X859015Y93511I0J-400D01*
G03X858969Y91535I971J-1011D01*
G02X858959Y90973I-290J-276D01*
G03X858914Y88873I1051J-1073D01*
G02Y88327I-292J-273D01*
G03X858970Y86216I1096J-1027D01*
G02X858985Y85655I-277J-288D01*
G03X861035I1025J-957D01*
G02X861050Y86216I292J273D01*
G03X861106Y88327I-1040J1084D01*
G02Y88873I292J273D01*
G03X861041Y90992I-1096J1027D01*
G02X861020Y91553I274J291D01*
G03X860957Y93511I-1034J947D01*
G02X861234Y94200I277J289D01*
G01X863672D01*
G02X863991Y93559I0J-400D01*
G03X864085Y91758I1119J-845D01*
G02X864069Y91197I-293J-272D01*
G03X864014Y89087I1041J-1083D01*
G02Y88541I-292J-273D01*
G03X864150Y86359I1096J-1027D01*
G02X864159Y85751I-256J-308D01*
G03X866031Y85736I928J-1051D01*
G02X866050Y86343I270J295D01*
G03X866206Y88541I-940J1171D01*
G02Y89087I292J273D01*
G03X866151Y91197I-1096J1027D01*
G02X866135Y91758I277J289D01*
G03X866229Y93559I-1025J956D01*
G02X866548Y94200I319J241D01*
G01X868682D01*
G02X869017Y93582I0J-400D01*
G03X871533I1258J-821D01*
G02X871868Y94200I335J218D01*
G01X875378D01*
G02X875712Y93581I-1J-400D01*
G03X878224I1256J-824D01*
G02X878558Y94200I335J219D01*
G01X882071D01*
G02X882405Y93581I-1J-400D01*
G03X884917I1256J-824D01*
G02X885251Y94200I335J219D01*
G01X888764D01*
G02X889098Y93581I-1J-400D01*
G03X891610I1256J-824D01*
G02X891944Y94200I335J219D01*
G01X895549D01*
G02X895826Y93511I0J-400D01*
G03X895780Y91535I971J-1011D01*
G02X895770Y90973I-290J-276D01*
G03X895725Y88873I1051J-1073D01*
G02Y88327I-292J-273D01*
G03X895781Y86216I1096J-1027D01*
G02X895796Y85655I-277J-288D01*
G03X897846I1025J-957D01*
G02X897861Y86216I292J273D01*
G03X897917Y88327I-1040J1084D01*
G02Y88873I292J273D01*
G03X897852Y90992I-1096J1027D01*
G02X897831Y91553I274J291D01*
G03X897768Y93511I-1034J947D01*
G02X898045Y94200I277J289D01*
G01X900483D01*
G02X900802Y93559I0J-400D01*
G03X900896Y91758I1119J-845D01*
G02X900880Y91197I-293J-272D01*
G03X900825Y89087I1041J-1083D01*
G02Y88541I-292J-273D01*
G03X900961Y86359I1096J-1027D01*
G02X900970Y85751I-256J-308D01*
G03X902842Y85736I928J-1051D01*
G02X902861Y86343I270J295D01*
G03X903017Y88541I-940J1171D01*
G02Y89087I292J273D01*
G03X902962Y91197I-1096J1027D01*
G02X902946Y91758I277J289D01*
G03X903040Y93559I-1025J956D01*
G02X903359Y94200I319J241D01*
G01X905496D01*
G02X905830Y93581I-1J-400D01*
G03X908342I1256J-824D01*
G02X908676Y94200I335J219D01*
G01X912189D01*
G02X912523Y93581I-1J-400D01*
G03X915035I1256J-824D01*
G02X915369Y94200I335J219D01*
G01X918882D01*
G02X919216Y93581I-1J-400D01*
G03X921728I1256J-824D01*
G02X922062Y94200I335J219D01*
G01X925575D01*
G02X925909Y93581I-1J-400D01*
G03X928421I1256J-824D01*
G02X928755Y94200I335J219D01*
G01X932360D01*
G02X932637Y93511I0J-400D01*
G03X932591Y91535I971J-1011D01*
G02X932581Y90973I-290J-276D01*
G03X932536Y88873I1051J-1073D01*
G02Y88327I-292J-273D01*
G03X932592Y86216I1096J-1027D01*
G02X932607Y85655I-277J-288D01*
G03X934657I1025J-957D01*
G02X934672Y86216I292J273D01*
G03X934728Y88327I-1040J1084D01*
G02Y88873I292J273D01*
G03X934663Y90992I-1096J1027D01*
G02X934642Y91553I274J291D01*
G03X934579Y93511I-1034J947D01*
G02X934856Y94200I277J289D01*
G01X937294D01*
G02X937613Y93559I0J-400D01*
G03X937707Y91758I1119J-845D01*
G02X937691Y91197I-293J-272D01*
G03X937636Y89087I1041J-1083D01*
G02Y88541I-292J-273D01*
G03X937772Y86359I1096J-1027D01*
G02X937781Y85751I-256J-308D01*
G03X939653Y85736I928J-1051D01*
G02X939672Y86343I270J295D01*
G03X939828Y88541I-940J1171D01*
G02Y89087I292J273D01*
G03X939773Y91197I-1096J1027D01*
G02X939757Y91758I277J289D01*
G03X939851Y93559I-1025J956D01*
G02X940170Y94200I319J241D01*
G01X942307D01*
G02X942641Y93581I-1J-400D01*
G03X945153I1256J-824D01*
G02X945487Y94200I335J219D01*
G01X949000D01*
G02X949334Y93581I-1J-400D01*
G03X951846I1256J-824D01*
G02X952180Y94200I335J219D01*
G01X955890D01*
G02X956199Y93546I0J-400D01*
G03X958367I1084J-889D01*
G02X958676Y94200I309J254D01*
G01X962456D01*
G02X962775Y93560I-1J-400D01*
G03X965177I1201J-903D01*
G02X965496Y94200I320J240D01*
G01X969079D01*
G02X969413Y93581I-1J-400D01*
G03X971925I1256J-824D01*
G02X972259Y94200I335J219D01*
G01X982465D01*
G02X982799Y93581I-1J-400D01*
G03X985311I1256J-824D01*
G02X985645Y94200I335J219D01*
G01X989158D01*
G02X989492Y93581I-1J-400D01*
G03X992004I1256J-824D01*
G02X992338Y94200I335J219D01*
G01X1002433D01*
G02X1002767Y93581I-1J-400D01*
G03X1005279I1256J-824D01*
G02X1005613Y94200I335J219D01*
G01X1011012D01*
G02X1011304Y93527I0J-400D01*
G03X1013512Y91490I1096J-1027D01*
G02X1014103I296J-269D01*
G03X1016311Y93527I1112J1010D01*
G02X1016603Y94200I292J273D01*
G01X1034818D01*
G02X1035116Y93533I0J-400D01*
G03X1034196Y91128I2681J-2404D01*
G01Y86228D01*
G03X1041398I3601J0D01*
G01Y91128D01*
G03X1040478Y93533I-3601J1D01*
G02X1040776Y94200I298J267D01*
G01X1056086D01*
G02X1056420Y93581I-1J-400D01*
G03X1058932I1256J-824D01*
G02X1059266Y94200I335J219D01*
G01X1062779D01*
G02X1063113Y93581I-1J-400D01*
G03X1065625I1256J-824D01*
G02X1065959Y94200I335J219D01*
G01X1069472D01*
G02X1069806Y93581I-1J-400D01*
G03X1072318I1256J-824D01*
G02X1072652Y94200I335J219D01*
G01X1099591D01*
G02X1099925Y93581I-1J-400D01*
G03X1102437I1256J-824D01*
G02X1102771Y94200I335J219D01*
G01X1106284D01*
G02X1106618Y93581I-1J-400D01*
G03X1109130I1256J-824D01*
G02X1109464Y94200I335J219D01*
G01X1113068D01*
G02X1113345Y93511I0J-400D01*
G03X1113299Y91535I971J-1011D01*
G02X1113289Y90973I-290J-276D01*
G03X1113244Y88873I1051J-1073D01*
G02Y88327I-292J-273D01*
G03X1113300Y86216I1096J-1027D01*
G02X1113315Y85655I-277J-288D01*
G03X1115365I1025J-957D01*
G02X1115380Y86216I292J273D01*
G03X1115436Y88327I-1040J1084D01*
G02Y88873I292J273D01*
G03X1115371Y90992I-1096J1027D01*
G02X1115350Y91553I274J291D01*
G03X1115287Y93511I-1034J947D01*
G02X1115564Y94200I277J289D01*
G01X1118002D01*
G02X1118321Y93559I0J-400D01*
G03X1118415Y91758I1119J-845D01*
G02X1118399Y91197I-293J-272D01*
G03X1118344Y89087I1041J-1083D01*
G02Y88541I-292J-273D01*
G03X1118480Y86359I1096J-1027D01*
G02X1118489Y85751I-256J-308D01*
G03X1120361Y85736I928J-1051D01*
G02X1120380Y86343I270J295D01*
G03X1120536Y88541I-940J1171D01*
G02Y89087I292J273D01*
G03X1120481Y91197I-1096J1027D01*
G02X1120465Y91758I277J289D01*
G03X1120559Y93559I-1025J956D01*
G02X1120878Y94200I319J241D01*
G01X1123016D01*
G02X1123350Y93581I-1J-400D01*
G03X1125862I1256J-824D01*
G02X1126196Y94200I335J219D01*
G01X1129709D01*
G02X1130043Y93581I-1J-400D01*
G03X1132555I1256J-824D01*
G02X1132889Y94200I335J219D01*
G01X1136402D01*
G02X1136736Y93581I-1J-400D01*
G03X1139248I1256J-824D01*
G02X1139582Y94200I335J219D01*
G01X1143095D01*
G02X1143429Y93581I-1J-400D01*
G03X1145941I1256J-824D01*
G02X1146275Y94200I335J219D01*
G01X1149880D01*
G02X1150157Y93511I0J-400D01*
G03X1150111Y91535I971J-1011D01*
G02X1150101Y90973I-290J-276D01*
G03X1150056Y88873I1051J-1073D01*
G02Y88327I-292J-273D01*
G03X1150112Y86216I1096J-1027D01*
G02X1150127Y85655I-277J-288D01*
G03X1152177I1025J-957D01*
G02X1152192Y86216I292J273D01*
G03X1152248Y88327I-1040J1084D01*
G02Y88873I292J273D01*
G03X1152183Y90992I-1096J1027D01*
G02X1152162Y91553I274J291D01*
G03X1152099Y93511I-1034J947D01*
G02X1152376Y94200I277J289D01*
G01X1154814D01*
G02X1155133Y93559I0J-400D01*
G03X1155227Y91758I1119J-845D01*
G02X1155211Y91197I-293J-272D01*
G03X1155156Y89087I1041J-1083D01*
G02Y88541I-292J-273D01*
G03X1155292Y86359I1096J-1027D01*
G02X1155301Y85751I-256J-308D01*
G03X1157173Y85736I928J-1051D01*
G02X1157192Y86343I270J295D01*
G03X1157348Y88541I-940J1171D01*
G02Y89087I292J273D01*
G03X1157293Y91197I-1096J1027D01*
G02X1157277Y91758I277J289D01*
G03X1157371Y93559I-1025J956D01*
G02X1157690Y94200I319J241D01*
G01X1159827D01*
G02X1160161Y93581I-1J-400D01*
G03X1162673I1256J-824D01*
G02X1163007Y94200I335J219D01*
G01X1166520D01*
G02X1166854Y93581I-1J-400D01*
G03X1169366I1256J-824D01*
G02X1169700Y94200I335J219D01*
G01X1173213D01*
G02X1173547Y93581I-1J-400D01*
G03X1176059I1256J-824D01*
G02X1176393Y94200I335J219D01*
G01X1179906D01*
G02X1180240Y93581I-1J-400D01*
G03X1182752I1256J-824D01*
G02X1183086Y94200I335J219D01*
G01X1186691D01*
G02X1186968Y93511I0J-400D01*
G03X1186922Y91535I971J-1011D01*
G02X1186912Y90973I-290J-276D01*
G03X1186867Y88873I1051J-1073D01*
G02Y88327I-292J-273D01*
G03X1186923Y86216I1096J-1027D01*
G02X1186938Y85655I-277J-288D01*
G03X1188988I1025J-957D01*
G02X1189003Y86216I292J273D01*
G03X1189059Y88327I-1040J1084D01*
G02Y88873I292J273D01*
G03X1188994Y90992I-1096J1027D01*
G02X1188973Y91553I274J291D01*
G03X1188910Y93511I-1034J947D01*
G02X1189187Y94200I277J289D01*
G01X1191625D01*
G02X1191944Y93559I0J-400D01*
G03X1192038Y91758I1119J-845D01*
G02X1192022Y91197I-293J-272D01*
G03X1191967Y89087I1041J-1083D01*
G02Y88541I-292J-273D01*
G03X1192103Y86359I1096J-1027D01*
G02X1192112Y85751I-256J-308D01*
G03X1193984Y85736I928J-1051D01*
G02X1194003Y86343I270J295D01*
G03X1194159Y88541I-940J1171D01*
G02Y89087I292J273D01*
G03X1194104Y91197I-1096J1027D01*
G02X1194088Y91758I277J289D01*
G03X1194182Y93559I-1025J956D01*
G02X1194501Y94200I319J241D01*
G01X1196638D01*
G02X1196972Y93581I-1J-400D01*
G03X1199484I1256J-824D01*
G02X1199818Y94200I335J219D01*
G01X1203331D01*
G02X1203665Y93581I-1J-400D01*
G03X1206177I1256J-824D01*
G02X1206511Y94200I335J219D01*
G01X1210024D01*
G02X1210358Y93581I-1J-400D01*
G03X1212870I1256J-824D01*
G02X1213204Y94200I335J219D01*
G01X1216717D01*
G02X1217051Y93581I-1J-400D01*
G03X1219563I1256J-824D01*
G02X1219897Y94200I335J219D01*
G01X1223502D01*
G02X1223779Y93511I0J-400D01*
G03X1223733Y91535I971J-1011D01*
G02X1223723Y90973I-290J-276D01*
G03X1223678Y88873I1051J-1073D01*
G02Y88327I-292J-273D01*
G03X1223734Y86216I1096J-1027D01*
G02X1223749Y85655I-277J-288D01*
G03X1225799I1025J-957D01*
G02X1225814Y86216I292J273D01*
G03X1225870Y88327I-1040J1084D01*
G02Y88873I292J273D01*
G03X1225805Y90992I-1096J1027D01*
G02X1225784Y91553I274J291D01*
G03X1225721Y93511I-1034J947D01*
G02X1225998Y94200I277J289D01*
G01X1228436D01*
G02X1228755Y93559I0J-400D01*
G03X1228849Y91758I1119J-845D01*
G02X1228833Y91197I-293J-272D01*
G03X1228778Y89087I1041J-1083D01*
G02Y88541I-292J-273D01*
G03X1228914Y86359I1096J-1027D01*
G02X1228923Y85751I-256J-308D01*
G03X1230795Y85736I928J-1051D01*
G02X1230814Y86343I270J295D01*
G03X1230970Y88541I-940J1171D01*
G02Y89087I292J273D01*
G03X1230915Y91197I-1096J1027D01*
G02X1230899Y91758I277J289D01*
G03X1230993Y93559I-1025J956D01*
G02X1231312Y94200I319J241D01*
G01X1233449D01*
G02X1233783Y93581I-1J-400D01*
G03X1236295I1256J-824D01*
G02X1236629Y94200I335J219D01*
G01X1240142D01*
G02X1240476Y93581I-1J-400D01*
G03X1242988I1256J-824D01*
G02X1243322Y94200I335J219D01*
G01X1246905D01*
G02X1247224Y93560I-1J-400D01*
G03X1249626I1201J-903D01*
G02X1249945Y94200I320J240D01*
G01X1250428D01*
G02X1250726Y93533I0J-400D01*
G03X1252816I1045J-934D01*
G02X1253114Y94200I298J267D01*
G01X1253643D01*
G02X1253953Y93547I0J-400D01*
G03X1256439Y91885I1164J-949D01*
G02X1257143I352J-191D01*
G03X1259786I1321J714D01*
G02X1260489I352J-190D01*
G03X1263132I1322J714D01*
G02X1263836I352J-191D01*
G03X1266322Y93547I1322J713D01*
G02X1266632Y94200I310J253D01*
G01X1267149D01*
G02X1267467Y93557I0J-400D01*
G03X1269695I1114J-851D01*
G02X1270013Y94200I318J243D01*
G01X1283480D01*
G02X1283723Y93483I-1J-400D01*
G03X1290802Y93685I3679J-4805D01*
G02X1290744Y94299I225J331D01*
G01X1291001Y94556D01*
X1291056D01*
X1291800Y95300D01*
X1297100D01*
X1298200Y94200D01*
X1302000D01*
X1322000Y74200D01*
Y64601D01*
G02X1321805Y64402I-200J1D01*
G03Y61598I36J-1402D01*
G02X1322000Y61399I-5J-200D01*
G01Y44384D01*
X1321988Y44351D01*
G03Y43327I1412J-512D01*
G01X1322000Y43294D01*
Y41984D01*
X1321988Y41951D01*
G03Y40927I1412J-512D01*
G01X1322000Y40894D01*
Y39600D01*
X1330000Y31600D01*
Y-20500D01*
X1329000Y-21500D01*
X733491D01*
G37*
G36*
G01X786600Y202900D02*
X785000Y204500D01*
Y207098D01*
X785002D01*
Y212815D01*
X785000Y212816D01*
Y213000D01*
X784948Y213052D01*
Y365748D01*
X785448Y366248D01*
X819000D01*
X819727Y365521D01*
Y210689D01*
X820891Y209525D01*
X843533D01*
X881708Y247700D01*
X910778Y247681D01*
X912376D01*
G02X912689Y247032I0J-400D01*
G03X914885I1098J-872D01*
G02X915198Y247681I313J249D01*
G01X916125D01*
X916177Y247559D01*
G03X918757I1290J550D01*
G01X918809Y247681D01*
X919436D01*
G02X919749Y247032I0J-400D01*
G03X921945I1098J-872D01*
G02X922258Y247681I313J249D01*
G01X922885D01*
X922937Y247559D01*
G03X925517I1290J550D01*
G01X925569Y247681D01*
X926196D01*
G02X926509Y247032I0J-400D01*
G03X928705I1098J-872D01*
G02X929018Y247681I313J249D01*
G01X929645D01*
X929697Y247559D01*
G03X932277I1290J550D01*
G01X932329Y247681D01*
X936405D01*
X936457Y247559D01*
G03X939037I1290J550D01*
G01X939089Y247681D01*
X943165D01*
X943217Y247559D01*
G03X945797I1290J550D01*
G01X945849Y247681D01*
X949925D01*
X949977Y247559D01*
G03X952557I1290J550D01*
G01X952609Y247681D01*
X956684D01*
X956736Y247559D01*
G03X959316I1290J550D01*
G01X959368Y247681D01*
X959995D01*
G02X960308Y247032I0J-400D01*
G03X962504I1098J-872D01*
G02X962817Y247681I313J249D01*
G01X963444D01*
X963496Y247559D01*
G03X966076I1290J550D01*
G01X966128Y247681D01*
X970204D01*
X970256Y247559D01*
G03X972836I1290J550D01*
G01X972888Y247681D01*
X973515D01*
G02X973828Y247032I0J-400D01*
G03X976024I1098J-872D01*
G02X976337Y247681I313J249D01*
G01X976964D01*
X977016Y247559D01*
G03X979596I1290J550D01*
G01X979648Y247681D01*
X980275D01*
G02X980588Y247032I0J-400D01*
G03X982784I1098J-872D01*
G02X983097Y247681I313J249D01*
G01X983724D01*
X983776Y247559D01*
G03X986356I1290J550D01*
G01X986408Y247681D01*
X990484D01*
X990536Y247559D01*
G03X993116I1290J550D01*
G01X993168Y247681D01*
X993795D01*
G02X994108Y247032I0J-400D01*
G03X996304I1098J-872D01*
G02X996617Y247681I313J249D01*
G01X997244D01*
X997296Y247559D01*
G03X999876I1290J550D01*
G01X999928Y247681D01*
X1000554D01*
G02X1000867Y247032I0J-400D01*
G03X1003063I1098J-872D01*
G02X1003376Y247681I313J249D01*
G01X1004003D01*
X1004055Y247559D01*
G03X1006635I1290J550D01*
G01X1006687Y247681D01*
X1007314D01*
G02X1007627Y247032I0J-400D01*
G03X1009823I1098J-872D01*
G02X1010136Y247681I313J249D01*
G01X1010763D01*
X1010815Y247559D01*
G03X1013395I1290J550D01*
G01X1013447Y247681D01*
X1014074D01*
G02X1014387Y247032I0J-400D01*
G03X1016583I1098J-872D01*
G02X1016896Y247681I313J249D01*
G01X1017523D01*
X1017575Y247559D01*
G03X1020155I1290J550D01*
G01X1020207Y247681D01*
X1020834D01*
G02X1021147Y247032I0J-400D01*
G03X1023343I1098J-872D01*
G02X1023656Y247681I313J249D01*
G01X1024283D01*
X1024335Y247559D01*
G03X1026915I1290J550D01*
G01X1026967Y247681D01*
X1027594D01*
G02X1027907Y247032I0J-400D01*
G03X1030103I1098J-872D01*
G02X1030416Y247681I313J249D01*
G01X1031689D01*
X1035108Y251100D01*
X1058367D01*
X1059008Y250459D01*
Y245463D01*
G02X1058321Y245185I-400J0D01*
G03Y243233I-1007J-976D01*
G02X1059008Y242955I287J-278D01*
G01Y241563D01*
G02X1058321Y241285I-400J0D01*
G03Y239333I-1007J-976D01*
G02X1059008Y239055I287J-278D01*
G01Y237663D01*
G02X1058321Y237385I-400J0D01*
G03Y235433I-1007J-976D01*
G02X1059008Y235155I287J-278D01*
G01Y233763D01*
G02X1058321Y233485I-400J0D01*
G03Y231533I-1007J-976D01*
G02X1059008Y231255I287J-278D01*
G01Y229864D01*
G02X1058321Y229586I-400J0D01*
G03Y227634I-1007J-976D01*
G02X1059008Y227356I287J-278D01*
G01Y225963D01*
G02X1058321Y225685I-400J0D01*
G03Y223733I-1007J-976D01*
G02X1059008Y223455I287J-278D01*
G01Y218163D01*
G02X1058321Y217885I-400J0D01*
G03Y215933I-1007J-976D01*
G02X1059008Y215655I287J-278D01*
G01Y203819D01*
X1058089Y202900D01*
X1051086D01*
G02X1050686Y203291I0J400D01*
G03X1047882I-1402J-31D01*
G02X1047482Y202900I-400J9D01*
G01X1044326D01*
G02X1043926Y203291I0J400D01*
G03X1041122I-1402J-31D01*
G02X1040722Y202900I-400J9D01*
G01X1017287D01*
G02X1016887Y203291I0J400D01*
G03X1014083I-1402J-31D01*
G02X1013683Y202900I-400J9D01*
G01X997008D01*
G02X996608Y203291I0J400D01*
G03X993804I-1402J-31D01*
G02X993404Y202900I-400J9D01*
G01X990247D01*
G02X989848Y203291I1J400D01*
G03X987044I-1402J-33D01*
G02X986645Y202900I-400J9D01*
G01X942929D01*
G02X942529Y203291I0J400D01*
G03X939725I-1402J-31D01*
G02X939325Y202900I-400J9D01*
G01X936169D01*
G02X935769Y203291I0J400D01*
G03X932965I-1402J-31D01*
G02X932565Y202900I-400J9D01*
G01X922649D01*
G02X922249Y203291I0J400D01*
G03X919445I-1402J-31D01*
G02X919045Y202900I-400J9D01*
G01X820415D01*
G03X817505I-1455J-670D01*
G01X810154D01*
G02X809756Y203346I0J400D01*
G03X806574I-1591J183D01*
G02X806176Y202900I-398J-46D01*
G01X804745D01*
X804732Y203085D01*
G03X801536I-1598J-116D01*
G01X801523Y202900D01*
X798974D01*
G03X796460I-1257J-993D01*
G01X786600D01*
G37*
G36*
G01X822100Y210800D02*
X821500Y211400D01*
Y213314D01*
X821674Y213337D01*
G03Y216513I-208J1588D01*
G01X821500Y216536D01*
X821508Y363100D01*
X822108Y363700D01*
X840823D01*
G02X841218Y363233I0J-400D01*
G03X843573Y361990I1382J-233D01*
G02X844127I277J-288D01*
G03X846073I973J1010D01*
G02X846627I277J-288D01*
G03X848982Y363233I973J1010D01*
G02X849377Y363700I395J67D01*
G01X863926D01*
X865269Y362500D01*
X897514Y330255D01*
X915672D01*
G02X916070Y329889I0J-400D01*
G03X918864I1397J120D01*
G02X919262Y330255I398J-34D01*
G01X922239D01*
X922881Y329613D01*
X922896Y329568D01*
G03X923786Y328678I1331J441D01*
G01X923831Y328663D01*
X924310Y328184D01*
G02X924072Y327503I-282J-283D01*
G03X925620Y325955I155J-1393D01*
G02X926301Y326193I398J-44D01*
G01X926628Y325866D01*
G02X926611Y325284I-283J-283D01*
G03X928731Y323164I996J-1124D01*
G02X929313Y323181I299J-266D01*
G01X929667Y322827D01*
X929623Y322707D01*
G03X931485Y320845I1364J-498D01*
G01X931605Y320889D01*
X934127Y318367D01*
G02X933960Y317702I-283J-282D01*
G03X935715Y316746I407J-1342D01*
G02X936099Y317256I384J110D01*
G01X936821D01*
G03X938673I926J1053D01*
G01X939395D01*
G02X939779Y316746I0J-400D01*
G03X942475I1348J-386D01*
G02X942859Y317256I384J110D01*
G01X943581D01*
G03X945433I926J1053D01*
G01X946155D01*
G02X946539Y316746I0J-400D01*
G03X949235I1348J-386D01*
G02X949619Y317256I384J110D01*
G01X950341D01*
G03X952193I926J1053D01*
G01X952915D01*
G02X953299Y316746I0J-400D01*
G03X955995I1348J-386D01*
G02X956379Y317256I384J110D01*
G01X957100D01*
G03X958952I926J1053D01*
G01X959674D01*
G02X960058Y316746I0J-400D01*
G03X962754I1348J-386D01*
G02X963138Y317256I384J110D01*
G01X963715D01*
G03X964435Y316849I1070J1053D01*
G01X964489Y316835D01*
X964845Y316480D01*
G02X964612Y315800I-283J-283D01*
G03X966177Y314235I174J-1391D01*
G02X966857Y314468I397J-50D01*
G01X967243Y314082D01*
G02X967228Y313502I-283J-283D01*
G03X969208Y311521I938J-1042D01*
G02X969788Y311537I298J-267D01*
G01X969974Y311350D01*
X970278D01*
Y311108D01*
X970261Y311070D01*
G03X972905Y310852I1285J-561D01*
G02X973293Y311350I388J98D01*
G01X974070D01*
G03X975782I856J1110D01*
G01X976559D01*
G02X976947Y310852I0J-400D01*
G03X979665I1359J-343D01*
G02X980053Y311350I388J98D01*
G01X980830D01*
G03X982542I856J1110D01*
G01X983319D01*
G02X983707Y310852I0J-400D01*
G03X986159Y311387I1359J-343D01*
G02X986174Y311654I156J125D01*
G01X986521Y312001D01*
G02X987168Y311883I283J-283D01*
G03X987959Y313775I1278J577D01*
G02X987420Y314150I-139J375D01*
G01Y314670D01*
G02X987959Y315045I400J0D01*
G03X989154Y317570I487J1315D01*
G02X989073Y318198I202J345D01*
G01X990225Y319350D01*
Y320866D01*
G02X990892Y321164I400J0D01*
G03Y323254I934J1045D01*
G02X990225Y323552I-267J298D01*
G01Y324767D01*
G02X990892Y325065I400J0D01*
G03Y327155I934J1045D01*
G02X990225Y327453I-267J298D01*
G01Y328666D01*
G02X990892Y328964I400J0D01*
G03Y331054I934J1045D01*
G02X990225Y331352I-267J298D01*
G01Y332566D01*
G02X990892Y332864I400J0D01*
G03Y334954I934J1045D01*
G02X990225Y335252I-267J298D01*
G01Y335472D01*
X991269Y336516D01*
X991386Y336478D01*
G03X993157Y338249I440J1331D01*
G01X993119Y338366D01*
X993587Y338834D01*
G02X994166Y338819I282J-283D01*
G03X996608Y339750I1040J941D01*
G01X996609Y339948D01*
X1000462D01*
X1000463Y339749D01*
G03X1003467I1502J11D01*
G01X1003468Y339948D01*
X1007322D01*
X1007323Y339750D01*
G03X1009763Y340702I1402J10D01*
G02X1009777Y341254I296J269D01*
G01X1010075Y341552D01*
G02X1010745Y341367I282J-283D01*
G03X1012447Y343069I1360J342D01*
G02X1012262Y343739I98J388D01*
G01X1012801Y344278D01*
G03X1013423Y344888I-696J1331D01*
G01X1013437Y344914D01*
X1014760Y346237D01*
X1014885Y346183D01*
G03X1016856Y346948I600J1377D01*
G01X1016909Y347066D01*
X1017406D01*
G02X1017730Y346431I0J-400D01*
G03X1020000I1135J-822D01*
G02X1020324Y347066I324J235D01*
G01X1020927D01*
X1020981Y346953D01*
G03X1023509I1264J607D01*
G01X1023563Y347066D01*
X1024166D01*
G02X1024490Y346431I0J-400D01*
G03X1026760I1135J-822D01*
G02X1027084Y347066I324J235D01*
G01X1027687D01*
X1027741Y346953D01*
G03X1030271Y346958I1264J607D01*
G01X1030286Y346989D01*
X1031621Y348324D01*
X1031751Y348259D01*
G03X1033538Y348712I634J1250D01*
G01X1053679D01*
G02X1053953Y348021I0J-400D01*
G03X1055875I961J-1021D01*
G02X1056149Y348712I274J291D01*
G01X1059420D01*
X1060766Y350058D01*
X1060837Y350065D01*
G03X1062089Y351317I-143J1395D01*
G01X1062096Y351388D01*
X1063308Y352600D01*
X1063323D01*
X1063664Y352941D01*
X1074907D01*
G02X1075305Y352575I0J-400D01*
G03X1078099I1397J121D01*
G02X1078497Y352941I398J-34D01*
G01X1081667D01*
G02X1082065Y352575I0J-400D01*
G03X1084859I1397J121D01*
G02X1085257Y352941I398J-34D01*
G01X1088426D01*
G02X1088824Y352575I0J-400D01*
G03X1091618I1397J121D01*
G02X1092016Y352941I398J-34D01*
G01X1095186D01*
G02X1095584Y352575I0J-400D01*
G03X1098378I1397J121D01*
G02X1098776Y352941I398J-34D01*
G01X1099020D01*
X1099521Y352440D01*
G02X1099488Y351844I-282J-283D01*
G03X1101458Y349874I873J-1097D01*
G02X1102054Y349907I313J-249D01*
G01X1102500Y349461D01*
X1102448Y349338D01*
G03X1102608Y347970I1293J-542D01*
G01Y342100D01*
X1098944Y338436D01*
X1098900Y338420D01*
G03X1097972Y337492I491J-1419D01*
G01X1097956Y337448D01*
X1085294Y324786D01*
G02X1084653Y324890I-283J283D01*
G03X1082504Y322741I-1433J-716D01*
G02X1082608Y322100I-179J-358D01*
G01X1073808Y313300D01*
X1060400D01*
X1058008Y310908D01*
Y297569D01*
G02X1057400Y297227I-400J0D01*
G03X1055367Y296920I-833J-1368D01*
G02X1054767I-300J265D01*
G03Y294798I-1200J-1061D01*
G02X1055367I300J-265D01*
G03X1057400Y294491I1200J1061D01*
G02X1058008Y294149I208J-342D01*
G01Y280641D01*
G02X1057407Y280295I-400J0D01*
G03X1055344Y279902I-805J-1385D01*
G02X1054717I-314J248D01*
G03X1052039Y279652I-1258J-992D01*
G02X1051322Y279670I-354J186D01*
G03X1051287Y278257I-1455J-671D01*
G02X1052004Y278239I354J-186D01*
G03X1054717Y277918I1455J671D01*
G02X1055344I314J-248D01*
G03X1057407Y277525I1258J992D01*
G02X1058008Y277179I201J-346D01*
G01Y266859D01*
G02X1057527Y266468I-400J1D01*
G03X1056002Y265960I-325J-1569D01*
G02X1055402I-300J265D01*
G03Y263838I-1200J-1061D01*
G02X1056002I300J-265D01*
G03X1057527Y263330I1200J1061D01*
G02X1058008Y262939I81J-392D01*
G01Y253100D01*
X1057208Y252300D01*
X1034283D01*
X1030981Y248998D01*
X1030681D01*
G02X1030309Y249545I0J400D01*
G03X1027701I-1304J515D01*
G02X1027329Y248998I-372J-147D01*
G01X1026709D01*
G03X1024541I-1084J-889D01*
G01X1023921D01*
G02X1023549Y249545I0J400D01*
G03X1020941I-1304J515D01*
G02X1020569Y248998I-372J-147D01*
G01X1020076D01*
G03X1017654I-1211J-889D01*
G01X1017268D01*
G02X1016893Y249537I0J400D01*
G03X1014077I-1408J523D01*
G02X1013702Y248998I-375J-139D01*
G01X1013316D01*
G03X1010894I-1211J-889D01*
G01X1010508D01*
G02X1010133Y249537I0J400D01*
G03X1007317I-1408J523D01*
G02X1006942Y248998I-375J-139D01*
G01X1006429D01*
G03X1004261I-1084J-889D01*
G01X1003748D01*
G02X1003373Y249537I0J400D01*
G03X1000557I-1408J523D01*
G02X1000182Y248998I-375J-139D01*
G01X999670D01*
G03X997502I-1084J-889D01*
G01X996989D01*
G02X996614Y249537I0J400D01*
G03X993798I-1408J523D01*
G02X993423Y248998I-375J-139D01*
G01X992910D01*
G03X990742I-1084J-889D01*
G01X990122D01*
G02X989750Y249545I0J400D01*
G03X987142I-1304J515D01*
G02X986770Y248998I-372J-147D01*
G01X986150D01*
G03X983982I-1084J-889D01*
G01X983362D01*
G02X982990Y249545I0J400D01*
G03X980382I-1304J515D01*
G02X980010Y248998I-372J-147D01*
G01X979390D01*
G03X977222I-1084J-889D01*
G01X976602D01*
G02X976230Y249545I0J400D01*
G03X973622I-1304J515D01*
G02X973250Y248998I-372J-147D01*
G01X972630D01*
G03X970462I-1084J-889D01*
G01X969949D01*
G02X969574Y249537I0J400D01*
G03X966758I-1408J523D01*
G02X966383Y248998I-375J-139D01*
G01X965997D01*
G03X963575I-1211J-889D01*
G01X959237D01*
G03X956815I-1211J-889D01*
G01X956323D01*
G02X955951Y249545I0J400D01*
G03X953343I-1304J515D01*
G02X952971Y248998I-372J-147D01*
G01X952351D01*
G03X950183I-1084J-889D01*
G01X949563D01*
G02X949191Y249545I0J400D01*
G03X946583I-1304J515D01*
G02X946211Y248998I-372J-147D01*
G01X945591D01*
G03X943423I-1084J-889D01*
G01X942803D01*
G02X942431Y249545I0J400D01*
G03X939823I-1304J515D01*
G02X939451Y248998I-372J-147D01*
G01X938831D01*
G03X936663I-1084J-889D01*
G01X936043D01*
G02X935671Y249545I0J400D01*
G03X933063I-1304J515D01*
G02X932691Y248998I-372J-147D01*
G01X932071D01*
G03X929903I-1084J-889D01*
G01X929283D01*
G02X928911Y249545I0J400D01*
G03X926303I-1304J515D01*
G02X925931Y248998I-372J-147D01*
G01X925311D01*
G03X923143I-1084J-889D01*
G01X922523D01*
G02X922151Y249545I0J400D01*
G03X919543I-1304J515D01*
G02X919171Y248998I-372J-147D01*
G01X918551D01*
G03X916383I-1084J-889D01*
G01X915463D01*
G02X915091Y249545I0J400D01*
G03X912483I-1304J515D01*
G02X912111Y248998I-372J-147D01*
G01X911394D01*
X911392Y249000D01*
X881408D01*
X843208Y210800D01*
X822100D01*
G37*
G36*
G01X970389Y312352D02*
X964484Y318258D01*
X964150D01*
X964144Y318264D01*
X959439D01*
X959421Y318445D01*
G03X956631I-1395J-136D01*
G01X956613Y318264D01*
X952680D01*
X952662Y318445D01*
G03X949872I-1395J-136D01*
G01X949854Y318264D01*
X945920D01*
X945902Y318445D01*
G03X943112I-1395J-136D01*
G01X943094Y318264D01*
X939160D01*
X939142Y318445D01*
G03X936581Y319087I-1395J-136D01*
G02X935965Y319026I-333J222D01*
G01X935595Y319396D01*
G03X933629Y321568I-1228J864D01*
G01X933497Y321494D01*
X932384Y322607D01*
X932370Y322653D01*
G03X931431Y323592I-1383J-444D01*
G01X931385Y323606D01*
X930949Y324042D01*
G02X931178Y324721I283J283D01*
G03X929598Y326301I-191J1389D01*
G02X928919Y326072I-396J54D01*
G01X928542Y326449D01*
G02X928555Y327027I283J283D01*
G03X926574Y329008I-948J1033D01*
G02X925996Y328995I-295J270D01*
G01X925525Y329466D01*
X925562Y329582D01*
G03X923604Y331265I-1335J427D01*
G01X923562Y331244D01*
X922906D01*
X922897Y331252D01*
X922658D01*
X922654Y331256D01*
X922623D01*
G02X922229Y331724I0J400D01*
G03X919465I-1382J236D01*
G02X919071Y331256I-394J-68D01*
G01X918108D01*
X918068Y331276D01*
G03X916866I-601J-1267D01*
G01X916826Y331256D01*
X915563D01*
G02X915169Y331724I0J400D01*
G03X912405I-1382J236D01*
G02X912011Y331256I-394J-68D01*
G01X911062D01*
X911018Y331300D01*
X898072D01*
X864172Y365200D01*
X824108D01*
X824079Y365229D01*
X821371D01*
X820728Y365872D01*
Y365936D01*
X819415Y367250D01*
X819350D01*
X818950Y367650D01*
Y403850D01*
X821713Y406613D01*
X872995D01*
X915878Y363730D01*
X923974D01*
X923990Y363727D01*
G03X924464I237J1382D01*
G01X924480Y363730D01*
X925276D01*
X926270Y362736D01*
X926285Y362693D01*
G03X927140Y361838I1322J467D01*
G01X927183Y361823D01*
X927674Y361332D01*
G02X927439Y360652I-283J-283D01*
G03X928999Y359092I168J-1392D01*
G02X929679Y359327I397J-48D01*
G01X930070Y358936D01*
G02X930053Y358355I-283J-282D01*
G03X932033Y356375I934J-1046D01*
G02X932614Y356392I299J-266D01*
G01X933079Y355927D01*
X933039Y355809D01*
G03X934816Y354032I1328J-449D01*
G01X934934Y354072D01*
X937494Y351512D01*
G02X937330Y350848I-283J-282D01*
G03X939086Y349092I417J-1339D01*
G02X939750Y349256I382J-119D01*
G01X940295Y348711D01*
X940153Y348568D01*
X940152Y348567D01*
G03X942514Y347359I975J-1007D01*
G01X942539Y347530D01*
X946475D01*
X946500Y347359D01*
G03X949274I1387J201D01*
G01X949299Y347530D01*
X953235D01*
X953260Y347359D01*
G03X956034I1387J201D01*
G01X956059Y347530D01*
X959894D01*
X959918Y347357D01*
G03X962894I1488J203D01*
G01X962918Y347530D01*
X966078D01*
X970382Y343226D01*
G02X970403Y342684I-283J-282D01*
G03X972521Y340566I1143J-975D01*
G02X973063Y340545I260J-304D01*
G01X973552Y340056D01*
X973538Y339957D01*
G03X976212Y339201I1388J-197D01*
G01X976264Y339321D01*
X976888D01*
G02X977203Y338674I0J-400D01*
G03X979409I1103J-865D01*
G02X979724Y339321I315J247D01*
G01X980348D01*
X980400Y339201D01*
G03X982972I1286J559D01*
G01X983024Y339321D01*
X983648D01*
G02X983963Y338674I0J-400D01*
G03X986169I1103J-865D01*
G02X986484Y339321I315J247D01*
G01X987108D01*
X987160Y339201D01*
G03X988792Y338401I1286J559D01*
G01X988902Y338430D01*
X989400Y337932D01*
Y337575D01*
G02X988877Y337194I-400J0D01*
G03X988740Y334489I-431J-1334D01*
G02X989224Y334098I84J-391D01*
G01Y333722D01*
G02X988740Y333331I-400J0D01*
G03Y330589I-294J-1371D01*
G02X989224Y330198I84J-391D01*
G01Y319765D01*
X987566Y318107D01*
X986418Y316960D01*
Y316950D01*
X986308Y316840D01*
Y313204D01*
X985455Y312352D01*
X983096D01*
X983086Y312540D01*
G03X980286I-1400J-80D01*
G01X980276Y312352D01*
X976336D01*
X976326Y312540D01*
G03X973526I-1400J-80D01*
G01X973516Y312352D01*
X970389D01*
G37*
G36*
G01X975818Y340842D02*
G03X975002Y341160I-892J-1082D01*
G01X974926Y341164D01*
X972263Y343827D01*
G02X972324Y344443I283J283D01*
G03X970380Y346387I-778J1166D01*
G02X969764Y346326I-333J222D01*
G01X967485Y348605D01*
X966516D01*
G02X966132Y349117I0J400D01*
G03X963440I-1346J392D01*
G02X963056Y348605I-384J-112D01*
G01X962341D01*
G03X960471I-935J-1045D01*
G01X959756D01*
G02X959372Y349117I0J400D01*
G03X956680I-1346J392D01*
G02X956296Y348605I-384J-112D01*
G01X955582D01*
G03X953712I-935J-1045D01*
G01X948822D01*
G03X946952I-935J-1045D01*
G01X944053D01*
X942161Y350497D01*
X942261Y350636D01*
G03X940172Y352486I-1135J823D01*
G01X939147Y353511D01*
X939139Y353579D01*
G03X937917Y354801I-1392J-170D01*
G01X937849Y354809D01*
X937434Y355224D01*
G02X937723Y355907I282J283D01*
G03X936345Y357285I24J1402D01*
G02X935662Y356996I-400J-7D01*
G01X935141Y357517D01*
G02X935189Y358124I282J283D01*
G03X933231Y360082I-822J1136D01*
G02X932624Y360034I-324J234D01*
G01X932187Y360471D01*
X932249Y360599D01*
G03X930377Y362471I-1262J610D01*
G01X930249Y362409D01*
X928851Y363807D01*
X928837Y363832D01*
G03X928279Y364390I-1230J-672D01*
G01X928254Y364404D01*
X925408Y367250D01*
X914750D01*
X884951Y397049D01*
Y405302D01*
X889149Y409500D01*
X1098750D01*
X1099049Y409201D01*
Y398042D01*
X1099038Y398010D01*
G03Y397084I1323J-463D01*
G01X1099049Y397052D01*
Y394142D01*
X1099038Y394110D01*
G03Y393184I1323J-463D01*
G01X1099049Y393152D01*
Y390242D01*
X1099038Y390210D01*
G03Y389284I1323J-463D01*
G01X1099049Y389252D01*
Y386342D01*
X1099038Y386310D01*
G03Y385384I1323J-463D01*
G01X1099049Y385352D01*
Y382442D01*
X1099038Y382410D01*
G03Y381484I1323J-463D01*
G01X1099049Y381452D01*
Y378542D01*
X1099038Y378510D01*
G03Y377584I1323J-463D01*
G01X1099049Y377552D01*
Y374641D01*
X1099038Y374609D01*
G03Y373683I1323J-463D01*
G01X1099049Y373651D01*
Y370742D01*
X1099038Y370710D01*
G03Y369784I1323J-463D01*
G01X1099049Y369752D01*
Y366842D01*
X1099038Y366810D01*
G03Y365884I1323J-463D01*
G01X1099049Y365852D01*
Y362942D01*
X1099038Y362910D01*
G03Y361984I1323J-463D01*
G01X1099049Y361952D01*
Y359042D01*
X1099038Y359010D01*
G03Y358084I1323J-463D01*
G01X1099049Y358052D01*
Y355142D01*
X1099038Y355110D01*
G03X1098960Y354687I1323J-463D01*
G01X1098957Y354607D01*
X1098725Y354375D01*
X1095398D01*
G02X1094999Y354747I0J400D01*
G03X1092203I-1398J-100D01*
G02X1091804Y354375I-399J28D01*
G01X1062398D01*
G02X1062020Y354905I0J400D01*
G03X1060064Y354107I-1326J455D01*
G02X1060167Y353467I-180J-357D01*
G01X1056700Y350000D01*
X1035000D01*
X1034000Y351000D01*
X1031100D01*
X1029063Y348963D01*
X1028982Y348962D01*
G03X1028246Y348739I23J-1402D01*
G01X1027389D01*
G02X1026997Y349221I0J400D01*
G03X1024253I-1372J288D01*
G02X1023861Y348739I-392J-82D01*
G01X1023004D01*
G03X1021486I-759J-1179D01*
G01X1020629D01*
G02X1020237Y349221I0J400D01*
G03X1017493I-1372J288D01*
G02X1017101Y348739I-392J-82D01*
G01X1016244D01*
G03X1014087Y347661I-759J-1179D01*
G01X1014081Y347586D01*
X1013104Y346609D01*
X1012964Y346717D01*
G03X1011113Y344618I-859J-1108D01*
G01X1010639Y344144D01*
G02X1009994Y344256I-283J282D01*
G03X1008129Y342391I-1269J-596D01*
G02X1008241Y341746I-170J-362D01*
G01X1007444Y340950D01*
X1007111D01*
G02X1006719Y341429I0J400D01*
G03X1003971I-1374J280D01*
G02X1003579Y340950I-392J-79D01*
G01X1002707D01*
G03X1001223I-742J-1190D01*
G01X1000352D01*
G02X999960Y341429I0J400D01*
G03X997212I-1374J280D01*
G02X996820Y340950I-392J-79D01*
G01X995948D01*
G03X994508Y340976I-742J-1190D01*
G01X994462Y340950D01*
X994286D01*
X994179Y340842D01*
X993566D01*
G02X993180Y341346I0J400D01*
G03X990472I-1354J363D01*
G02X990086Y340842I-386J-104D01*
G01X989338D01*
G03X987554I-892J-1082D01*
G01X986806D01*
G02X986420Y341346I0J400D01*
G03X983712I-1354J363D01*
G02X983326Y340842I-386J-104D01*
G01X982578D01*
G03X980794I-892J-1082D01*
G01X980046D01*
G02X979660Y341346I0J400D01*
G03X976952I-1354J363D01*
G02X976566Y340842I-386J-104D01*
G01X975818D01*
G37*
G36*
G01X1277069Y162883D02*
X1251452Y188500D01*
X1228000Y202261D01*
X1228002Y202377D01*
G03X1225064Y202841I-1502J23D01*
G01X1225021Y202700D01*
X1197892D01*
X1197866Y202707D01*
G03X1197118I-374J-1351D01*
G01X1197092Y202700D01*
X1189677D01*
X1189626Y202823D01*
G03X1186852I-1387J-576D01*
G01X1186801Y202700D01*
X1185998D01*
G02X1185745Y203410I0J400D01*
G03X1183973I-886J1086D01*
G02X1183720Y202700I-253J-310D01*
G01X1182982D01*
X1182948Y202859D01*
G03X1180010I-1469J-312D01*
G01X1179976Y202700D01*
X1179391D01*
G02X1179119Y203394I-1J400D01*
G03X1177079I-1020J1102D01*
G02X1176807Y202700I-271J-294D01*
G01X1176222D01*
X1176188Y202859D01*
G03X1173250I-1469J-312D01*
G01X1173216Y202700D01*
X1066381D01*
G02X1066128Y203410I0J400D01*
G03X1064356I-886J1086D01*
G02X1064103Y202700I-253J-310D01*
G01X1060900D01*
X1060010Y203590D01*
Y205785D01*
Y262797D01*
G02X1060408Y263197I400J0D01*
G03X1061602Y263738I-6J1602D01*
G02X1062202I300J-265D01*
G03X1064524Y263655I1200J1061D01*
G02X1065103Y263636I280J-285D01*
G03X1065178Y265844I1197J1065D01*
G02X1064599Y265863I-280J285D01*
G03X1062202Y265860I-1197J-1064D01*
G02X1061602I-300J265D01*
G03X1060408Y266401I-1200J-1061D01*
G02X1060010Y266801I2J400D01*
G01Y276985D01*
G02X1060519Y277369I400J-1D01*
G03X1062036Y277725I439J1541D01*
G02X1062574I269J-296D01*
G03Y280095I1078J1185D01*
G02X1062036I-269J296D01*
G03X1060519Y280451I-1078J-1185D01*
G02X1060010Y280835I-109J385D01*
G01Y293889D01*
G02X1060481Y294283I400J0D01*
G03X1061967Y294798I286J1576D01*
G02X1062567I300J-265D01*
G03Y296920I1200J1061D01*
G02X1061967I-300J265D01*
G03X1060481Y297435I-1200J-1061D01*
G02X1060010Y297829I-71J394D01*
G01Y311045D01*
X1061065Y312100D01*
X1077800D01*
X1085400Y319700D01*
X1087500D01*
X1087600Y319600D01*
X1112111D01*
X1112130Y319619D01*
X1113402D01*
X1113453Y319496D01*
G03X1116225I1386J579D01*
G01X1116276Y319619D01*
X1125988D01*
X1126002Y319435D01*
G03X1128801Y319609I1398J112D01*
G01X1128797Y319697D01*
X1129621Y320521D01*
X1129762Y320391D01*
G03X1130387Y322946I1018J1105D01*
G02X1129882Y323332I-105J386D01*
G01Y323560D01*
G02X1130387Y323946I400J0D01*
G03X1129713Y326453I393J1450D01*
G01X1129571Y326311D01*
X1128783Y327099D01*
X1128794Y327194D01*
G03X1127247Y328741I-1394J153D01*
G01X1127152Y328730D01*
X1126350Y329532D01*
Y335450D01*
X1125600Y336200D01*
Y341813D01*
G02X1126311Y342064I400J0D01*
G03Y343830I1089J883D01*
G02X1125600Y344081I-311J251D01*
G01Y345560D01*
G02X1126294Y345830I400J-1D01*
G03Y347864I1106J1017D01*
G02X1125600Y348134I-294J271D01*
G01Y349460D01*
G02X1126294Y349730I400J-1D01*
G03Y351764I1106J1017D01*
G02X1125600Y352034I-294J271D01*
G01Y353513D01*
G02X1126311Y353764I400J0D01*
G03X1127701Y356016I1089J883D01*
G02X1127504Y356690I86J391D01*
G01X1128234Y357420D01*
G03X1128527Y357713I-834J1127D01*
G01X1130085Y359271D01*
X1130210Y359215D01*
G03X1132158Y360237I570J1281D01*
G01X1132189Y360400D01*
X1135900D01*
X1136192Y360108D01*
X1136207Y360062D01*
G03X1137106Y359163I1333J434D01*
G01X1137152Y359148D01*
X1137540Y358760D01*
G02X1137317Y358081I-282J-283D01*
G03X1139025Y356373I223J-1485D01*
G02X1139704Y356596I396J-59D01*
G01X1139944Y356356D01*
G02X1139926Y355773I-283J-283D01*
G03X1140285Y353286I994J-1126D01*
G01X1140400Y353232D01*
Y352055D01*
X1140290Y351999D01*
G03Y349495I630J-1252D01*
G01X1140400Y349439D01*
Y348155D01*
X1140290Y348099D01*
G03Y345595I630J-1252D01*
G01X1140400Y345539D01*
Y344362D01*
X1140285Y344308D01*
G03X1140449Y341521I635J-1361D01*
G01X1140494Y341506D01*
X1140895Y341105D01*
G02X1140982Y340975I-283J-283D01*
G01X1141312Y340645D01*
X1141106Y340440D01*
X1141015Y340446D01*
G03X1142319Y339142I-95J-1399D01*
G01X1142313Y339233D01*
X1142518Y339439D01*
X1142849Y339108D01*
G02X1142978Y339022I-153J-370D01*
G01X1143328Y338672D01*
G02X1143324Y338102I-283J-283D01*
G03X1145699Y337012I976J-1006D01*
G01X1145711Y337200D01*
X1148800D01*
X1150802Y335198D01*
G02X1150639Y334533I-283J-283D01*
G03X1152103Y332259I421J-1337D01*
G02X1152800Y331991I297J-268D01*
G01Y320000D01*
X1152750Y319950D01*
Y314450D01*
X1151600Y313300D01*
Y311694D01*
G02X1151171Y311295I-400J0D01*
G03Y308299I-111J-1498D01*
G02X1151600Y307900I29J-399D01*
G01Y307693D01*
G02X1151169Y307294I-400J0D01*
G03Y304498I-109J-1398D01*
G02X1151600Y304099I31J-399D01*
G01Y299893D01*
G02X1151169Y299494I-400J0D01*
G03X1152415Y297736I-109J-1398D01*
G02X1153084Y297916I386J-103D01*
G01X1153100Y297900D01*
X1156100D01*
X1158000Y299800D01*
X1158900D01*
X1159053Y299953D01*
G02X1159728Y299749I283J-283D01*
G03X1161498Y301519I1472J298D01*
G02X1161294Y302194I79J392D01*
G01X1161598Y302498D01*
X1161645Y302512D01*
G03X1162275Y302898I-446J1435D01*
G01X1162849D01*
G02X1163234Y302387I1J-400D01*
G03X1165843Y301387I1346J-391D01*
G01X1165897Y301500D01*
X1170022D01*
X1170076Y301387D01*
G03X1171812Y300676I1263J609D01*
G01X1171931Y300719D01*
X1177007Y295643D01*
G02X1177029Y295102I-283J-282D01*
G03X1179005Y293126I1070J-906D01*
G02X1179546Y293104I259J-305D01*
G01X1180105Y292545D01*
X1180091Y292446D01*
G03X1181678Y290859I1388J-199D01*
G01X1181777Y290873D01*
X1182552Y290098D01*
X1183462D01*
X1183501Y289948D01*
G03X1186217I1358J348D01*
G01X1186256Y290098D01*
X1187047D01*
G02X1187311Y289398I0J-400D01*
G03X1189167I928J-1051D01*
G02X1189431Y290098I264J300D01*
G01X1190222D01*
X1190261Y289948D01*
G03X1192977I1358J348D01*
G01X1193016Y290098D01*
X1193807D01*
G02X1194071Y289398I0J-400D01*
G03X1195927I928J-1051D01*
G02X1196191Y290098I264J300D01*
G01X1196882D01*
X1196919Y289945D01*
G03X1199839I1460J351D01*
G01X1199876Y290098D01*
X1200567D01*
G02X1200831Y289398I0J-400D01*
G03X1202687I928J-1051D01*
G02X1202951Y290098I264J300D01*
G01X1204042D01*
X1204081Y289948D01*
G03X1206797I1358J348D01*
G01X1206836Y290098D01*
X1318381D01*
X1318411Y289934D01*
G03X1321365I1477J271D01*
G01X1321395Y290098D01*
X1322181D01*
X1322211Y289934D01*
G03X1325165I1477J271D01*
G01X1325195Y290098D01*
X1345026D01*
X1368088Y267036D01*
G02X1368093Y266475I-283J-283D01*
G03X1368081Y266463I985J-997D01*
G02X1367481Y266484I-291J274D01*
G03X1366312Y267036I-1168J-960D01*
G01X1362803D01*
G03Y264014I1J-1511D01*
G01X1366312D01*
G03X1367463Y264546I0J1511D01*
G02X1368064Y264556I305J-259D01*
G03X1370075Y264493I1036J944D01*
G02X1370636Y264488I278J-288D01*
G01X1392724Y242400D01*
Y239754D01*
G02X1392235Y239364I-400J0D01*
G03X1391011Y236689I-335J-1464D01*
G02X1391025Y236054I-236J-323D01*
G03X1390976Y233905I875J-1095D01*
G02X1390962Y233291I-263J-301D01*
G03X1392235Y230654I938J-1173D01*
G02X1392724Y230264I89J-390D01*
G01Y167491D01*
X1391164Y165931D01*
X1391024Y166055D01*
G03X1389045Y164076I-924J-1055D01*
G01X1389169Y163936D01*
X1388116Y162883D01*
X1306361D01*
G02X1306110Y163595I-1J400D01*
G03X1304232I-939J1172D01*
G02X1303981Y162883I-250J-312D01*
G01X1277069D01*
G37*
G36*
G01X1158598Y318762D02*
G03X1157627Y318985I-779J-1166D01*
G01X1157529Y318971D01*
X1154953Y321547D01*
G02X1155059Y322188I283J282D01*
G03X1154255Y324836I-619J1258D01*
G02X1153802Y325232I-53J396D01*
G01Y329461D01*
G02X1154255Y329857I400J0D01*
G03Y332637I185J1390D01*
G02X1153802Y333033I-53J396D01*
G01Y333361D01*
G02X1154255Y333757I400J0D01*
G03X1153046Y335293I185J1390D01*
G02X1152365Y335051I-398J41D01*
G01X1152032Y335384D01*
G02X1152051Y335967I283J283D01*
G03X1149931Y338087I-991J1129D01*
G02X1149348Y338068I-300J264D01*
G01X1149303Y338113D01*
X1149215Y338202D01*
X1145214D01*
X1144452Y338964D01*
G02X1144638Y339635I283J283D01*
G03X1142939Y341334I-338J1361D01*
G02X1142268Y341148I-388J97D01*
G01X1142094Y341322D01*
Y342010D01*
G03Y343884I-1174J937D01*
G01Y346081D01*
G03Y347613I-1174J766D01*
G01Y349981D01*
G03Y351513I-1174J766D01*
G01Y352486D01*
X1142100Y352493D01*
Y353718D01*
G03X1142138Y355526I-1180J929D01*
G01X1142100Y355579D01*
Y355700D01*
X1141236Y356564D01*
G02X1141386Y357225I282J283D01*
G03X1139598Y359013I-466J1322D01*
G02X1138937Y358863I-378J132D01*
G01X1138416Y359384D01*
X1138552Y359525D01*
G03X1136470Y361402I-1012J971D01*
G01X1135843D01*
G02X1135469Y361945I0J400D01*
G03X1132851I-1309J502D01*
G02X1132477Y361402I-374J-143D01*
G01X1131850D01*
G03X1129382Y360396I-1070J-906D01*
G01X1129388Y360305D01*
X1128509Y359426D01*
X1128368Y359561D01*
G03X1126386Y357579I-968J-1014D01*
G02X1126383Y357300I-145J-138D01*
G01X1126001Y356918D01*
G02X1125342Y357067I-282J283D01*
G03X1124159Y355201I-1321J-471D01*
G02X1124598Y354803I39J-398D01*
G01Y354489D01*
G02X1124159Y354091I-400J0D01*
G03Y351301I-138J-1395D01*
G02X1124598Y350903I39J-398D01*
G01Y350589D01*
G02X1124159Y350191I-400J0D01*
G03Y347401I-138J-1395D01*
G02X1124598Y347003I39J-398D01*
G01Y346790D01*
G02X1124161Y346391I-400J-1D01*
G03Y343401I-140J-1495D01*
G02X1124598Y343002I37J-398D01*
G01Y342789D01*
G02X1124159Y342391I-400J0D01*
G03Y339601I-138J-1395D01*
G02X1124598Y339203I39J-398D01*
G01Y338889D01*
G02X1124159Y338491I-400J0D01*
G03X1124160Y335701I-138J-1395D01*
G02X1124600Y335303I40J-398D01*
G01Y335200D01*
X1125100Y334700D01*
Y328547D01*
X1126022Y327625D01*
X1126010Y327527D01*
G03X1127580Y325957I1390J-180D01*
G01X1127678Y325969D01*
X1128880Y324766D01*
Y321528D01*
X1128114Y320761D01*
X1127988Y320820D01*
G03X1126602Y320700I-588J-1273D01*
G01X1121279D01*
G02X1120889Y321188I0J400D01*
G03X1118153I-1368J308D01*
G02X1117763Y320700I-390J-88D01*
G01X1116205D01*
G03X1113473I-1366J-625D01*
G01X1094755D01*
X1094231Y321224D01*
Y322056D01*
G02X1094785Y322426I400J1D01*
G03X1096642Y322890I617J1478D01*
G02X1097242Y322913I310J-253D01*
G03X1099520Y322869I1161J1104D01*
G02X1100079I280J-286D01*
G03X1100082Y325161I1121J1145D01*
G02X1099523I-279J286D01*
G03X1097162Y325031I-1121J-1144D01*
G02X1096562Y325008I-310J253D01*
G03X1094785Y325382I-1160J-1104D01*
G02X1094231Y325752I-154J369D01*
G01Y332231D01*
X1097854Y335854D01*
G02X1098401Y335872I283J-283D01*
G03X1100441Y335927I990J1129D01*
G02X1101053Y335863I279J-286D01*
G03X1101250Y337774I1247J837D01*
G02X1100638Y337838I-279J286D01*
G03X1100520Y337991I-1246J-839D01*
G02X1100538Y338538I301J264D01*
G01X1101900Y339900D01*
X1102796Y340795D01*
X1103301Y341300D01*
X1103519Y341083D01*
X1103497Y340978D01*
G03X1104201Y341929I1374J-281D01*
G02X1103610Y342280I-191J351D01*
G01Y347196D01*
G02X1103801Y347395I200J-1D01*
G03Y350197I-60J1401D01*
G02X1103610Y350396I9J200D01*
G01Y351096D01*
G02X1103801Y351295I200J-1D01*
G03Y354097I-60J1401D01*
G02X1103610Y354296I9J200D01*
G01Y354996D01*
G02X1103801Y355195I200J-1D01*
G03Y357997I-60J1401D01*
G02X1103610Y358196I9J200D01*
G01Y358896D01*
G02X1103801Y359095I200J-1D01*
G03Y361897I-60J1401D01*
G02X1103610Y362096I9J200D01*
G01Y362796D01*
G02X1103801Y362995I200J-1D01*
G03Y365797I-60J1401D01*
G02X1103610Y365996I9J200D01*
G01Y366696D01*
G02X1103801Y366895I200J-1D01*
G03Y369697I-60J1401D01*
G02X1103610Y369896I9J200D01*
G01Y370597D01*
G02X1103801Y370796I200J-1D01*
G03Y373598I-60J1401D01*
G02X1103610Y373797I9J200D01*
G01Y374496D01*
G02X1103801Y374695I200J-1D01*
G03Y377497I-60J1401D01*
G02X1103610Y377696I9J200D01*
G01Y378396D01*
G02X1103801Y378595I200J-1D01*
G03Y381397I-60J1401D01*
G02X1103610Y381596I9J200D01*
G01Y382296D01*
G02X1103801Y382495I200J-1D01*
G03Y385297I-60J1401D01*
G02X1103610Y385496I9J200D01*
G01Y386196D01*
G02X1103801Y386395I200J-1D01*
G03Y389197I-60J1401D01*
G02X1103610Y389396I9J200D01*
G01Y390096D01*
G02X1103801Y390295I200J-1D01*
G03Y393097I-60J1401D01*
G02X1103610Y393296I9J200D01*
G01Y407304D01*
X1104928Y408622D01*
X1115715D01*
G02X1116058Y408016I0J-400D01*
G03X1118464I1203J-720D01*
G02X1118807Y408622I343J206D01*
G01X1184237D01*
G02X1184626Y408128I0J-400D01*
G03X1187352I1363J-328D01*
G02X1187741Y408622I389J94D01*
G01X1191149D01*
G03X1193251I1051J928D01*
G01X1195198D01*
G02X1195598Y408217I0J-400D01*
G03X1195686Y407693I1502J-17D01*
G02X1195364Y407162I-376J-135D01*
G03X1196307Y404590I191J-1389D01*
G02X1196838Y404496I214J-338D01*
G03X1198567Y406813I1191J915D01*
G02X1198371Y407400I143J374D01*
G03X1198602Y408217I-1271J800D01*
G02X1199002Y408622I400J5D01*
G01X1203446D01*
X1215414Y420590D01*
X1215415D01*
X1215500Y420674D01*
X1311925D01*
X1313198Y421948D01*
X1314850Y423600D01*
X1335695D01*
X1335745Y423548D01*
X1335752D01*
X1337592Y421708D01*
Y359108D01*
X1329982Y351499D01*
X1329915Y351490D01*
G03X1328710Y350285I185J-1390D01*
G01X1328701Y350218D01*
X1327181Y348698D01*
X1327039Y348830D01*
G03X1324916Y346707I-1025J-1098D01*
G02X1324912Y346429I-146J-137D01*
G01X1317885Y339402D01*
X1219885D01*
X1214129Y333646D01*
G02X1213481Y333766I-283J283D01*
G03X1211630Y331915I-1281J-570D01*
G02X1211750Y331267I-163J-365D01*
G01X1203834Y323351D01*
G02X1203153Y323592I-283J283D01*
G03X1201613Y322052I-1394J-146D01*
G02X1201854Y321371I-42J-398D01*
G01X1199245Y318762D01*
X1196759D01*
G02X1196369Y319247I1J400D01*
G03X1193629I-1370J300D01*
G02X1193239Y318762I-391J-85D01*
G01X1192566D01*
G03X1190672I-947J-1166D01*
G01X1189999D01*
G02X1189609Y319247I1J400D01*
G03X1186869I-1370J300D01*
G02X1186479Y318762I-391J-85D01*
G01X1185806D01*
G03X1183912I-947J-1166D01*
G01X1183239D01*
G02X1182849Y319247I1J400D01*
G03X1180109I-1370J300D01*
G02X1179719Y318762I-391J-85D01*
G01X1178877D01*
G03X1177321I-778J-1166D01*
G01X1176582D01*
G02X1176190Y319243I0J400D01*
G03X1173248I-1471J304D01*
G02X1172856Y318762I-392J-81D01*
G01X1172117D01*
G03X1170561I-778J-1166D01*
G01X1169720D01*
G02X1169330Y319247I1J400D01*
G03X1166590I-1370J300D01*
G02X1166200Y318762I-391J-85D01*
G01X1165358D01*
G03X1163802I-778J-1166D01*
G01X1162960D01*
G02X1162570Y319247I1J400D01*
G03X1159830I-1370J300D01*
G02X1159440Y318762I-391J-85D01*
G01X1158598D01*
G37*
G36*
G01X1183060Y291100D02*
X1182669Y291491D01*
X1182733Y291620D01*
G03X1180852Y293501I-1254J627D01*
G01X1180723Y293437D01*
X1179369Y294791D01*
X1179354Y294820D01*
G03X1178723Y295451I-1255J-624D01*
G01X1178694Y295466D01*
X1178123Y296037D01*
G02X1178337Y296714I282J283D01*
G03X1176717Y298334I-238J1382D01*
G02X1176040Y298120I-394J68D01*
G01X1175759Y298401D01*
Y298441D01*
X1175710Y298490D01*
G02Y299055I283J283D01*
G03X1173727Y301038I-991J992D01*
G02X1173162I-283J283D01*
G01X1172667Y301533D01*
X1172696Y301644D01*
G03X1170360Y303000I-1357J352D01*
G01X1165813D01*
X1164913Y303900D01*
X1162712D01*
X1162696Y304082D01*
G03X1160086Y302940I-1496J-135D01*
G02X1160072Y302388I-297J-269D01*
G01X1158485Y300802D01*
X1157585D01*
X1157584Y300800D01*
X1156900D01*
X1155002Y298902D01*
X1153515D01*
X1152602Y299815D01*
Y312701D01*
X1154168Y314268D01*
X1154265Y314256D01*
G03X1155831Y315822I175J1391D01*
G01X1155819Y315919D01*
X1156390Y316490D01*
G02X1156927Y316515I282J-283D01*
G03X1159211Y317424I893J1081D01*
G01X1159233Y317600D01*
X1163167D01*
X1163189Y317424D01*
G03X1165971I1391J172D01*
G01X1165993Y317600D01*
X1169926D01*
X1169948Y317424D01*
G03X1172730I1391J172D01*
G01X1172752Y317600D01*
X1176686D01*
X1176708Y317424D01*
G03X1179490I1391J172D01*
G01X1179512Y317600D01*
X1183346D01*
X1183367Y317423D01*
G03X1186351I1492J173D01*
G01X1186372Y317600D01*
X1190106D01*
X1190127Y317423D01*
G03X1193111I1492J173D01*
G01X1193132Y317600D01*
X1199500D01*
X1220300Y338400D01*
X1318104D01*
G02X1318504Y338006I0J-400D01*
G03X1319855Y339426I1402J19D01*
G01X1319768Y339423D01*
X1319565Y339626D01*
X1319892Y339953D01*
G02X1319975Y340075I367J-160D01*
G01X1326133Y346233D01*
X1326201Y346242D01*
G03X1327504Y347545I-187J1490D01*
G01X1327513Y347613D01*
X1329051Y349151D01*
X1329192Y349032D01*
G03X1330931Y348971I908J1068D01*
G02X1331469Y348912I237J-322D01*
G03X1331515Y350938I1131J988D01*
G02X1331211Y350955I-145J138D01*
G03X1331168Y351008I-1110J-856D01*
G01X1331049Y351149D01*
X1335519Y355619D01*
X1338594Y358693D01*
Y358694D01*
X1338600Y358700D01*
Y421550D01*
X1352916Y435866D01*
Y435903D01*
X1353532Y436519D01*
G02X1354100Y436517I283J-283D01*
G03X1356083Y438500I1000J983D01*
G02X1356081Y439068I281J285D01*
G01X1356300Y439287D01*
X1356337D01*
X1362600Y445550D01*
X1379050D01*
X1379100Y445600D01*
X1380000D01*
X1380583Y446183D01*
X1380621Y446199D01*
G03X1381401Y446979I-521J1301D01*
G01X1381417Y447017D01*
X1384000Y449600D01*
X1395700D01*
X1398200Y447100D01*
Y425100D01*
X1395653Y422553D01*
X1395616Y422538D01*
G03X1394848Y421770I530J-1298D01*
G01X1394833Y421733D01*
X1384910Y411810D01*
X1384874Y411795D01*
G03X1384406Y411474I543J-1293D01*
G02X1383836Y411467I-288J277D01*
G03X1381919Y411520I-987J-996D01*
G02X1381386Y411522I-265J299D01*
G03X1379457Y411470I-937J-1043D01*
G02X1378898Y411464I-283J283D01*
G03X1376930Y411436I-970J-1013D01*
G02X1376333Y411467I-285J281D01*
G03X1374160Y411486I-1094J-877D01*
G02X1373560Y411468I-308J255D01*
G03X1371513Y411472I-1025J-956D01*
G02X1370930I-291J274D01*
G03X1368761Y411321I-1023J-959D01*
G02X1368112Y411313I-327J230D01*
G03X1365986Y411465I-1128J-832D01*
G02X1365413Y411469I-285J281D01*
G03X1363306Y411369I-1010J-973D01*
G02X1362674Y411375I-314J248D01*
G03X1360748Y411671I-1116J-848D01*
G02X1360178Y411785I-231J326D01*
G03X1357973Y410075I-1188J-745D01*
G02X1357955Y409507I-290J-275D01*
G03X1357899Y407509I955J-1027D01*
G02X1357915Y406971I-288J-278D01*
G03X1357658Y405593I1065J-912D01*
G02X1357414Y405082I-377J-134D01*
G03X1356863Y404725I466J-1322D01*
G02X1356220Y404812I-290J275D01*
G03X1353953Y405106I-1238J-658D01*
G02X1353366I-294J272D01*
G03X1351314Y403195I-1028J-953D01*
G02X1351292Y402627I-292J-273D01*
G03X1350962Y401015I947J-1034D01*
G02X1350771Y400490I-365J-165D01*
G03X1352322Y398189I608J-1263D01*
G02X1352909Y398135I269J-296D01*
G03X1354981Y397961I1115J850D01*
G02X1355544Y397944I273J-293D01*
G03X1357618Y397990I1016J966D01*
G02X1358239Y397968I302J-263D01*
G03X1360584Y398126I1121J842D01*
G02X1361225Y398203I349J-196D01*
G03X1363491Y399813I1025J956D01*
G02X1363713Y400377I354J186D01*
G03X1362284Y402716I-463J1323D01*
G02X1361662Y402805I-276J290D01*
G03X1359852Y403368I-1212J-705D01*
G02X1359282Y403737I-170J362D01*
G03X1359202Y404227I-1402J23D01*
G02X1359446Y404738I377J134D01*
G03X1359991Y407031I-466J1322D01*
G02X1359975Y407569I288J278D01*
G03X1359787Y409574I-1065J911D01*
G02X1359797Y409893I125J156D01*
G03X1359800Y409896I-990J993D01*
G02X1360370Y409782I231J-326D01*
G03X1362655Y409654I1188J745D01*
G02X1363287Y409648I314J-248D01*
G03X1365401Y409512I1116J848D01*
G02X1365974Y409508I285J-281D01*
G03X1368130Y409673I1010J973D01*
G02X1368779Y409681I327J-230D01*
G03X1370929Y409553I1128J832D01*
G02X1371512I291J-274D01*
G03X1373614Y409616I1023J959D01*
G02X1374214Y409634I308J-255D01*
G03X1376237Y409605I1025J956D01*
G02X1376834Y409574I285J-281D01*
G03X1378920Y409460I1094J877D01*
G02X1379479Y409466I283J-283D01*
G03X1381379Y409430I970J1013D01*
G02X1381912Y409428I265J-299D01*
G03X1382456Y409125I937J1043D01*
G01X1382600Y409083D01*
Y407240D01*
X1382638Y407202D01*
Y403078D01*
G02X1382130Y402693I-400J0D01*
G03X1380779Y402353I-379J-1350D01*
G02X1380225I-277J288D01*
G03X1378573Y402570I-973J-1010D01*
G02X1378029Y402727I-194J350D01*
G03X1375827Y403063I-1229J-674D01*
G02X1375273I-277J288D01*
G03X1373105Y402786I-973J-1010D01*
G02X1372417Y402796I-341J209D01*
G03X1372395Y401367I-1217J-696D01*
G02X1373083Y401357I341J-209D01*
G03X1375273Y401043I1217J696D01*
G02X1375827I277J-288D01*
G03X1377479Y400826I973J1010D01*
G02X1378023Y400669I194J-350D01*
G03X1380225Y400333I1229J674D01*
G02X1380779I277J-288D01*
G03X1380866Y400256I972J1011D01*
G02X1380872Y399951I-126J-155D01*
G03X1380768Y397951I928J-1051D01*
G02X1380701Y397352I-295J-270D01*
G03X1382074Y394921I799J-1152D01*
G02X1382638Y394556I164J-365D01*
G01Y393362D01*
G03X1382555Y393272I1062J-1062D01*
G02X1381945I-305J259D01*
G03Y391328I-1145J-972D01*
G02X1382555I305J-259D01*
G03X1382638Y391238I1145J972D01*
G01Y389859D01*
X1382600Y389821D01*
Y384412D01*
G02X1381911Y384135I-400J0D01*
G03Y382193I-1011J-971D01*
G02X1382600Y381916I289J-277D01*
G01Y379316D01*
G02X1381905Y379046I-400J0D01*
G03Y377150I-1033J-948D01*
G02X1382600Y376880I295J-270D01*
G01Y369377D01*
G02X1382159Y368979I-400J0D01*
G03Y366189I-142J-1395D01*
G02X1382600Y365791I41J-398D01*
G01Y337500D01*
X1369600Y324500D01*
Y322470D01*
G03Y322330I1400J-70D01*
G01Y319385D01*
X1369599Y319373D01*
G03Y319017I1491J-178D01*
G01X1369600Y319005D01*
Y315585D01*
X1369599Y315573D01*
G03X1369593Y315515I1491J-184D01*
G02X1369338Y315339I-200J16D01*
G03X1369144Y312605I-391J-1346D01*
G02X1369600Y312209I56J-396D01*
G01Y311721D01*
G02X1369417Y311522I-200J0D01*
G03X1368624Y309064I123J-1397D01*
G02X1368568Y308418I-262J-303D01*
G03Y305842I772J-1288D01*
G02X1368624Y305196I-206J-343D01*
G03X1368577Y303116I916J-1061D01*
G02X1368516Y302488I-275J-290D01*
G03X1369225Y299720I804J-1269D01*
G02X1369600Y299321I-25J-399D01*
G01Y294470D01*
X1366230Y291100D01*
X1339032D01*
G02X1338647Y291608I0J400D01*
G03X1336108Y293043I-1447J404D01*
G02X1335519Y293051I-291J275D01*
G03X1332962Y291616I-1119J-1002D01*
G02X1332579Y291100I-383J-116D01*
G01X1324894D01*
G03X1322482I-1206J-895D01*
G01X1321094D01*
G03X1318682I-1206J-895D01*
G01X1305458D01*
G02X1305104Y291688I-1J400D01*
G03X1305267Y292399I-1238J658D01*
G02X1305644Y292813I400J15D01*
G03X1304063Y294173I-85J1500D01*
G02X1303709Y293738I-398J-37D01*
G03X1302628Y291688I157J-1393D01*
G02X1302274Y291100I-353J-188D01*
G01X1206588D01*
G03X1204290I-1149J-804D01*
G01X1203399D01*
G02X1203035Y291665I0J400D01*
G03X1200483I-1276J582D01*
G02X1200119Y291100I-364J-165D01*
G01X1199648D01*
G03X1197110I-1269J-804D01*
G01X1196639D01*
G02X1196275Y291665I0J400D01*
G03X1193723I-1276J582D01*
G02X1193359Y291100I-364J-165D01*
G01X1192768D01*
G03X1190470I-1149J-804D01*
G01X1189879D01*
G02X1189515Y291665I0J400D01*
G03X1186963I-1276J582D01*
G02X1186599Y291100I-364J-165D01*
G01X1186008D01*
G03X1183710I-1149J-804D01*
G01X1183060D01*
G37*
G36*
G01X1530774Y308261D02*
X1528937Y310098D01*
G02X1529004Y310718I283J283D01*
G03X1527578Y313130I-754J1182D01*
G02X1526986Y313481I-192J351D01*
G01Y324223D01*
X1531769Y329006D01*
X1537441D01*
G03X1539371I965J1151D01*
G01X1558526D01*
X1558563Y328852D01*
G03X1561485I1461J348D01*
G01X1561522Y329006D01*
X1578825D01*
X1578879Y328891D01*
G03X1581421I1271J592D01*
G01X1581475Y329006D01*
X1589409D01*
X1595496Y322919D01*
Y311056D01*
X1592701Y308261D01*
X1589211D01*
X1589183Y308428D01*
G03X1586417I-1383J-228D01*
G01X1586389Y308261D01*
X1578845D01*
G03X1576127I-1359J-640D01*
G01X1571524D01*
X1571489Y308417D01*
G03X1568363I-1563J-353D01*
G01X1568328Y308261D01*
X1565909D01*
X1565900Y308452D01*
G03X1565412Y309493I-1500J-68D01*
G02X1565403Y310076I269J296D01*
G03X1563431Y310096I-976J1007D01*
G02X1563411Y309513I-284J-282D01*
G03X1562900Y308452I989J-1130D01*
G01X1562891Y308261D01*
X1561792D01*
X1561736Y308370D01*
G03X1561300Y308885I-1335J-688D01*
G02X1561216Y309439I240J320D01*
G03X1559097Y309115I-1219J878D01*
G02X1559181Y308561I-240J-320D01*
G03X1559064Y308370I1219J-878D01*
G01X1559008Y308261D01*
X1536358D01*
G02X1536037Y308900I0J400D01*
G03X1533629I-1204J898D01*
G02X1533308Y308261I-321J-239D01*
G01X1530774D01*
G37*
G36*
G01X1624167Y119500D02*
G03X1622655Y119827I-977J-860D01*
G01X1622529Y119771D01*
X1620100Y122200D01*
Y126778D01*
X1620265Y126807D01*
G03Y129371I-225J1282D01*
G01X1620100Y129400D01*
Y133077D01*
X1620265Y133106D01*
G03Y135670I-225J1282D01*
G01X1620100Y135699D01*
Y139376D01*
X1620265Y139405D01*
G03Y141969I-225J1282D01*
G01X1620100Y141998D01*
Y145676D01*
X1620265Y145705D01*
G03Y148269I-225J1282D01*
G01X1620100Y148298D01*
Y148886D01*
X1620273Y148910D01*
G03Y151490I-173J1290D01*
G01X1620100Y151514D01*
Y151986D01*
X1620273Y152010D01*
G03Y154590I-173J1290D01*
G01X1620100Y154614D01*
Y158274D01*
X1620265Y158303D01*
G03Y160867I-225J1282D01*
G01X1620100Y160896D01*
Y161424D01*
X1620265Y161453D01*
G03Y164017I-225J1282D01*
G01X1620100Y164046D01*
Y164574D01*
X1620266Y164603D01*
G03Y167167I-225J1282D01*
G01X1620100Y167196D01*
Y167647D01*
X1620261Y167679D01*
G03Y170233I-255J1277D01*
G01X1620100Y170265D01*
Y173700D01*
X1620606Y174206D01*
X1620850Y173961D01*
X1620784Y173832D01*
G03X1621347Y174395I1158J-595D01*
G01X1621218Y174329D01*
X1620973Y174573D01*
X1621600Y175200D01*
X1667080D01*
X1673897Y182017D01*
X1674036Y181905D01*
G03X1676007Y183876I876J1095D01*
G01X1675895Y184015D01*
X1679160Y187280D01*
X1686086D01*
G02X1686458Y186734I0J-400D01*
G03X1689442I1492J-584D01*
G02X1689814Y187280I372J146D01*
G01X1690820D01*
X1694134Y183966D01*
Y164751D01*
G03Y164601I1600J-75D01*
G01Y164434D01*
X1691651Y161951D01*
G02X1691035Y162012I-283J283D01*
G03X1688953Y159930I-1250J-832D01*
G02X1689014Y159314I-222J-333D01*
G01X1675650Y145950D01*
X1665743D01*
G02X1665377Y146512I0J400D01*
G03X1662995I-1191J526D01*
G02X1662629Y145950I-366J-162D01*
G01X1662563D01*
G02X1662192Y146500I0J400D01*
G03X1659778I-1207J487D01*
G02X1659407Y145950I-371J-150D01*
G01X1659082D01*
G02X1658916Y146261I0J200D01*
G03X1656628Y146500I-1081J726D01*
G02X1656257Y145950I-371J-150D01*
G01X1655932D01*
G02X1655766Y146261I0J200D01*
G03X1653478Y146500I-1081J726D01*
G02X1653107Y145950I-371J-150D01*
G01X1652782D01*
G02X1652617Y146262I1J200D01*
G03X1650329Y146500I-1081J726D01*
G02X1649958Y145950I-371J-150D01*
G01X1649050D01*
X1648500Y145400D01*
Y120644D01*
X1647356Y119500D01*
X1646215D01*
G03X1644259I-978J-860D01*
G01X1643145D01*
G03X1641155I-995J-840D01*
G01X1639916D01*
G03X1637960I-978J-859D01*
G01X1636766D01*
G03X1634810I-978J-860D01*
G01X1633617D01*
G03X1631661I-978J-860D01*
G01X1630467D01*
G03X1628511I-978J-860D01*
G01X1627326D01*
G03X1625352I-987J-849D01*
G01X1624167D01*
G37*
G36*
G01X1654443Y94300D02*
X1651808Y96935D01*
Y100797D01*
G02X1652420Y101136I400J0D01*
G03Y103344I691J1104D01*
G02X1651808Y103683I-212J339D01*
G01Y107910D01*
X1651945Y107955D01*
G03Y110427I-409J1236D01*
G01X1651808Y110472D01*
Y111060D01*
X1651945Y111105D01*
G03Y113577I-409J1236D01*
G01X1651808Y113622D01*
Y114210D01*
X1651945Y114255D01*
G03Y116727I-409J1236D01*
G01X1651808Y116772D01*
Y118192D01*
X1649600Y120400D01*
Y144500D01*
X1650048Y144948D01*
X1653139D01*
G02X1653502Y144381I0J-400D01*
G03X1655868I1183J-544D01*
G02X1656231Y144948I363J167D01*
G01X1656289D01*
G02X1656652Y144381I0J-400D01*
G03X1659018I1183J-544D01*
G02X1659381Y144948I363J167D01*
G01X1659439D01*
G02X1659802Y144381I0J-400D01*
G03X1662168I1183J-544D01*
G02X1662531Y144948I363J167D01*
G01X1676065D01*
X1694624Y163508D01*
X1694763Y163402D01*
G03X1696959Y165708I971J1274D01*
G01X1696841Y165848D01*
X1702269Y171276D01*
X1711891D01*
X1717950Y177336D01*
X1723609D01*
X1723673Y177400D01*
X1725248D01*
G02X1725637Y176905I0J-400D01*
G03X1727694Y175003I1556J-380D01*
G01X1727725Y175014D01*
X1731661D01*
X1731692Y175003D01*
G03X1733749Y176905I501J1522D01*
G02X1734138Y177400I389J95D01*
G01X1737847D01*
G02X1738236Y176905I0J-400D01*
G03X1740293Y175003I1556J-380D01*
G01X1740324Y175014D01*
X1744260D01*
X1744291Y175003D01*
G03X1746348Y176905I501J1522D01*
G02X1746737Y177400I389J95D01*
G01X1750445D01*
G02X1750834Y176905I0J-400D01*
G03X1752891Y175003I1556J-380D01*
G01X1752922Y175014D01*
X1756858D01*
X1756889Y175003D01*
G03X1758946Y176905I501J1522D01*
G02X1759335Y177400I389J95D01*
G01X1763043D01*
G02X1763432Y176905I0J-400D01*
G03X1765489Y175003I1556J-380D01*
G01X1765520Y175014D01*
X1769456D01*
X1769487Y175003D01*
G03X1770982Y175268I501J1522D01*
G01X1771121Y175379D01*
X1778526Y167974D01*
G02X1778374Y167313I-283J-283D01*
G03X1780413Y165274I526J-1513D01*
G02X1781074Y165426I378J-131D01*
G01X1790400Y156100D01*
Y155999D01*
G02X1790020Y155600I-400J0D01*
G03X1789521Y155494I79J-1600D01*
G02X1789002Y155728I-144J373D01*
G03X1788079Y153676I-1502J-558D01*
G02X1788598Y153442I144J-373D01*
G03X1790020Y152400I1502J558D01*
G02X1790400Y152001I-20J-399D01*
G01Y112950D01*
X1788150Y110700D01*
X1771911D01*
G03X1769789I-1061J-1200D01*
G01X1768820D01*
X1762960Y104840D01*
Y96360D01*
X1760900Y94300D01*
X1748022D01*
G02X1747682Y94911I0J400D01*
G03X1745300I-1191J739D01*
G02X1744960Y94300I-340J-211D01*
G01X1702302D01*
G02X1701902Y94701I0J400D01*
G03X1699147Y95815I-1602J2D01*
G02X1698869Y95805I-144J139D01*
G03X1696735Y95809I-1069J-1193D01*
G02X1696457Y95820I-133J149D01*
G03X1694059Y95725I-1157J-1108D01*
G02X1693456Y95705I-310J253D01*
G03X1690685Y94682I-1171J-1093D01*
G02X1690285Y94300I-400J18D01*
G01X1660792D01*
G02X1660403Y94791I0J400D01*
G03X1657673I-1365J320D01*
G02X1657284Y94300I-389J-91D01*
G01X1654443D01*
G37*
G36*
G01X1678652Y205624D02*
G02X1678252Y206029I0J400D01*
G03X1675357Y206612I-1502J21D01*
G01X1675307Y206487D01*
X1672513D01*
X1672349Y206651D01*
G02X1672393Y207254I283J282D01*
G03X1672950Y208225I-837J1125D01*
G02X1673388Y208579I397J-44D01*
G03X1672136Y210128I142J1395D01*
G02X1671698Y209774I-397J44D01*
G03X1670431Y209216I-142J-1395D01*
G02X1669828Y209172I-321J239D01*
G01X1667900Y211100D01*
G02X1668009Y211743I283J283D01*
G03X1666092Y212285I-653J1353D01*
G02X1665755Y211670I-337J-215D01*
G01X1665334D01*
G02X1664981Y212257I0J400D01*
G03X1662151I-1415J752D01*
G02X1661798Y211670I-353J-187D01*
G01X1660361D01*
X1660072Y211959D01*
X1660238Y212126D01*
X1660271Y212141D01*
G03X1658386Y214327I-628J1364D01*
G02X1657768Y214263I-335J219D01*
G01X1657740Y214290D01*
X1652276D01*
X1650507Y212522D01*
X1649763D01*
G02X1649461Y213183I0J400D01*
G03X1647385Y215067I-1061J917D01*
G02X1646802Y215071I-290J276D01*
G03X1644761Y212878I-1102J-1021D01*
G01X1644836Y212818D01*
Y212522D01*
X1644338D01*
X1637028Y219832D01*
Y227908D01*
X1637026Y227910D01*
Y227980D01*
X1635360Y229646D01*
Y269516D01*
G02X1636016Y269823I400J0D01*
G03Y271977I898J1077D01*
G02X1635360Y272284I-256J307D01*
G01Y273268D01*
G02X1635965Y273611I400J0D01*
G03X1637746Y275730I719J1204D01*
G02X1637762Y276269I303J261D01*
G03X1637816Y278302I-1078J1046D01*
G02Y278828I302J263D01*
G03X1637413Y281128I-1132J987D01*
G02Y281828I194J350D01*
G03X1635954Y284454I-730J1313D01*
G02X1635360Y284803I-194J350D01*
G01Y286364D01*
G02X1635979Y286698I400J-1D01*
G03X1636658Y289451I821J1258D01*
G02X1636220Y289849I-38J398D01*
G01Y290555D01*
G02X1636663Y290952I400J-1D01*
G03X1637954Y293433I159J1494D01*
G02Y293959I302J263D01*
G03X1637994Y295886I-1132J987D01*
G02X1638015Y296411I312J250D01*
G03X1636685Y298927I-1090J1033D01*
G02X1636220Y299321I-65J395D01*
G01Y300710D01*
G02X1636684Y301105I400J0D01*
G03X1638028Y303604I238J1483D01*
G02X1638016Y304130I295J270D01*
G03X1636671Y306581I-1155J961D01*
G02X1636220Y306978I-51J397D01*
G01Y315301D01*
X1633604Y317918D01*
Y322889D01*
G02X1634288Y323171I400J0D01*
G03Y325285I1067J1057D01*
G02X1633604Y325567I-284J282D01*
G01Y338975D01*
G02X1634319Y339222I400J0D01*
G03Y341070I1184J924D01*
G02X1633604Y341317I-315J247D01*
G01Y342124D01*
G03Y344168I-1101J1022D01*
G01Y344875D01*
G02X1634319Y345122I400J0D01*
G03Y346970I1184J924D01*
G02X1633604Y347217I-315J247D01*
G01Y411142D01*
G02X1634092Y411532I400J0D01*
G03X1635475Y413800I308J1368D01*
G01X1635358Y413940D01*
X1646775Y425357D01*
X1646777D01*
Y425359D01*
X1648895Y427477D01*
Y465020D01*
X1669831Y485956D01*
G02X1670107Y485963I142J-141D01*
G03X1672087Y487943I943J1037D01*
G01X1671959Y488084D01*
X1678598Y494723D01*
X1715535D01*
X1721972Y501160D01*
X1723994D01*
X1723998Y500964D01*
G03X1723999Y500933I1602J36D01*
G02X1723776Y500726I-200J-8D01*
G03X1723570Y497533I-185J-1591D01*
G02X1723965Y497144I-5J-400D01*
G03X1726418Y495829I1601J42D01*
G02X1726932Y495754I213J-338D01*
G03X1729310Y497901I1207J1053D01*
G02X1729602Y498574I292J273D01*
G01X1733639D01*
G03X1735141Y499916I0J1511D01*
G01X1735150Y500000D01*
Y500095D01*
G03X1735053Y500619I-1511J-9D01*
G02X1735427Y501160I374J141D01*
G01X1735799D01*
Y500953D01*
G03X1738802Y500883I1501J-53D01*
G02X1739200Y501248I398J-35D01*
G01X1791362D01*
X1793150Y499460D01*
Y484168D01*
X1792460Y483478D01*
X1790283Y481300D01*
X1789784Y480801D01*
X1789721Y480790D01*
G03X1788485Y479554I254J-1490D01*
G01X1788474Y479491D01*
X1787993Y479010D01*
X1787992D01*
X1787612Y478630D01*
X1680808D01*
X1669763Y467585D01*
G02X1669100Y467742I-283J283D01*
G03X1666631Y468352I-1426J-471D01*
G02X1666078Y468349I-278J288D01*
G03X1666090Y466176I-1031J-1092D01*
G02X1666643Y466179I278J-288D01*
G03X1667135Y465869I1032J1092D01*
G02X1667381Y465404I-143J-373D01*
G03X1667351Y465234I1462J-346D01*
G01X1667343Y465165D01*
X1659535Y457357D01*
Y422514D01*
X1659532Y422510D01*
Y419560D01*
X1656646Y416674D01*
Y416544D01*
X1656590Y416488D01*
Y402953D01*
G02X1655899Y402678I-400J0D01*
G03X1653715Y400616I-1090J-1033D01*
G02X1653722Y400076I-292J-274D01*
G03X1653800Y398133I1048J-931D01*
G02X1653820Y397576I-277J-289D01*
G03X1655895Y395690I1041J-939D01*
G02X1656590Y395420I295J-270D01*
G01Y305472D01*
G03Y303528I1010J-972D01*
G01Y294015D01*
G03Y291617I904J-1199D01*
G01Y288866D01*
G03Y286734I910J-1066D01*
G01Y286096D01*
G03Y283704I908J-1196D01*
G01Y281096D01*
G03X1656520Y278760I908J-1196D01*
G01X1656590Y278700D01*
Y278371D01*
X1656528Y278312D01*
G03Y276288I970J-1012D01*
G01X1656590Y276229D01*
Y275900D01*
X1656520Y275840D01*
G03X1656590Y273504I978J-1140D01*
G01Y270896D01*
G03X1656520Y268560I908J-1196D01*
G01X1656590Y268500D01*
Y268171D01*
X1656528Y268112D01*
G03Y266088I970J-1012D01*
G01X1656590Y266029D01*
Y265744D01*
X1656528Y265685D01*
G03X1656590Y263460I1039J-1084D01*
G01Y260895D01*
G03Y258505I910J-1195D01*
G01Y257583D01*
X1656584Y257561D01*
G03Y256919I1365J-321D01*
G01X1656590Y256897D01*
Y235919D01*
X1656646Y235863D01*
Y235854D01*
X1667957Y224543D01*
X1693565D01*
X1695579Y222528D01*
X1703422D01*
X1703423Y222530D01*
X1703426D01*
X1704312Y223416D01*
X1708507Y227610D01*
X1711576Y230680D01*
X1725622D01*
X1725662Y230720D01*
X1725742D01*
X1731865Y236843D01*
G02X1732516Y236716I283J-283D01*
G03X1734887Y236168I1384J584D01*
G02X1735413I263J-302D01*
G03Y238432I987J1132D01*
G02X1734887I-263J302D01*
G03X1734484Y238684I-988J-1131D01*
G02X1734357Y239335I156J368D01*
G01X1735707Y240685D01*
X1735734D01*
X1737823Y242774D01*
X1744855D01*
X1748764Y238865D01*
Y235282D01*
X1746496Y233014D01*
G02X1745856Y233118I-282J283D01*
G03X1744330Y233864I-1253J-629D01*
G02X1743862Y234346I-78J392D01*
G03X1740934Y235015I-1464J335D01*
G02X1740397Y234732I-390J89D01*
G03X1738662Y234257I-550J-1398D01*
G02X1738032I-315J246D01*
G03X1735516Y234030I-1185J-923D01*
G02X1734892Y233920I-354J185D01*
G03X1735211Y232114I-1012J-1110D01*
G02X1735835Y232224I354J-185D01*
G03X1738032Y232411I1012J1110D01*
G02X1738662I315J-246D01*
G03X1741311Y233000I1185J923D01*
G02X1741848Y233283I390J-89D01*
G03X1742742Y233219I549J1398D01*
G02X1743226Y232754I91J-389D01*
G03X1743930Y231259I1377J-265D01*
G02X1744021Y230625I-192J-351D01*
G01X1730279Y216882D01*
X1721367D01*
X1721343Y216859D01*
X1710108Y205624D01*
X1678652D01*
G37*
G36*
G01X1843147Y18700D02*
X1842073Y19774D01*
G02X1842132Y20388I283J283D01*
G03X1841341Y23132I-843J1243D01*
G02X1840955Y23532I14J400D01*
G01Y33841D01*
G02X1841144Y34040I200J-1D01*
G03Y37040I-84J1500D01*
G02X1840955Y37239I11J200D01*
G01Y50422D01*
X1846258Y55725D01*
G02X1846865Y55677I283J-283D01*
G03X1848973Y55490I1135J823D01*
G02X1849527I277J-288D01*
G03Y57510I973J1010D01*
G02X1848973I-277J288D01*
G03X1848823Y57635I-970J-1012D01*
G02X1848775Y58242I235J324D01*
G01X1856488Y65955D01*
Y68900D01*
X1857588Y70000D01*
X1858800D01*
X1860600Y71800D01*
Y72060D01*
X1860663Y72119D01*
G03X1856866Y76751I-2062J2182D01*
G01X1856729Y76653D01*
X1856482Y76900D01*
Y80000D01*
X1859923Y83441D01*
X1860063Y83331D01*
G03X1862259Y83697I932J1178D01*
G02X1862931I336J-216D01*
G03X1865003Y85775I1264J812D01*
G02X1865006Y86451I215J337D01*
G03X1865387Y88655I-798J1273D01*
G01X1865276Y88794D01*
X1870210Y93728D01*
X1876319D01*
X1876832Y94240D01*
X1877239D01*
X1881510Y98512D01*
X1881651Y98395D01*
G03X1883951Y99405I900J1075D01*
G02X1884508Y99754I399J-18D01*
G03X1886556Y100758I594J1380D01*
G02X1887140Y101006I387J-100D01*
G03X1888403Y103506I690J1221D01*
G02X1888342Y104202I164J365D01*
G03X1888952Y105815I-845J1241D01*
G01X1888924Y105926D01*
X1889333Y106335D01*
X1889557Y106111D01*
X1889526Y105999D01*
G03X1891045Y107100I1448J-399D01*
G02X1890781Y107783I19J400D01*
G01X1896499Y113500D01*
X1896637Y113397D01*
G03X1898739Y115499I899J1203D01*
G01X1898636Y115637D01*
X1910662Y127664D01*
X1910793Y127596D01*
G03X1912684Y129487I647J1244D01*
G01X1912616Y129618D01*
X1917100Y134102D01*
G02X1917764Y133940I283J-283D01*
G03X1918276Y133208I1431J456D01*
G02X1918343Y132641I-245J-316D01*
G03X1918781Y130390I1171J-940D01*
G02X1918820Y129717I-195J-349D01*
G03X1918599Y127482I882J-1216D01*
G02Y126939I-294J-272D01*
G03X1920805I1103J-1019D01*
G02Y127482I294J272D01*
G03X1920435Y129812I-1103J1019D01*
G02X1920396Y130485I195J349D01*
G03X1920433Y132889I-882J1216D01*
G02X1920366Y133456I245J316D01*
G03X1919651Y135827I-1171J940D01*
G02X1919489Y136491I121J381D01*
G01X1923218Y140220D01*
G02X1923872Y140086I283J-283D01*
G03X1925957Y142171I1486J599D01*
G02X1925823Y142825I149J371D01*
G01X1933710Y150711D01*
Y151118D01*
X1934161Y151570D01*
Y174828D01*
G02X1934792Y175155I400J0D01*
G03Y177445I808J1145D01*
G02X1934161Y177772I-231J327D01*
G01Y186238D01*
X1934171Y186268D01*
G03Y187132I-1334J432D01*
G01X1934161Y187162D01*
Y191989D01*
X1934328Y192017D01*
G03Y194783I-228J1383D01*
G01X1934161Y194811D01*
Y197107D01*
G02X1934779Y197442I400J0D01*
G03Y199958I821J1258D01*
G02X1934161Y200293I-218J335D01*
G01Y215322D01*
X1934303Y215365D01*
G03Y218049I-405J1342D01*
G01X1934161Y218092D01*
Y218927D01*
X1922450Y230638D01*
X1904792D01*
G02X1904395Y231092I-1J400D01*
G03X1901419I-1488J202D01*
G02X1901022Y230638I-396J-54D01*
G01X1887138D01*
X1884908Y232868D01*
G02X1885077Y233535I282J283D01*
G03X1883426Y235844I-426J1440D01*
G02X1882911Y235723I-326J232D01*
G03X1881999Y235888I-710J-1323D01*
G01X1881901Y235875D01*
X1873398Y244378D01*
Y263117D01*
G03X1873715Y264730I-1075J1049D01*
G02X1874086Y265280I371J150D01*
G01X1884153D01*
X1885828Y263605D01*
Y248231D01*
X1889174Y244885D01*
X1912219D01*
G02X1912582Y244317I0J-400D01*
G03X1915492I1455J-671D01*
G02X1915855Y244885I363J168D01*
G01X1947578D01*
G02X1947833Y244177I0J-400D01*
G03X1946598Y241555I2166J-2622D01*
G01Y239155D01*
G03X1953251Y238154I3402J0D01*
G01X1953852D01*
G02X1954244Y237673I0J-400D01*
G03X1959543Y236615I2646J-547D01*
G02X1960225Y236815I393J-76D01*
G03X1959666Y239000I1665J1590D01*
G02X1958972Y238849I-386J104D01*
G03X1957841Y239655I-2081J-1724D01*
G02X1957616Y240190I141J374D01*
G03X1956667Y244177I-3116J1365D01*
G02X1956922Y244885I255J308D01*
G01X1963680D01*
X1964290Y244275D01*
Y241230D01*
X1966180Y239340D01*
X1973888D01*
X1974388Y238840D01*
Y210620D01*
X1973788Y210020D01*
X1965970D01*
X1964440Y208490D01*
Y205770D01*
X1966290Y203920D01*
X1974108D01*
X1974388Y203640D01*
Y166534D01*
G02X1973696Y166261I-400J0D01*
G03Y164211I-1098J-1025D01*
G02X1974388Y163938I292J-273D01*
G01Y149087D01*
G02X1973849Y148712I-400J0D01*
G03Y145894I-521J-1409D01*
G02X1974388Y145519I139J-375D01*
G01Y144748D01*
G02X1973781Y144405I-400J-1D01*
G03Y141835I-777J-1285D01*
G02X1974388Y141492I207J-342D01*
G01Y58688D01*
X1972700Y57000D01*
X1958595D01*
G02X1958208Y57502I0J400D01*
G03X1955306Y61270I-2902J766D01*
G01X1950206D01*
G03X1947304Y57502I0J-3002D01*
G02X1946917Y57000I-387J-102D01*
G01X1905320D01*
X1903120Y54800D01*
Y52760D01*
G02X1902523Y52412I-400J0D01*
G03X1897805Y48998I-1578J-2786D01*
G02X1897250Y48554I-392J-79D01*
G03Y42706I-1305J-2924D01*
G02X1897805Y42262I163J-365D01*
G03X1897771Y41214I3140J-626D01*
G02X1897224Y40790I-397J-53D01*
G03X1897035Y34415I-1279J-3152D01*
G02X1897561Y33995I128J-379D01*
G03Y33289I3384J-353D01*
G02X1897035Y32869I-398J-41D01*
G03Y26423I-1090J-3223D01*
G02X1897561Y26003I128J-379D01*
G03X1897588Y25098I3384J-352D01*
G02X1897055Y24658I-394J-65D01*
G03X1893687Y19384I-1110J-3004D01*
G02X1893405Y18700I-282J-284D01*
G01X1878283D01*
X1878243Y18848D01*
G03X1875341I-1451J-387D01*
G01X1875301Y18700D01*
X1843147D01*
G37*
G36*
G01X1972434Y-21822D02*
X1923232D01*
X1922200Y-20790D01*
Y-14600D01*
X1923100Y-13700D01*
X1972800D01*
X1974296Y-15196D01*
Y-19960D01*
X1972434Y-21822D01*
G37*
%LPC*%
G75*
G36*
G01X1498944Y114388D02*
G02X1501966Y114398I1511J0D01*
G01Y110848D01*
X1501957Y110764D01*
G02X1501849Y110349I-1502J169D01*
G03X1502081Y109818I369J-155D01*
G02X1500638Y107483I-478J-1318D01*
G03X1500037Y107423I-274J-291D01*
G02X1498719Y109789I-1227J867D01*
G03X1499063Y110344I-24J399D01*
G02X1498971Y110644I1391J591D01*
G03X1498384Y110916I-392J-77D01*
G02X1496581Y112986I-685J1223D01*
G03X1496346Y113619I-319J242D01*
G02X1497824Y114141I312J1469D01*
G03X1498038Y113501I310J-252D01*
G02X1498356Y113378I-343J-1359D01*
G03X1498944Y113731I188J354D01*
G01Y114388D01*
G37*
G36*
G01X32628Y481823D02*
G02X32555Y483834I-1151J965D01*
G03X33149Y483855I288J278D01*
G02X35646Y483556I1151J-965D01*
G03X36352Y483534I359J177D01*
G02X38556Y483831I1216J-698D01*
G03X39137Y483849I282J284D01*
G02X39197Y481923I1048J-931D01*
G03X38616Y481905I-282J-284D01*
G02X36330Y482179I-1048J931D01*
G03X35624Y482180I-353J-188D01*
G02X33222Y481844I-1324J710D01*
G03X32628Y481823I-288J-278D01*
G37*
G36*
G01X66912Y475954D02*
G02X65589Y477106I-1462J-344D01*
G03X66015Y477596I37J398D01*
G02X67338Y476444I1462J344D01*
G03X66912Y475954I-37J-398D01*
G37*
G36*
G01X635228Y468705D02*
G02X633613Y469184I-1195J-1067D01*
G03X633815Y469826I-105J386D01*
G02X633520Y471193I1152J964D01*
G03X633062Y471694I-385J108D01*
G02X634300Y472790I-291J1575D01*
G03X634741Y472275I382J-120D01*
G02X635191I225J-1485D01*
G03X635650Y472700I60J396D01*
G02X636924Y471324I1498J109D01*
G03X636465Y470899I-60J-396D01*
G02X635408Y469354I-1498J-109D01*
G03X635228Y468705I118J-382D01*
G37*
G36*
G01X1302222Y465814D02*
G02X1302177Y467261I-1222J686D01*
G03X1302868Y467294I336J217D01*
G02X1302914Y465824I1332J-694D01*
G03X1302222Y465814I-343J-206D01*
G37*
G36*
G01X1325145Y463100D02*
G02X1322522Y463000I-1330J443D01*
G03X1321947Y463188I-369J-155D01*
G02X1322582Y464991I-775J1286D01*
G03X1323148Y464776I376J137D01*
G02X1324672Y464653I667J-1233D01*
G03X1325296Y464843I245J316D01*
G02X1327682Y465322I1330J-443D01*
G03X1328285I301J263D01*
G02X1328242Y463404I1134J-985D01*
G03X1327640Y463431I-313J-249D01*
G02X1325769Y463290I-1014J969D01*
G03X1325145Y463100I-245J-316D01*
G37*
G36*
G01X608723Y464975D02*
G02X607410Y464044I77J-1500D01*
G03X607034Y464595I-370J151D01*
G02X607020Y467399I-22J1402D01*
G03X607396Y467941I2J400D01*
G02X608736Y466974I1404J534D01*
G03X608340Y466447I-17J-399D01*
G02X608328Y465513I-1328J-450D01*
G03X608723Y464975I375J-139D01*
G37*
G36*
G01X1261832Y463030D02*
G02X1261198Y461801I868J-1226D01*
G03X1260577Y462133I-400J-1D01*
G02X1261201Y463344I-777J1167D01*
G03X1261832Y463030I400J12D01*
G37*
G36*
G01X587529Y446495D02*
G02X586415Y447709I-1393J-160D01*
G03X586892Y448146I80J392D01*
G02X588006Y446932I1393J160D01*
G03X587529Y446495I-80J-392D01*
G37*
G36*
G01X1286966Y440969D02*
G02X1285411Y441521I-1197J-907D01*
G03X1285634Y442151I-96J388D01*
G02X1286812Y444560I1197J907D01*
G03X1287199Y445039I-5J400D01*
G02X1288690Y443836I1472J299D01*
G03X1288303Y443357I5J-400D01*
G02X1287189Y441599I-1472J-299D01*
G03X1286966Y440969I96J-388D01*
G37*
G36*
G01X635495Y436263D02*
G02X635317Y437648I-1295J538D01*
G03X636005Y437737I318J242D01*
G02X638310Y438172I1295J-537D01*
G03X638956Y438271I288J278D01*
G02X639179Y436600I1344J-671D01*
G03X638530Y436526I-298J-266D01*
G02X636183Y436352I-1230J674D01*
G03X635495Y436263I-318J-242D01*
G37*
G36*
G01X65611Y349258D02*
G02X65075Y347156I739J-1308D01*
G03X64539Y347292I-339J-212D01*
G02X62698Y347580I-738J1308D01*
G03X62070Y347528I-294J-272D01*
G02X61888Y349295I-1170J772D01*
G03X62512Y349373I281J284D01*
G02X65075Y349394I1288J-773D01*
G03X65611Y349258I339J212D01*
G37*
G36*
G01X88660Y345360D02*
G02X87260Y345321I-660J-1460D01*
G03X87240Y346040I-185J355D01*
G02X88640Y346079I660J1460D01*
G03X88660Y345360I185J-355D01*
G37*
G36*
G01X80856Y334377D02*
G02X80357Y336497I-1256J823D01*
G03X80894Y336623I202J345D01*
G02X83452Y336548I1256J-823D01*
G03X84132Y336526I347J199D01*
G02X85478Y337141I1168J-776D01*
G03X85922Y337466I51J397D01*
G02X87125Y335723I1478J-266D01*
G03X86663Y335423I-73J-393D01*
G02X84108Y335011I-1363J327D01*
G03X83428I-340J-210D01*
G02X81393Y334503I-1278J789D01*
G03X80856Y334377I-202J-345D01*
G37*
G36*
G01X77121Y310560D02*
G02X74280Y309752I-1495J-142D01*
G03X73628Y309847I-359J-177D01*
G02X73833Y311468I-1028J953D01*
G03X74487Y311398I351J191D01*
G02X75611Y311920I1138J-980D01*
G03X76005Y312358I-4J400D01*
G02X76624Y313720I1495J142D01*
G03X76592Y314390I-234J325D01*
G02X78158Y314491I708J1210D01*
G03X78212Y313822I244J-317D01*
G02X77515Y310998I-712J-1322D01*
G03X77121Y310560I4J-400D01*
G37*
G36*
G01X1514254Y281476D02*
G02X1514234Y280160I1228J-677D01*
G03X1513528Y280171I-356J-182D01*
G02X1513548Y281487I-1228J677D01*
G03X1514254Y281476I356J182D01*
G37*
G36*
G01X1603806Y269550D02*
G02X1602781Y268530I416J-1443D01*
G03X1602286Y269027I-384J113D01*
G02X1603311Y270047I-416J1443D01*
G03X1603806Y269550I384J-113D01*
G37*
G36*
G01X1608431Y241463D02*
G02X1607100Y242792I-1582J-253D01*
G03X1607560Y243235I63J395D01*
G02X1608873Y241924I1491J180D01*
G03X1608431Y241463I-47J-397D01*
G37*
G36*
G01X1649838Y196575D02*
G02X1648924Y195521I462J-1324D01*
G03X1648389Y195971I-392J76D01*
G02X1649317Y197041I-537J1403D01*
G03X1649838Y196575I390J-88D01*
G37*
G36*
G01X1636765Y196094D02*
G02X1636691Y194146I1105J-1017D01*
G03X1636097Y194183I-314J-248D01*
G02X1634120Y194190I-985J998D01*
G03X1633575Y194210I-283J-282D01*
G02X1631125Y195673I-985J1134D01*
G03X1630757Y196160I-390J88D01*
G02X1630564Y196185I83J1399D01*
G03X1630340Y195913I-39J-196D01*
G02X1629039Y196843I-1390J-569D01*
G03X1629456Y197313I23J399D01*
G02X1632072Y198221I1380J247D01*
G03X1632771Y198209I353J189D01*
G02X1635485Y196953I1298J-756D01*
G03X1635696Y196456I377J-133D01*
G02X1636169Y196102I-585J-1274D01*
G03X1636765Y196094I302J263D01*
G37*
G36*
G01X1709041Y188532D02*
G02X1708455Y186890I859J-1232D01*
G03X1707855Y187119I-385J-108D01*
G02X1708432Y188736I-755J1181D01*
G03X1709041Y188532I380J124D01*
G37*
G36*
G01X1643138Y183981D02*
G02X1640433Y184087I-1338J419D01*
G03X1639869Y184358I-390J-89D01*
G02X1640658Y185686I-611J1262D01*
G03X1640976Y185534I200J10D01*
G02X1641061Y185591I823J-1135D01*
G03X1641188Y186145I-211J340D01*
G02X1643944Y187159I1269J803D01*
G03X1644361Y186815I396J56D01*
G02X1643722Y184206I72J-1400D01*
G03X1643138Y183981I-203J-345D01*
G37*
G36*
G01X87867Y182912D02*
G02X86194Y183018I-915J-1191D01*
G03X86236Y183681I-201J346D01*
G02X87909Y183575I915J1191D01*
G03X87867Y182912I201J-346D01*
G37*
G36*
G01X115006Y179785D02*
G02Y181215I-1206J715D01*
G03X115694I344J204D01*
G02Y179785I1206J-715D01*
G03X115006I-344J-204D01*
G37*
G36*
G01X1597025Y179619D02*
G02Y180981I-1225J681D01*
G03X1597725I350J194D01*
G02Y179619I1225J-681D01*
G03X1597025I-350J-194D01*
G37*
G36*
G01X1242777Y155687D02*
G02X1242769Y154158I1171J-771D01*
G03X1242098Y154161I-336J-216D01*
G02X1242106Y155690I-1171J771D01*
G03X1242777Y155687I336J216D01*
G37*
G36*
G01X1578718Y150684D02*
G02X1576965Y150787I-948J-1165D01*
G03X1577002Y151435I-215J337D01*
G02X1578755Y151332I948J1165D01*
G03X1578718Y150684I215J-337D01*
G37*
G36*
G01X1542531Y150245D02*
G02X1540774Y149951I-700J-1215D01*
G03X1540657Y150568I-302J262D01*
G02X1540671Y153239I694J1332D01*
G03X1540684Y153946I-181J357D01*
G02X1542093Y153920I729J1313D01*
G03X1542080Y153213I181J-357D01*
G02X1542441Y150866I-729J-1313D01*
G03X1542531Y150245I290J-275D01*
G37*
G36*
G01X662991Y141753D02*
G02X662743Y143236I-1291J546D01*
G03X663409Y143347I298J267D01*
G02X663657Y141864I1291J-546D01*
G03X662991Y141753I-298J-267D01*
G37*
G36*
G01X1526072Y140039D02*
G02X1524841Y140601I-1172J-939D01*
G03X1525138Y141251I-15J400D01*
G02X1526369Y140689I1172J939D01*
G03X1526072Y140039I15J-400D01*
G37*
G36*
G01X1557043Y139093D02*
G02X1556623Y137754I1057J-1067D01*
G03X1555956Y137975I-394J-71D01*
G02X1556371Y139293I-956J1025D01*
G03X1557043Y139093I391J84D01*
G37*
G36*
G01X1542102Y137821D02*
G02X1540713Y137839I-712J-1323D01*
G03X1540722Y138548I-180J357D01*
G02X1542111Y138530I712J1323D01*
G03X1542102Y137821I180J-357D01*
G37*
G36*
G01X1590983Y135717D02*
G02X1588569Y134355I-1103J-866D01*
G03X1588067Y134592I-374J-142D01*
G02X1588931Y136417I-447J1329D01*
G03X1589433Y136180I374J142D01*
G02X1589465Y136190I434J-1333D01*
G03X1589653Y136831I-118J383D01*
G02X1591920Y138800I1147J969D01*
G03X1592503Y138786I298J267D01*
G02Y136814I997J-986D01*
G03X1591920Y136800I-285J-281D01*
G02X1591193Y136350I-1121J999D01*
G03X1590983Y135717I104J-386D01*
G37*
G36*
G01X1262697Y134362D02*
G02X1262517Y132923I1101J-868D01*
G03X1261838Y133008I-365J-163D01*
G02X1262018Y134447I-1101J868D01*
G03X1262697Y134362I365J163D01*
G37*
G36*
G01X1553376Y132283D02*
G02X1553124Y134028I-1205J717D01*
G03X1553740Y134117I272J293D01*
G02X1556097Y134199I1205J-717D01*
G03X1556777Y134238I328J229D01*
G02X1556838Y132711I1323J-712D01*
G03X1556157Y132695I-336J-217D01*
G02X1553992Y132372I-1212J705D01*
G03X1553376Y132283I-272J-293D01*
G37*
G36*
G01X1531389Y133225D02*
G02X1529991Y134069I-1288J-554D01*
G03X1530321Y134639I-31J398D01*
G02X1530189Y135484I1357J645D01*
G03X1529721Y135931I-396J54D01*
G02X1530938Y137208I-272J1477D01*
G03X1531406Y136761I396J-54D01*
G02X1531740Y133783I272J-1477D01*
G03X1531389Y133225I16J-400D01*
G37*
G36*
G01X1473905Y130098D02*
G02X1472295I-805J-1148D01*
G03Y130752I-230J327D01*
G02X1473905I805J1148D01*
G03Y130098I230J-327D01*
G37*
G36*
G01X1484671Y129908D02*
G02X1482702Y129028I-558J-1395D01*
G03X1482497Y129527I-376J137D01*
G02X1483786Y132015I597J1269D01*
G03X1484356Y132217I198J348D01*
G02X1484815Y132843I1400J-545D01*
G03X1484708Y133528I-250J312D01*
G02X1486121Y133771I502J1309D01*
G03X1486249Y133089I260J-304D01*
G02X1484772Y130535I-494J-1418D01*
G03X1484448Y130436I-131J-151D01*
G02X1484436Y130394I-1354J364D01*
G03X1484671Y129908I383J-115D01*
G37*
G36*
G01X1357397Y125723D02*
G02Y127277I-1167J777D01*
G03X1358063I333J222D01*
G02X1359107Y127897I1167J-777D01*
G03X1359440Y128451I-35J398D01*
G02X1361897Y129777I1290J549D01*
G03X1362563I333J222D01*
G02X1364897I1167J-777D01*
G03X1365563I333J222D01*
G02X1367897I1167J-777D01*
G03X1368563I333J222D01*
G02X1369853Y127603I1167J-777D01*
G03X1369520Y127049I35J-398D01*
G02X1367063Y125723I-1290J-549D01*
G03X1366397I-333J-222D01*
G02X1364063I-1167J777D01*
G03X1363397I-333J-222D01*
G02X1361063I-1167J777D01*
G03X1360397I-333J-222D01*
G02X1358063I-1167J777D01*
G03X1357397I-333J-222D01*
G37*
G36*
G01X1381867Y124673D02*
G02X1379923Y126617I-1167J777D01*
G03Y127283I-222J333D01*
G02X1381867Y129227I777J1167D01*
G03X1382533I333J222D01*
G02X1384867I1167J-777D01*
G03X1385533I333J222D01*
G02X1387477Y127283I1167J-777D01*
G03Y126617I222J-333D01*
G02X1385533Y124673I-777J-1167D01*
G03X1384867I-333J-222D01*
G02X1382533I-1167J777D01*
G03X1381867I-333J-222D01*
G37*
G36*
G01X1500837Y125213D02*
G02X1499205Y125860I-1219J-693D01*
G03X1499426Y126454I-118J382D01*
G02X1501083Y125798I1274J796D01*
G03X1500837Y125213I102J-387D01*
G37*
G36*
G01X639979Y125292D02*
G02X637828Y123610I-879J-1092D01*
G03X637247Y123777I-363J-168D01*
G02X635189Y124408I-766J1174D01*
G03X634545Y124543I-369J-155D01*
G02X634028Y126889I-965J1017D01*
G03X634554Y127301I128J379D01*
G02X637258Y127926I1397J118D01*
G03X637890Y127767I373J145D01*
G02X639913Y125847I911J-1066D01*
G03X639979Y125292I317J-244D01*
G37*
G36*
G01X1392867Y122173D02*
G02X1390923Y124117I-1167J777D01*
G03Y124783I-222J333D01*
G02Y127117I777J1167D01*
G03Y127783I-222J333D01*
G02X1392867Y129727I777J1167D01*
G03X1393533I333J222D01*
G02X1395477Y127783I1167J-777D01*
G03Y127117I222J-333D01*
G02Y124783I-777J-1167D01*
G03Y124117I222J-333D01*
G02X1393533Y122173I-777J-1167D01*
G03X1392867I-333J-222D01*
G37*
G36*
G01X648287Y121923D02*
G02Y123477I-1167J777D01*
G03X648953I333J222D01*
G02Y121923I1167J-777D01*
G03X648287I-333J-222D01*
G37*
G36*
G01X654278Y120773D02*
G02Y122327I-1167J777D01*
G03X654944I333J222D01*
G02X656120Y122952I1167J-777D01*
G03X656517Y123418I3J400D01*
G02X657123Y124817I1383J232D01*
G03Y125483I-222J333D01*
G02X659067Y127427I777J1167D01*
G03X659733I333J222D01*
G02X661677Y125483I1167J-777D01*
G03Y124817I222J-333D01*
G02X659733Y122873I-777J-1167D01*
G03X659067I-333J-222D01*
G02X657891Y122248I-1167J777D01*
G03X657494Y121782I-3J-400D01*
G02X654944Y120773I-1383J-232D01*
G03X654278I-333J-222D01*
G37*
G36*
G01X1401422Y122341D02*
G02X1399879Y122837I-1122J-841D01*
G03X1400078Y123459I-121J381D01*
G02X1399817Y124532I1122J841D01*
G03X1399418Y124998I-394J66D01*
G02X1400783Y126168I-18J1402D01*
G03X1401182Y125702I394J-66D01*
G02X1401621Y122963I18J-1402D01*
G03X1401422Y122341I121J-381D01*
G37*
G36*
G01X1554838Y121420D02*
G02X1552729Y122171I-1338J-420D01*
G03X1552686Y122863I-220J334D01*
G02X1554724Y124823I667J1346D01*
G03X1555219Y124608I365J163D01*
G02X1556146Y124604I458J-1325D01*
G03X1556663Y124864I134J377D01*
G02X1559101Y123307I1437J-437D01*
G03X1559149Y122674I267J-298D01*
G02X1557608Y122668I-766J-1174D01*
G03X1557568Y123022I-110J167D01*
G02X1557524Y123040I547J1399D01*
G03X1556995Y122806I-153J-369D01*
G02X1555321Y121927I-1318J477D01*
G03X1554838Y121420I-102J-387D01*
G37*
G36*
G01X1398444Y117893D02*
G02X1397340Y117114I156J-1393D01*
G03X1396936Y117687I-360J175D01*
G02X1398040Y118466I-156J1393D01*
G03X1398444Y117893I360J-175D01*
G37*
G36*
G01X1403778Y117090D02*
G02X1402565Y117801I-1278J-790D01*
G03X1402922Y118410I17J399D01*
G02X1404135Y117699I1278J790D01*
G03X1403778Y117090I-17J-399D01*
G37*
G36*
G01X671956Y115503D02*
G02X669054Y116278I-1453J381D01*
G03X668667Y116783I-386J105D01*
G02X669469Y119334I-2J1402D01*
G03X670042Y119458I229J328D01*
G02X672631Y118510I1207J-714D01*
G03X673146Y118061I395J-67D01*
G02X673280Y118097I430J-1334D01*
G03X673575Y118622I-82J391D01*
G02X676063Y119870I1321J471D01*
G03X676729I333J222D01*
G02X678174Y117719I1167J-777D01*
G03X677863Y117241I80J-392D01*
G02X675415Y116045I-1369J-301D01*
G03X674765Y115997I-308J-255D01*
G02X672614Y115695I-1199J727D01*
G03X671956Y115503I-271J-294D01*
G37*
G36*
G01X1525175Y115066D02*
G03X1524540Y115166I-355J-185D01*
G02X1524370Y117307I-983J999D01*
G03X1525002Y117633I232J326D01*
G01Y118926D01*
G03X1524427Y119285I-400J-1D01*
G02X1522924Y121630I-614J1260D01*
G03X1522950Y122226I-253J310D01*
G02X1524777Y124585I1050J1074D01*
G03X1525351Y124768I207J342D01*
G02X1527319Y122787I1377J-600D01*
G03X1527275Y122074I158J-368D01*
G02X1528024Y120779I-762J-1305D01*
G01Y115684D01*
X1528015Y115600D01*
G02X1525175Y115066I-1502J169D01*
G37*
G36*
G01X649566Y116708D02*
G02X649105Y114797I741J-1190D01*
G03X648550Y114931I-343J-206D01*
G02X646607Y115400I-741J1190D01*
G03X646052Y115534I-343J-206D01*
G02X644209Y115857I-741J1190D01*
G03X643674Y115943I-314J-247D01*
G02X641615Y116549I-775J1169D01*
G03X640981Y116686I-366J-160D01*
G02X641327Y118291I-938J1042D01*
G03X641961Y118154I366J160D01*
G02X644001Y117979I938J-1042D01*
G03X644536Y117893I314J247D01*
G02X646513Y117445I774J-1169D01*
G03X647068Y117311I343J206D01*
G02X649011Y116842I741J-1190D01*
G03X649566Y116708I343J206D01*
G37*
G36*
G01X1375250Y114376D02*
G02X1373073Y115617I-1400J74D01*
G03Y116283I-222J333D01*
G02Y118617I777J1167D01*
G03Y119283I-222J333D01*
G02Y121617I777J1167D01*
G03Y122283I-222J333D01*
G02X1374211Y124805I777J1167D01*
G03X1374711Y125138I104J386D01*
G02X1375739Y123595I1389J-188D01*
G03X1375239Y123262I-104J-386D01*
G02X1374627Y122283I-1389J188D01*
G03Y121617I222J-333D01*
G02X1374647Y121603I-794J-1155D01*
G03X1375273Y121895I228J329D01*
G02X1377446Y120596I1396J-132D01*
G03Y119930I222J-333D01*
G02X1377346Y117535I-777J-1167D01*
G03X1377219Y116944I193J-351D01*
G02X1375749Y114743I-1119J-844D01*
G03X1375250Y114376I-99J-388D01*
G37*
G36*
G01X1640008Y111617D02*
G02X1639990Y113019I-1106J687D01*
G03X1640664Y113028I334J220D01*
G02X1640682Y111626I1106J-687D01*
G03X1640008Y111617I-334J-220D01*
G37*
G36*
G01X622008Y113589D02*
G02X620798Y112220I192J-1389D01*
G03X620326Y112619I-400J6D01*
G02X618552Y114062I-272J1477D01*
G03X617994Y114421I-400J-8D01*
G02X616152Y116636I-594J1379D01*
G03X615897Y117251I-332J223D01*
G02X615446Y117424I269J1376D01*
G03X614896Y117284I-206J-343D01*
G02X614442Y119292I-1294J763D01*
G03X614999Y119402I224J332D01*
G02X617359Y117889I1168J-775D01*
G03X617636Y117283I340J-211D01*
G02X618902Y115834I-236J-1483D01*
G03X619460Y115475I400J8D01*
G02X621553Y114008I594J-1379D01*
G03X622008Y113589I399J-23D01*
G37*
G36*
G01X603350Y108965D02*
G02X602992Y110681I-1250J635D01*
G03X603611Y110824I255J309D01*
G02X603974Y109082I1366J-624D01*
G03X603350Y108965I-267J-298D01*
G37*
G36*
G01X1611921Y108539D02*
G02X1611920Y109841I-1128J650D01*
G03X1612613Y109842I346J200D01*
G02X1612614Y108540I1128J-650D01*
G03X1611921Y108539I-346J-200D01*
G37*
G36*
G01X121205Y107701D02*
G02X119466Y107899I-1008J-1114D01*
G03X119551Y108534I-195J349D01*
G02X121264Y108339I982J1001D01*
G03X121205Y107701I209J-341D01*
G37*
G36*
G01X74915Y103760D02*
G02Y106240I-2115J1240D01*
G03X75606I346J202D01*
G02X79837Y106239I2115J-1240D01*
G03X80527I345J202D01*
G02X84758Y106240I2116J-1239D01*
G03X85449I345J202D01*
G02X89679I2115J-1240D01*
G03X90370I346J202D01*
G02X94600I2115J-1240D01*
G03X95291I345J202D01*
G02X99522Y106239I2115J-1240D01*
G03X100212I345J202D01*
G02X104443Y106240I2116J-1239D01*
G03X105134I345J202D01*
G02Y103760I2115J-1240D01*
G03X104443I-345J-202D01*
G02X100212Y103761I-2115J1240D01*
G03X99522I-345J-202D01*
G02X95291Y103760I-2116J1239D01*
G03X94600I-345J-202D01*
G02X90370I-2115J1240D01*
G03X89679I-345J-202D01*
G02X85449I-2115J1240D01*
G03X84758I-345J-202D01*
G02X80527Y103761I-2115J1240D01*
G03X79837I-345J-202D01*
G02X75606Y103760I-2116J1239D01*
G03X74915I-345J-202D01*
G37*
G36*
G01X1396336Y101886D02*
G02X1394316I-1010J-973D01*
G03Y102440I-288J277D01*
G02X1394374Y104443I1010J973D01*
G03X1394379Y105026I-271J294D01*
G02X1394090Y106661I968J1014D01*
G03X1393857Y107217I-359J176D01*
G02X1393169Y107717I441J1331D01*
G03X1392517Y107705I-322J-237D01*
G02X1392488Y109327I-1158J791D01*
G03X1393140Y109339I322J237D01*
G02X1393502Y109702I1157J-792D01*
G03X1393504Y110359I-227J329D01*
G02X1395174Y112610I806J1147D01*
G03X1395814Y112854I246J315D01*
G02X1396329Y111498I1379J-252D01*
G03X1395689Y111254I-246J-315D01*
G02X1395106Y110352I-1379J252D01*
G03X1395104Y109695I227J-329D01*
G02X1395555Y107927I-806J-1147D01*
G03X1395788Y107371I359J-176D01*
G02X1396376Y106992I-442J-1331D01*
G03X1396954Y106983I293J272D01*
G02X1398919Y104983I997J-986D01*
G03X1398928Y104395I276J-290D01*
G02X1396934Y102433I-934J-1045D01*
G03X1396342Y102447I-302J-262D01*
G02X1396336Y102440I-1068J909D01*
G03Y101886I288J-277D01*
G37*
G36*
G01X1500648Y99497D02*
G02X1499420Y97741I127J-1396D01*
G03X1498965Y98033I-387J-102D01*
G02X1497194Y99501I-260J1489D01*
G01X1497149Y102725D01*
G02X1499767Y103775I1511J21D01*
G03X1500424Y103881I293J272D01*
G02X1500831Y102199I1276J-581D01*
G03X1500184Y101880I-247J-314D01*
G01X1500212Y99890D01*
G03X1500648Y99497I400J5D01*
G37*
G36*
G01X1639706Y95785D02*
G02Y97215I-1206J715D01*
G03X1640394I344J204D01*
G02Y95785I1206J-715D01*
G03X1639706I-344J-204D01*
G37*
G36*
G01X1363012Y95261D02*
G02X1360588Y96453I-1378J258D01*
G03Y96985I-298J266D01*
G02X1362680I1046J934D01*
G03Y96453I298J-266D01*
G02X1362959Y95976I-1047J-932D01*
G03X1363342Y96091I189J64D01*
G02X1363693Y95465I1358J350D01*
G03X1363012Y95261I-288J-278D01*
G37*
G36*
G01X733247Y93211D02*
G02X731940Y94192I-1337J-421D01*
G03X732325Y94726I8J400D01*
G02X733652Y93731I1415J504D01*
G03X733247Y93211I-23J-400D01*
G37*
G36*
G01X679467Y91853D02*
G02X677290Y93603I-1167J778D01*
G03Y94157I-288J277D01*
G02X677173Y94296I1012J971D01*
G03X676839Y94279I-161J-118D01*
G02X676619Y95982I-1209J710D01*
G03X677211Y96013I282J284D01*
G02X679467Y95907I1089J-883D01*
G03X680133I333J222D01*
G02X682310Y94157I1167J-778D01*
G03Y93603I288J-277D01*
G02X682467Y93407I-1011J-971D01*
G03X683133I333J222D01*
G02Y91853I1167J-777D01*
G03X682467I-333J-222D01*
G02X680133I-1167J777D01*
G03X679467I-333J-222D01*
G37*
G36*
G01X1377318Y92950D02*
G02X1377200Y91168I1146J-971D01*
G03X1376558Y91211I-337J-216D01*
G02X1376676Y92993I-1146J971D01*
G03X1377318Y92950I337J216D01*
G37*
G36*
G01X699100Y90315D02*
G02X698399Y89052I700J-1215D01*
G03X697800Y89385I-400J-14D01*
G02X698501Y90648I-700J1215D01*
G03X699100Y90315I400J14D01*
G37*
G36*
G01X707312Y87073D02*
G02X704606Y86976I-1340J-413D01*
G03X704134Y87458I-389J91D01*
G02X705211Y88514I-289J1372D01*
G03X705683Y88032I389J-91D01*
G02X705688Y88033I277J-1374D01*
G03X705989Y88542I-81J392D01*
G02X707613Y87582I1340J413D01*
G03X707312Y87073I81J-392D01*
G37*
G36*
G01X714182Y87090D02*
G02X712274Y86956I-882J-1090D01*
G03X712233Y87539I-293J272D01*
G02X714330Y89329I882J1090D01*
G03X715030Y89341I347J199D01*
G02X715053Y87983I1238J-658D01*
G03X714353Y87971I-347J-199D01*
G02X714141Y87673I-1239J657D01*
G03X714182Y87090I293J-272D01*
G37*
G36*
G01X649092Y84374D02*
G02X646112Y84406I-1492J-174D01*
G03X645818Y84847I-396J54D01*
G02X645068Y87287I382J1453D01*
G03Y87813I-302J263D01*
G02X645916Y90275I1132J987D01*
G03X646148Y90923I-76J393D01*
G02X646122Y90955I1153J963D01*
G03X645617Y91060I-315J-247D01*
G02X646086Y93309I-713J1322D01*
G03X646591Y93204I315J247D01*
G02X648640Y92568I713J-1322D01*
G03X649250Y92442I356J183D01*
G02X651539Y91970I954J-1160D01*
G03X652086Y91801I356J183D01*
G02X652097Y91807I725J-1315D01*
G03X652079Y92522I-188J353D01*
G02X653425Y92556I639J1359D01*
G03X653443Y91841I188J-353D01*
G02X651469Y89794I-639J-1359D01*
G03X650922Y89963I-356J-183D01*
G02X650797Y89902I-720J1318D01*
G03X650586Y89380I158J-367D01*
G02X650332Y87813I-1386J-579D01*
G03Y87287I302J-263D01*
G02X649428Y84815I-1132J-987D01*
G03X649092Y84374I61J-395D01*
G37*
G36*
G01X1521094Y80163D02*
G02X1519046Y78074I-780J-1283D01*
G03X1518366Y78065I-337J-215D01*
G02X1518482Y79256I-1204J718D01*
G03X1518864Y79271I189J67D01*
G02X1518954Y79518I1451J-389D01*
G03X1518800Y80030I-362J170D01*
G02X1520940Y80675I780J1283D01*
G03X1521094Y80163I362J-170D01*
G37*
G36*
G01X1408479Y76369D02*
G02X1406535Y78593I-1179J931D01*
G03X1406694Y79106I-203J344D01*
G02X1406651Y79208I1269J595D01*
G03X1406277I-187J-70D01*
G02X1403617Y80088I-1313J492D01*
G03X1403239Y80598I-385J110D01*
G02X1404431Y82777I25J1402D01*
G03X1405097I333J222D01*
G02X1407431I1167J-777D01*
G03X1408097I333J222D01*
G02X1409588Y80636I1167J-777D01*
G03X1409300Y80126I93J-389D01*
G02X1409319Y79339I-1336J-426D01*
G03X1409809Y78850I387J-103D01*
G02X1409088Y76390I391J-1450D01*
G03X1408479Y76369I-296J-269D01*
G37*
G36*
G01X1613998Y71634D02*
G02X1613900Y70086I1117J-848D01*
G03X1613227Y70117I-346J-200D01*
G02X1613327Y71688I-1227J867D01*
G03X1613998Y71634I353J188D01*
G37*
G36*
G01X666267Y67823D02*
G02Y69377I-1167J777D01*
G03X666933I333J222D01*
G02Y67823I1167J-777D01*
G03X666267I-333J-222D01*
G37*
G36*
G01X704753Y68146D02*
G02X703871Y65776I127J-1396D01*
G03X703316Y65796I-288J-277D01*
G02X701407Y65830I-936J1044D01*
G03X700853I-277J-288D01*
G02X698905Y65832I-973J1010D01*
G03X698364Y65845I-278J-288D01*
G02X696449Y65909I-923J1055D01*
G03X695907Y65931I-283J-283D01*
G02X695991Y67991I-907J1069D01*
G03X696533Y67969I283J283D01*
G02X698415Y67908I907J-1069D01*
G03X698956Y67895I278J288D01*
G02X699312Y68122I923J-1055D01*
G03X699480Y68712I-163J365D01*
G02X699597Y70436I1160J787D01*
G03X699534Y71027I-298J267D01*
G02X699335Y71204I828J1131D01*
G03X698755Y71209I-292J-273D01*
G02X696632Y71334I-1008J975D01*
G03X696003Y71342I-318J-243D01*
G02X696025Y73070I-1093J878D01*
G03X696654Y73062I318J243D01*
G02X698772Y73140I1093J-878D01*
G03X699352Y73135I292J273D01*
G02X701403Y71224I1008J-975D01*
G03X701466Y70633I298J-267D01*
G02X701654Y70468I-827J-1132D01*
G03X702204Y70442I289J277D01*
G02X704362Y68730I916J-1062D01*
G03X704753Y68146I354J-186D01*
G37*
G36*
G01X656587Y64968D02*
G02X654677Y67285I-987J1132D01*
G03Y67915I-246J315D01*
G02X655252Y70561I923J1185D01*
G03X655442Y71234I-92J389D01*
G02X655577Y73485I1058J1066D01*
G03Y74115I-246J315D01*
G02X657487Y76432I923J1185D01*
G03X658013I263J302D01*
G02X659923Y74115I987J-1132D01*
G03Y73485I246J-315D01*
G02X659348Y70839I-923J-1185D01*
G03X659158Y70166I92J-389D01*
G02X659023Y67915I-1058J-1066D01*
G03Y67285I246J-315D01*
G02X657113Y64968I-923J-1185D01*
G03X656587I-263J-302D01*
G37*
G36*
G01X664867Y64823D02*
G02Y66377I-1167J777D01*
G03X665533I333J222D01*
G02Y64823I1167J-777D01*
G03X664867I-333J-222D01*
G37*
G36*
G01X1410417Y64582D02*
G02X1408473Y66526I-1167J777D01*
G03Y67192I-222J333D01*
G02X1408380Y69459I777J1167D01*
G03X1408358Y70102I-248J313D01*
G02X1410317Y72036I792J1157D01*
G03X1410983I333J222D01*
G02X1413020Y70159I1167J-778D01*
G03X1413042Y69516I248J-313D01*
G02X1413027Y67192I-792J-1157D01*
G03Y66526I222J-333D01*
G02X1411083Y64582I-777J-1167D01*
G03X1410417I-333J-222D01*
G37*
G36*
G01X53277Y58867D02*
G02X51723I-777J-1167D01*
G03Y59533I-222J333D01*
G02Y61867I777J1167D01*
G03Y62533I-222J333D01*
G02X53277I777J1167D01*
G03Y61867I222J-333D01*
G02Y59533I-777J-1167D01*
G03Y58867I222J-333D01*
G37*
G36*
G01X1382757Y58993D02*
G02X1381727Y57963I414J-1444D01*
G03X1381244Y58461I-384J110D01*
G02X1382259Y59476I-344J1359D01*
G03X1382757Y58993I388J-99D01*
G37*
G36*
G01X714619Y54213D02*
G02X712577Y54229I-1029J-953D01*
G03X712581Y54777I-289J276D01*
G02X712619Y56722I1029J953D01*
G03X712622Y57286I-282J284D01*
G02X712689Y59319I998J985D01*
G03X712703Y59905I-265J299D01*
G02X712580Y61779I977J1005D01*
G03X712440Y62388I-314J248D01*
G02X712012Y62707I609J1263D01*
G03X711433Y62720I-296J-269D01*
G02X711478Y64653I-993J990D01*
G03X712057Y64640I296J269D01*
G02X714150Y62781I993J-990D01*
G03X714290Y62172I314J-248D01*
G02X715056Y61180I-610J-1262D01*
G03X715526Y60865I392J77D01*
G02X716814Y58521I274J-1375D01*
G03Y57969I289J-276D01*
G02X715449Y55643I-1014J-969D01*
G03X714963Y55361I-100J-387D01*
G02X714623Y54761I-1352J370D01*
G03X714619Y54213I289J-276D01*
G37*
G36*
G01X1408317Y52082D02*
G02X1406373Y54026I-1167J777D01*
G03Y54692I-222J333D01*
G02Y57026I777J1167D01*
G03Y57692I-222J333D01*
G02X1408317Y59636I777J1167D01*
G03X1408983I333J222D01*
G02X1410927Y57692I1167J-777D01*
G03Y57026I222J-333D01*
G02Y54692I-777J-1167D01*
G03Y54026I222J-333D01*
G02X1408983Y52082I-777J-1167D01*
G03X1408317I-333J-222D01*
G37*
G36*
G01X1398290Y52158D02*
G02X1396499Y51982I-790J-1158D01*
G03X1396312Y52649I-286J280D01*
G02X1395800Y52830I740J2909D01*
G02X1393300I-1250J2729D01*
G02X1389228Y56583I-1250J2729D01*
G03X1388916Y57115I-376J137D01*
G02X1389356Y59884I222J1384D01*
G02X1393300Y61288I2694J-1325D01*
G02X1395800I1250J-2729D01*
G02X1399650Y57059I1250J-2729D01*
G02X1398343Y52850I-2600J-1500D01*
G03X1398290Y52158I172J-361D01*
G37*
G36*
G01X1371355Y50196D02*
G02X1370408Y48784I555J-1396D01*
G03X1369875Y49157I-400J-4D01*
G02X1370808Y50548I-467J1322D01*
G03X1371355Y50196I399J20D01*
G37*
G36*
G01X664412Y46340D02*
G02X662559Y46356I-936J-1044D01*
G03X662564Y46956I-262J302D01*
G02X664667Y48777I936J1044D01*
G03X665333I333J222D01*
G02Y47223I1167J-777D01*
G03X664667I-333J-222D01*
G02X664417Y46940I-1166J778D01*
G03X664412Y46340I262J-302D01*
G37*
G36*
G01X1380607Y44908D02*
G02X1377608Y45072I-1497J125D01*
G03X1377162Y45479I-400J10D01*
G02X1378491Y46932I-173J1492D01*
G03X1378937Y46525I400J-10D01*
G02X1379835Y46349I174J-1492D01*
G03X1380425Y46651I193J350D01*
G02X1381186Y45232I1392J-167D01*
G03X1380607Y44908I-180J-357D01*
G37*
G36*
G01X1412322Y44402D02*
G02X1410529Y44222I-776J-1286D01*
G03X1410479Y44849I-271J294D01*
G02X1412246Y45027I775J1169D01*
G03X1412322Y44402I283J-283D01*
G37*
G36*
G01X1407451Y44314D02*
G02X1405746Y44387I-905J-1198D01*
G03X1405786Y45035I-213J338D01*
G02X1407466Y44963I888J1085D01*
G03X1407451Y44314I226J-330D01*
G37*
G36*
G01X717821Y39557D02*
G02X715736Y37718I-921J-1057D01*
G03X715097Y37752I-332J-223D01*
G02X712873Y37851I-1074J901D01*
G03X712224Y37862I-328J-228D01*
G02X710054Y39634I-1123J839D01*
G03Y40166I-298J266D01*
G02X712250Y41902I1046J933D01*
G03X712899Y41891I328J228D01*
G02X713154Y42154I1126J-836D01*
G03X713149Y42786I-247J314D01*
G02X713067Y44947I851J1114D01*
G03X712995Y45595I-266J298D01*
G02X714647Y47831I679J1227D01*
G03X715203I278J288D01*
G02X716403Y48205I973J-1009D01*
G03X716866Y48644I65J395D01*
G02X721049Y51722I2984J326D01*
G02X724896Y47471I1263J-2723D01*
G02X722547Y46006I-1293J-543D01*
G02X722215Y45999I-229J2993D01*
G02X720085Y45977I-1074J901D01*
G02X719635Y45976I-232J2993D01*
G02X717699Y45847I-1035J945D01*
G03X717161Y45825I-257J-307D01*
G02X717105Y45772I-991J991D01*
G03X717222Y45101I265J-299D01*
G02X717628Y42749I-522J-1301D01*
G03X717637Y42141I264J-300D01*
G02X717786Y40126I-895J-1079D01*
G03X717821Y39557I298J-267D01*
G37*
G36*
G01X702098Y36889D02*
G02X700469Y36532I-573J-1279D01*
G03X700331Y37160I-302J263D01*
G02X701960Y37517I573J1279D01*
G03X702098Y36889I302J-263D01*
G37*
G36*
G01X53277Y35867D02*
G02X51723I-777J-1167D01*
G03Y36533I-222J333D01*
G02Y38867I777J1167D01*
G03Y39533I-222J333D01*
G02Y41867I777J1167D01*
G03Y42533I-222J333D01*
G02X53277I777J1167D01*
G03Y41867I222J-333D01*
G02Y39533I-777J-1167D01*
G03Y38867I222J-333D01*
G02Y36533I-777J-1167D01*
G03Y35867I222J-333D01*
G37*
G36*
G01X28105Y26362D02*
G02X26205Y26461I-1004J-979D01*
G03X26236Y27048I-255J308D01*
G02X26242Y29013I1003J979D01*
G03X26234Y29584I-284J282D01*
G02X25801Y30685I966J1016D01*
G03X25445Y31107I-400J24D01*
G02X25521Y33900I155J1393D01*
G03X25898Y34299I-23J399D01*
G02X25901Y34385I1402J-6D01*
G03X25545Y34807I-400J24D01*
G02X25563Y37595I156J1393D01*
G03X25918Y38061I-39J398D01*
G02X25910Y38487I1382J239D01*
G03X25600Y38931I-396J53D01*
G02X25532Y41653I300J1369D01*
G03X25822Y42100I-105J386D01*
G02X25826Y42550I1386J213D01*
G03X25492Y43014I-394J68D01*
G02X25651Y45801I209J1386D01*
G03X25993Y46384I-14J400D01*
G02X26103Y47849I1246J643D01*
G03X25997Y48419I-324J235D01*
G02X27896Y48773I763J1176D01*
G03X28002Y48203I324J-235D01*
G02X27288Y45626I-763J-1176D01*
G03X26946Y45043I14J-400D01*
G02X27082Y44163I-1246J-643D01*
G03X27416Y43699I394J-68D01*
G02X27576Y40960I-208J-1386D01*
G03X27286Y40513I105J-386D01*
G02X27290Y40113I-1386J-214D01*
G03X27600Y39669I396J-53D01*
G02X27437Y36905I-301J-1369D01*
G03X27082Y36439I39J-398D01*
G02X27099Y36115I-1382J-235D01*
G03X27455Y35693I400J-24D01*
G02X27379Y32900I-155J-1393D01*
G03X27002Y32501I23J-399D01*
G02X26999Y32415I-1402J6D01*
G03X27355Y31993I400J-24D01*
G02X28197Y29614I-155J-1393D01*
G03X28205Y29043I284J-282D01*
G02X28136Y26949I-966J-1016D01*
G03X28105Y26362I255J-308D01*
G37*
G36*
G01X15387Y25853D02*
G02X15294Y23728I1013J-1109D01*
G03X14729Y23752I-295J-271D01*
G02X12379Y24177I-1013J1109D01*
G03X11707Y24240I-356J-182D01*
G02X9215Y25317I-1107J860D01*
G03X8786Y25777I-395J62D01*
G02X10133Y26979I-126J1497D01*
G03X10542Y26501I392J-79D01*
G02X11825Y25781I57J-1401D01*
G03X12499Y25741I350J194D01*
G02X14822Y25877I1217J-880D01*
G03X15387Y25853I295J271D01*
G37*
G36*
G01X1591580Y25295D02*
G02X1591546Y23679I1249J-835D01*
G03X1590872Y23693I-341J-208D01*
G02X1590906Y25309I-1249J835D01*
G03X1591580Y25295I341J208D01*
G37*
G36*
G01X39086Y18836D02*
G02X36511Y18636I-1347J665D01*
G03X35859Y18639I-327J-230D01*
G02X35833Y20306I-1140J816D01*
G03X36485Y20328I318J242D01*
G02X38596Y20734I1254J-827D01*
G03X39183Y20885I228J328D01*
G02X39673Y18987I1347J-665D01*
G03X39086Y18836I-228J-328D01*
G37*
G36*
G01X55499Y-7137D02*
G02X54264Y-6550I-1192J-914D01*
G03X54576Y-5916I-12J400D01*
G02X54410Y-5613I1137J820D01*
G03X53766Y-5468I-372J-148D01*
G02X52323Y-2926I-1022J1100D01*
G03X52471Y-2238I-112J384D01*
G02X53814Y-2507I912J1065D01*
G03X53687Y-3199I124J-380D01*
G02X54159Y-3865I-943J-1169D01*
G03X54797Y-4033I377J135D01*
G02X55794Y-6495I916J-1062D01*
G03X55499Y-7137I23J-399D01*
G37*
G36*
G01X43033Y-15035D02*
G03X43211Y-15562I361J-172D01*
G02X41164Y-16251I-690J-1334D01*
G03X40986Y-15724I-361J172D01*
G02X43033Y-15035I690J1334D01*
G37*
G36*
G01X1375619Y17927D02*
G02X1375654Y12428I1223J-2742D01*
G02X1372919Y12576I-1223J2742D01*
G02X1369148Y16600I-1019J2824D01*
G02X1369174Y19057I2752J1200D01*
G02X1369198Y21398I2776J1142D01*
G02X1370532Y25268I2743J1219D01*
G03X1370621Y25526I-94J177D01*
G02X1370890Y27073I1279J574D01*
G03Y27627I-288J277D01*
G02Y29573I1010J973D01*
G03Y30127I-288J277D01*
G02X1372910I1010J973D01*
G03Y29573I288J-277D01*
G02Y27627I-1010J-973D01*
G03Y27073I288J-277D01*
G02X1373192Y25557I-1010J-972D01*
G03X1373287Y25300I185J-78D01*
G02X1374693Y21419I-1346J-2683D01*
G02X1374676Y18943I-2743J-1219D01*
G02X1374883Y18138I-2776J-1143D01*
G02X1375619Y17927I-453J-2968D01*
G37*
G36*
G01X1357926Y16416D02*
G03X1357607Y15910I65J-394D01*
G02X1356035Y16901I-1346J-393D01*
G03X1356354Y17407I-65J394D01*
G02X1356359Y18210I1346J393D01*
G03X1356049Y18721I-382J118D01*
G02X1356089Y21486I251J1379D01*
G03X1356423Y21952I-60J395D01*
G02X1356410Y22357I1380J247D01*
G03X1356093Y22794I-398J45D01*
G02X1356088Y25539I283J1373D01*
G03X1356404Y25968I-82J391D01*
G02X1356418Y26339I1396J133D01*
G03X1356063Y26805I-394J68D01*
G02X1356129Y29600I138J1395D01*
G03X1356507Y30044I-20J400D01*
G02X1356498Y30217I1393J159D01*
G03X1356134Y30621I-400J6D01*
G02X1355251Y32990I127J1396D01*
G03Y33544I-288J277D01*
G02X1355922Y35877I1010J973D01*
G03X1356152Y36495I-97J388D01*
G02X1358273Y38310I1147J806D01*
G03X1358827I277J288D01*
G02X1360801Y36318I973J-1010D01*
G03X1360792Y35767I285J-280D01*
G02X1360771Y33844I-1031J-950D01*
G03Y33290I288J-277D01*
G02X1359693Y30917I-1010J-973D01*
G03X1359280Y30447I-19J-400D01*
G02X1357971Y28800I-1380J-247D01*
G03X1357593Y28356I20J-400D01*
G02X1357582Y27961I-1393J-159D01*
G03X1357937Y27495I394J-68D01*
G02X1358088Y24728I-137J-1395D01*
G03X1357772Y24299I82J-391D01*
G02X1357769Y24010I-1396J-130D01*
G03X1358086Y23573I398J-45D01*
G02X1358014Y20814I-283J-1373D01*
G03X1357680Y20348I60J-395D01*
G02X1357641Y19690I-1380J-248D01*
G03X1357951Y19179I382J-118D01*
G02X1357926Y16416I-251J-1379D01*
G37*
G36*
G01X23654Y16742D02*
G03X23374Y17271I-374J140D01*
G02X25134Y18203I354J1460D01*
G03X25414Y17674I374J-140D01*
G02X23654Y16742I-354J-1460D01*
G37*
G36*
G01X1381Y22981D02*
G03X1003Y23431I-397J50D01*
G02X1059Y26233I65J1400D01*
G03X1451Y26696I-3J400D01*
G02X2875Y25432I1483J237D01*
G03X2461Y24988I-16J-400D01*
G02X2466Y24724I-1393J-158D01*
G03X2866Y24293I399J-31D01*
G02X1381Y22981I5J-1502D01*
G37*
G36*
G01X1380603Y27537D02*
G03X1381116Y27305I374J143D01*
G02X1380239Y25361I526J-1407D01*
G03X1379726Y25593I-374J-143D01*
G02X1380603Y27537I-526J1407D01*
G37*
G36*
G01X1509076Y30459D02*
G03X1508564Y30057I-112J-384D01*
G02X1507532Y32530I-3898J-175D01*
G03X1508178Y32612I294J272D01*
G02X1509076Y30459I1322J-712D01*
G37*
G36*
G01X12579Y32941D02*
G03X12566Y32382I279J-286D01*
G02X10560Y32430I-1026J-955D01*
G03X10573Y32989I-279J286D01*
G02X10590Y34917I1027J955D01*
G03Y35471I-288J277D01*
G02X12610I1010J973D01*
G03Y34917I288J-277D01*
G02X12579Y32941I-1010J-972D01*
G37*
G36*
G01X1368673Y36704D02*
G03X1368127I-273J-292D01*
G02Y38896I-1027J1096D01*
G03X1368673I273J292D01*
G02X1370826Y38794I1027J-1096D01*
G03X1371408Y38776I299J265D01*
G02X1371398Y36805I992J-991D01*
G03X1370815Y36793I-286J-280D01*
G02X1368673Y36704I-1115J1007D01*
G37*
G36*
G01X686498Y45656D02*
G02X686275Y40237I-1398J-2657D01*
G02X683582Y40410I-1371J-294D01*
G02X683558Y45576I1518J2590D01*
G03X683719Y46081I-205J344D01*
G02X686311Y46152I1281J569D01*
G03X686498Y45656I374J-142D01*
G37*
G36*
G01X1363657Y44922D02*
G03X1363609Y44366I261J-303D01*
G02X1361465Y44549I-1161J-953D01*
G03X1361513Y45105I-261J303D01*
G02X1363657Y44922I1161J953D01*
G37*
G36*
G01X657580Y43507D02*
G03X657054I-263J-302D01*
G02X655144Y45824I-987J1132D01*
G03Y46454I-246J315D01*
G02X657054Y48771I923J1185D01*
G03X657580I263J302D01*
G02X659490Y46454I987J-1132D01*
G03Y45824I246J-315D01*
G02X657580Y43507I-923J-1185D01*
G37*
G36*
G01X25074Y60921D02*
G03Y60367I288J-277D01*
G02X23054I-1010J-973D01*
G03Y60921I-288J277D01*
G02X25074I1010J973D01*
G37*
G36*
G01X1610356Y62550D02*
G03X1609844Y62326I-141J-374D01*
G02X1606956Y63026I-1392J564D01*
G03X1606608Y63459I-398J36D01*
G02X1608293Y64813I189J1490D01*
G03X1608641Y64380I398J-36D01*
G02X1609061Y64263I-189J-1490D01*
G03X1609585Y64458I162J366D01*
G02X1610356Y62550I1268J-597D01*
G37*
G36*
G01X1396239Y62392D02*
G02X1393639I-1300J2706D01*
G02X1389625Y66381I-1300J2706D01*
G02X1393551Y70660I2524J1625D01*
G02X1396300Y70788I1499J-2601D01*
G02X1400156Y66569I1250J-2729D01*
G02X1396239Y62392I-2617J-1471D01*
G37*
G36*
G01X724800Y66531D02*
G03X724911Y65938I314J-248D01*
G02X723100Y65599I-711J-1208D01*
G03X722989Y66192I-314J248D01*
G02X722337Y67729I711J1208D01*
G03X722062Y68206I-389J94D01*
G02X723823Y69221I398J1344D01*
G03X724098Y68744I389J-94D01*
G02X724800Y66531I-398J-1344D01*
G37*
G36*
G01X1586597Y69993D02*
G03X1585969Y69965I-303J-261D01*
G02X1585885Y71821I-1221J875D01*
G03X1586513Y71849I303J261D01*
G02X1586597Y69993I1221J-875D01*
G37*
G36*
G01X651513Y71168D02*
G03X650987I-263J-302D01*
G02X649077Y73485I-987J1132D01*
G03Y74115I-246J315D01*
G02X650987Y76432I923J1185D01*
G03X651513I263J302D01*
G02X653423Y74115I987J-1132D01*
G03Y73485I246J-315D01*
G02X651513Y71168I-923J-1185D01*
G37*
G36*
G01X1454277Y74673D02*
G03X1454869Y74662I301J263D01*
G02X1454833Y72777I1020J-962D01*
G03X1454241Y72788I-301J-263D01*
G02X1454277Y74673I-1020J962D01*
G37*
G36*
G01X1390765Y73812D02*
G03X1390207Y73739I-242J-318D01*
G02X1389168Y76000I-1107J861D01*
G03X1389587Y76376I20J400D01*
G02X1389623Y76695I2997J-177D01*
G03X1389193Y77160I-395J67D01*
G02X1389567Y79866I-125J1396D01*
G03X1389822Y79975I71J187D01*
G02X1393790Y81547I2762J-1177D01*
G02X1396200Y81552I1211J-2747D01*
G02X1400106Y77500I1200J-2752D01*
G02X1396200Y73448I-2706J-1300D01*
G02X1393792Y73452I-1199J2752D01*
G02X1390765Y73812I-1208J2748D01*
G37*
G36*
G01X1622615Y74417D02*
G03X1622096Y74216I-156J-369D01*
G02X1621318Y76230I-1363J631D01*
G03X1621837Y76431I156J369D01*
G02X1622615Y74417I1363J-631D01*
G37*
G36*
G01X1593215Y76755D02*
G03X1592905Y76213I62J-395D01*
G02X1590542Y74780I-1305J-513D01*
G03X1589971Y74814I-302J-262D01*
G02X1588731Y77410I-1009J1112D01*
G03X1589067Y77840I-62J395D01*
G02X1591381Y79023I1397J122D01*
G03X1591944Y79062I262J302D01*
G02X1593215Y76755I1056J-922D01*
G37*
G36*
G01X1581380Y74745D02*
G03X1580834I-273J-292D01*
G02Y76937I-1027J1096D01*
G03X1581380I273J292D01*
G02Y74745I1027J-1096D01*
G37*
G36*
G01X675599Y76999D02*
G03X675021I-289J-277D01*
G02X672971Y78911I-1011J971D01*
G03X672946Y79472I-297J268D01*
G02X672883Y81465I954J1028D01*
G03X672867Y82031I-290J275D01*
G02X674841Y84021I962J1020D01*
G03X675419I289J277D01*
G02X677447Y82085I1011J-971D01*
G03X677463Y81519I290J-275D01*
G02X677539Y79559I-963J-1019D01*
G03X677564Y78998I297J-268D01*
G02X675599Y76999I-954J-1028D01*
G37*
G36*
G01X694085Y83696D02*
G03X693552Y83430I-147J-372D01*
G02X692715Y85104I-1352J370D01*
G03X693248Y85370I147J372D01*
G02X694085Y83696I1352J-370D01*
G37*
G36*
G01X1574840Y83196D02*
G03X1574231Y83179I-297J-267D01*
G02X1574179Y85122I-1171J941D01*
G03X1574788Y85139I297J267D01*
G02X1574840Y83196I1171J-941D01*
G37*
G36*
G01X1500789Y85477D02*
G03X1500716Y84911I242J-319D01*
G02X1498702Y85112I-1103J-865D01*
G03X1498742Y85681I-260J304D01*
G02X1498364Y86681I1134J1000D01*
G01Y90481D01*
G02X1501386Y90491I1511J0D01*
G01Y86596D01*
X1501377Y86512D01*
G02X1500789Y85477I-1502J169D01*
G37*
G36*
G01X1588940Y83400D02*
G03X1588376Y83383I-273J-292D01*
G02X1588319Y85370I-1017J965D01*
G03X1588883Y85387I273J292D01*
G02X1588940Y83400I1017J-965D01*
G37*
G36*
G01X70196Y91249D02*
G03X70688Y90955I389J92D01*
G02X69707Y89199I362J-1354D01*
G03X69198Y89464I-383J-115D01*
G02X68725Y89388I-473J1436D01*
G01X63724D01*
G02X63134Y89509I3J1512D01*
G03X62605Y89287I-157J-368D01*
G02X61774Y91120I-1305J513D01*
G03X62289Y91371I135J376D01*
G02X63725Y92412I1436J-470D01*
G01X68725D01*
G02X70196Y91249I0J-1512D01*
G37*
G36*
G01X1405579Y90903D02*
G03X1404913I-333J-222D01*
G02X1403448Y93050I-1167J777D01*
G03X1403759Y93494I-85J391D01*
G02X1406151Y94660I1390J185D01*
G03X1406757Y94700I286J279D01*
G02X1408404Y92365I1203J-900D01*
G03X1408128Y91916I118J-382D01*
G02X1405579Y90903I-1382J-236D01*
G37*
G36*
G01X1455210Y94097D02*
G03X1455533Y93555I373J-145D01*
G02X1453946Y92607I-186J-1490D01*
G03X1453623Y93149I-373J145D01*
G02X1455210Y94097I186J1490D01*
G37*
G36*
G01X691464Y93829D02*
G03X692074Y93682I363J168D01*
G02X691636Y91871I926J-1182D01*
G03X691026Y92018I-363J-168D01*
G02X688742Y92559I-926J1182D01*
G03X688163Y92724I-362J-171D01*
G02X688638Y94558I-763J1176D01*
G03X689224Y94420I353J187D01*
G02X691464Y93829I876J-1220D01*
G37*
G36*
G01X1605005Y94753D02*
G03X1605585Y94714I308J255D01*
G02X1605465Y92931I885J-955D01*
G03X1604885Y92970I-308J-255D01*
G02X1605005Y94753I-885J955D01*
G37*
G36*
G01X1589830Y95117D02*
G03X1590401Y95040I323J237D01*
G02X1590140Y93111I869J-1100D01*
G03X1589569Y93188I-323J-237D01*
G02X1589830Y95117I-869J1100D01*
G37*
G36*
G01X1573583Y97382D02*
G03X1573573Y96771I253J-310D01*
G02X1571637Y96803I-987J-1132D01*
G03X1571647Y97414I-253J310D01*
G02X1573583Y97382I987J1132D01*
G37*
G36*
G01X1555704Y99831D02*
G03X1555727Y99252I287J-279D01*
G02X1553745Y99124I-927J-1052D01*
G03X1553693Y99701I-301J264D01*
G02X1555704Y99831I934J1176D01*
G37*
G36*
G01X1559131Y99752D02*
G03X1559108Y99174I265J-300D01*
G02X1557118Y99201I-1008J-974D01*
G03X1557111Y99779I-280J286D01*
G02X1559131Y99752I1025J1098D01*
G37*
G36*
G01X1375685Y100772D02*
G03Y100460I125J-156D01*
G02X1373798Y100339I-877J-1094D01*
G03Y100893I-288J277D01*
G02Y102839I1010J973D01*
G03Y103393I-288J277D01*
G02Y105339I1010J973D01*
G03Y105893I-288J277D01*
G02X1375781Y107876I1010J973D01*
G03X1376335I277J288D01*
G02X1378318Y105893I973J-1010D01*
G03Y105339I288J-277D01*
G02Y103393I-1010J-973D01*
G03Y102839I288J-277D01*
G02X1376335Y100856I-1010J-973D01*
G03X1375781I-277J-288D01*
G02X1375685Y100772I-970J1012D01*
G37*
G36*
G01X1586622Y101841D02*
G03X1587165Y101748I320J239D01*
G02X1586749Y99669I835J-1248D01*
G03X1586212Y99792I-333J-221D01*
G02X1586622Y101841I-712J1208D01*
G37*
G36*
G01X743589Y101538D02*
G03X743054Y101351I-174J-360D01*
G02X742426Y103315I-1354J649D01*
G03X742970Y103473I193J350D01*
G02X744736Y104095I1230J-673D01*
G03X745269Y104340I153J370D01*
G02X746064Y102605I1331J-440D01*
G03X745531Y102360I-153J-370D01*
G02X743589Y101538I-1331J440D01*
G37*
G36*
G01X700131Y103748D02*
G03X699963Y103231I195J-349D01*
G02X697568Y101509I-1363J-631D01*
G03X697042Y101530I-275J-290D01*
G02X694936Y101751I-942J1170D01*
G03X694410Y101835I-310J-253D01*
G02X692159Y103525I-810J1265D01*
G03X691783Y104038I-383J113D01*
G02X692920Y106552I27J1502D01*
G03X693477Y106519I295J269D01*
G02X695681Y106255I982J-1137D01*
G03X695960Y106209I163J117D01*
G02X697814Y106122I872J-1223D01*
G03X698354Y106138I261J303D01*
G02X700477Y106107I1046J-1078D01*
G03X701014Y106074I287J279D01*
G02X703131Y105834I939J-1172D01*
G03X703650Y105738I314J248D01*
G02X703241Y103516I769J-1290D01*
G03X702722Y103612I-314J-248D01*
G02X700876Y103855I-769J1290D01*
G03X700339Y103888I-287J-279D01*
G02X700131Y103748I-940J1172D01*
G37*
G36*
G01X327811Y104723D02*
G03X327904Y104164I325J-233D01*
G02X325908Y102270I-812J-1143D01*
G03X325331Y102377I-338J-214D01*
G02X324666Y104891I-839J1123D01*
G03X325110Y105354I50J397D01*
G02X327811Y104723I1482J246D01*
G37*
G36*
G01X428696Y104680D02*
G03X428682Y104097I267J-298D01*
G02X426710I-986J-997D01*
G03X426696Y104680I-281J285D01*
G02X428696I1000J1120D01*
G37*
G36*
G01X402382Y104686D02*
G03X402367Y104106I268J-297D01*
G02X400383I-992J-990D01*
G03X400368Y104686I-283J283D01*
G02X402382I1007J1114D01*
G37*
G36*
G01X409153Y104654D02*
G03X409138Y104086I274J-291D01*
G02X407114I-1012J-970D01*
G03X407099Y104654I-289J277D01*
G02X409153I1027J1096D01*
G37*
G36*
G01X415827Y104685D02*
G03X415812Y104106I268J-297D01*
G02X413827Y104107I-993J-990D01*
G03X413812Y104686I-283J282D01*
G02X415827Y104685I1008J1114D01*
G37*
G36*
G01X422514Y104689D02*
G03X422501Y104110I269J-296D01*
G02X420516Y104103I-989J-994D01*
G03X420500Y104682I-284J282D01*
G02X422514Y104689I1003J1118D01*
G37*
G36*
G01X1490546Y104528D02*
G03X1490393Y104003I204J-344D01*
G02X1488287Y104617I-1340J-678D01*
G03X1488440Y105142I-204J344D01*
G02X1490546Y104528I1340J678D01*
G37*
G36*
G01X1513448Y103101D02*
G03X1512949Y102873I-129J-379D01*
G02X1511941Y104772I-1299J527D01*
G03X1512424Y105163I83J391D01*
G01Y107637D01*
G03X1511941Y108028I-400J0D01*
G02X1512931Y109971I-291J1372D01*
G03X1513430Y109757I365J163D01*
G02X1515446Y108342I505J-1425D01*
G01Y104447D01*
X1515437Y104363D01*
G02X1513448Y103101I-1502J169D01*
G37*
G36*
G01X298659Y106735D02*
G03X298673Y106170I290J-275D01*
G02X296603Y106176I-1038J-1086D01*
G03X296620Y106740I-275J291D01*
G02X298659Y106735I1022J960D01*
G37*
G36*
G01X305191Y106575D02*
G03X305179Y105996I270J-295D01*
G02X303195Y105985I-987J-996D01*
G03X303177Y106564I-285J281D01*
G02X305191Y106575I1001J1120D01*
G37*
G36*
G01X253358Y106576D02*
G03X253345Y106014I278J-288D01*
G02X251297Y106004I-1019J-963D01*
G03X251279Y106565I-293J271D01*
G02X251230Y108696I1034J1090D01*
G03X251236Y109245I-288J278D01*
G02X251299Y111347I1103J1019D01*
G03X251314Y111909I-277J289D01*
G02X253364I1025J956D01*
G03X253379Y111347I292J-273D01*
G02X253422Y109223I-1040J-1083D01*
G03X253416Y108674I288J-278D01*
G02X253358Y106576I-1103J-1019D01*
G37*
G36*
G01X290169D02*
G03X290156Y106014I278J-288D01*
G02X288108Y106004I-1019J-963D01*
G03X288090Y106565I-293J271D01*
G02X288041Y108696I1034J1090D01*
G03X288047Y109245I-288J278D01*
G02X288110Y111347I1103J1019D01*
G03X288125Y111909I-277J289D01*
G02X290175I1025J956D01*
G03X290190Y111347I292J-273D01*
G02X290233Y109223I-1040J-1083D01*
G03X290227Y108674I288J-278D01*
G02X290169Y106576I-1103J-1019D01*
G37*
G36*
G01X507689D02*
G03X507676Y106014I278J-288D01*
G02X505628Y106004I-1019J-963D01*
G03X505610Y106565I-293J271D01*
G02X505561Y108696I1034J1090D01*
G03X505567Y109245I-288J278D01*
G02X505630Y111347I1103J1019D01*
G03X505645Y111909I-277J289D01*
G02X507695I1025J956D01*
G03X507710Y111347I292J-273D01*
G02X507753Y109223I-1040J-1083D01*
G03X507747Y108674I288J-278D01*
G02X507689Y106576I-1103J-1019D01*
G37*
G36*
G01X544500D02*
G03X544487Y106014I278J-288D01*
G02X542439Y106004I-1019J-963D01*
G03X542421Y106565I-293J271D01*
G02X542372Y108696I1034J1090D01*
G03X542378Y109245I-288J278D01*
G02X542441Y111347I1103J1019D01*
G03X542456Y111909I-277J289D01*
G02X544506I1025J956D01*
G03X544521Y111347I292J-273D01*
G02X544564Y109223I-1040J-1083D01*
G03X544558Y108674I288J-278D01*
G02X544500Y106576I-1103J-1019D01*
G37*
G36*
G01X248280Y106782D02*
G03X248264Y106221I277J-289D01*
G02X246214I-1025J-956D01*
G03X246198Y106782I-293J272D01*
G02X246151Y108900I1041J1083D01*
G03X246145Y109457I-290J275D01*
G02X246172Y111597I1068J1057D01*
G03X246188Y112158I-277J289D01*
G02X248238I1025J956D01*
G03X248254Y111597I293J-272D01*
G02X248301Y109479I-1041J-1083D01*
G03X248307Y108922I290J-275D01*
G02X248280Y106782I-1068J-1057D01*
G37*
G36*
G01X285091D02*
G03X285075Y106221I277J-289D01*
G02X283025I-1025J-956D01*
G03X283009Y106782I-293J272D01*
G02X282962Y108900I1041J1083D01*
G03X282956Y109457I-290J275D01*
G02X282983Y111597I1068J1057D01*
G03X282999Y112158I-277J289D01*
G02X285049I1025J956D01*
G03X285065Y111597I293J-272D01*
G02X285112Y109479I-1041J-1083D01*
G03X285118Y108922I290J-275D01*
G02X285091Y106782I-1068J-1057D01*
G37*
G36*
G01X502611D02*
G03X502595Y106221I277J-289D01*
G02X500545I-1025J-956D01*
G03X500529Y106782I-293J272D01*
G02X500482Y108900I1041J1083D01*
G03X500476Y109457I-290J275D01*
G02X500503Y111597I1068J1057D01*
G03X500519Y112158I-277J289D01*
G02X502569I1025J956D01*
G03X502585Y111597I293J-272D01*
G02X502632Y109479I-1041J-1083D01*
G03X502638Y108922I290J-275D01*
G02X502611Y106782I-1068J-1057D01*
G37*
G36*
G01X539422D02*
G03X539406Y106221I277J-289D01*
G02X537356I-1025J-956D01*
G03X537340Y106782I-293J272D01*
G02X537293Y108900I1041J1083D01*
G03X537287Y109457I-290J275D01*
G02X537314Y111597I1068J1057D01*
G03X537330Y112158I-277J289D01*
G02X539380I1025J956D01*
G03X539396Y111597I293J-272D01*
G02X539443Y109479I-1041J-1083D01*
G03X539449Y108922I290J-275D01*
G02X539422Y106782I-1068J-1057D01*
G37*
G36*
G01X244417Y108578D02*
G03X244433Y108017I293J-272D01*
G02X242351I-1041J-1083D01*
G03X242367Y108578I-277J289D01*
G02X244417I1025J956D01*
G37*
G36*
G01X281228D02*
G03X281244Y108017I293J-272D01*
G02X279162I-1041J-1083D01*
G03X279178Y108578I-277J289D01*
G02X281228I1025J956D01*
G37*
G36*
G01X492455Y108608D02*
G03X492471Y108047I293J-272D01*
G02X490389I-1041J-1083D01*
G03X490405Y108608I-277J289D01*
G02X492455I1025J956D01*
G37*
G36*
G01X498748D02*
G03X498764Y108047I293J-272D01*
G02X496682I-1041J-1083D01*
G03X496698Y108608I-277J289D01*
G02X498748I1025J956D01*
G37*
G36*
G01X515845D02*
G03X515861Y108047I293J-272D01*
G02X513779I-1041J-1083D01*
G03X513795Y108608I-277J289D01*
G02X515845I1025J956D01*
G37*
G36*
G01X522138D02*
G03X522154Y108047I293J-272D01*
G02X520072I-1041J-1083D01*
G03X520088Y108608I-277J289D01*
G02X522138I1025J956D01*
G37*
G36*
G01X535559D02*
G03X535575Y108047I293J-272D01*
G02X533493I-1041J-1083D01*
G03X533509Y108608I-277J289D01*
G02X535559I1025J956D01*
G37*
G36*
G01X238092Y108948D02*
G03X238119Y108387I298J-267D01*
G02X236038Y108347I-1020J-1103D01*
G03X236042Y108908I-283J283D01*
G02X238092Y108948I1006J976D01*
G37*
G36*
G01X261810Y108987D02*
G03X261824Y108404I281J-285D01*
G02X259824I-1000J-1120D01*
G03X259838Y108987I-267J298D01*
G02X261810I986J997D01*
G37*
G36*
G01X268503D02*
G03X268517Y108404I281J-285D01*
G02X266517I-1000J-1120D01*
G03X266531Y108987I-267J298D01*
G02X268503I986J997D01*
G37*
G36*
G01X274903Y108948D02*
G03X274930Y108387I298J-267D01*
G02X272849Y108347I-1020J-1103D01*
G03X272853Y108908I-283J283D01*
G02X274903Y108948I1006J976D01*
G37*
G36*
G01X529234Y108978D02*
G03X529261Y108417I298J-267D01*
G02X527180Y108377I-1020J-1103D01*
G03X527184Y108938I-283J283D01*
G02X529234Y108978I1006J976D01*
G37*
G36*
G01X552952Y109017D02*
G03X552966Y108434I281J-285D01*
G02X550966I-1000J-1120D01*
G03X550980Y109017I-267J298D01*
G02X552952I986J997D01*
G37*
G36*
G01X559645D02*
G03X559659Y108434I281J-285D01*
G02X557659I-1000J-1120D01*
G03X557673Y109017I-267J298D01*
G02X559645I986J997D01*
G37*
G36*
G01X614990Y109822D02*
G03X615527Y109612I369J153D01*
G02X614849Y107736I588J-1273D01*
G03X614302Y107918I-361J-172D01*
G02X614990Y109822I-700J1329D01*
G37*
G36*
G01X1597943Y109433D02*
G03X1597480Y109141I-76J-393D01*
G02X1594921Y109551I-1260J329D01*
G03X1594506Y109976I-399J25D01*
G02X1595845Y111217I-54J1401D01*
G03X1596237Y110772I397J-45D01*
G02X1596467Y110748I-20J-1302D01*
G03X1596930Y111040I76J393D01*
G02X1599047Y111691I1260J-329D01*
G03X1599587Y111704I263J301D01*
G02X1599633Y109786I903J-938D01*
G03X1599093Y109773I-263J-301D01*
G02X1597943Y109433I-903J938D01*
G37*
G36*
G01X302014Y111340D02*
G03X302027Y110779I291J-274D01*
G02X299945Y110787I-1045J-1079D01*
G03X299963Y111348I-276J290D01*
G02X302014Y111340I1029J952D01*
G37*
G36*
G01X1514846Y115137D02*
G03X1514833Y114509I241J-319D01*
G02X1512445Y112903I-954J-1160D01*
G03X1511968Y113173I-382J-119D01*
G02X1511938Y115904I-333J1362D01*
G03X1512424Y116305I86J391D01*
G01Y119436D01*
G03X1511937Y119826I-400J-1D01*
G02X1512912Y121773I-303J1369D01*
G03X1513414Y121562I364J164D01*
G02X1515446Y120153I521J-1419D01*
G01Y116258D01*
X1515437Y116174D01*
G02X1514846Y115137I-1502J169D01*
G37*
G36*
G01X660254Y114819D02*
G03X659685Y114699I-228J-329D01*
G02X659289Y116584I-1195J733D01*
G03X659858Y116704I228J329D01*
G02X660254Y114819I1195J-733D01*
G37*
G36*
G01X1483594Y117861D02*
G03X1483838Y117328I370J-153D01*
G02X1482010Y116548I-472J-1426D01*
G03X1481793Y117093I-361J172D01*
G02X1481750Y119690I507J1307D01*
G03X1481966Y120202I-157J368D01*
G02X1483877Y119334I1400J544D01*
G03X1483633Y118834I136J-376D01*
G02X1483594Y117861I-1333J-434D01*
G37*
G36*
G01X1474138Y119918D02*
G03X1474146Y119335I278J-288D01*
G02X1472177Y119259I-946J-1035D01*
G03X1472140Y119841I-292J274D01*
G02X1471900Y121908I956J1158D01*
G03X1471785Y122494I-319J242D01*
G02X1473656Y122906I715J1206D01*
G03X1473799Y122327I330J-226D01*
G02X1474138Y119918I-703J-1327D01*
G37*
G36*
G01X1543619Y120382D02*
G03X1543451Y119856I192J-351D01*
G02X1541381Y120518I-1351J-656D01*
G03X1541549Y121044I-192J351D01*
G02X1543619Y120382I1351J656D01*
G37*
G36*
G01X645317Y124397D02*
G03X645034Y123914I105J-386D01*
G02X642303Y123865I-1360J-341D01*
G03X641920Y124348I-391J83D01*
G02X643117Y126527I30J1402D01*
G03X643783I333J222D01*
G02X645317Y124397I1167J-777D01*
G37*
G36*
G01X1513090Y127819D02*
G03X1513693Y127719I344J205D01*
G02X1513430Y125878I907J-1069D01*
G03X1512823Y125951I-334J-220D01*
G02X1513090Y127819I-1023J1099D01*
G37*
G36*
G01X683927Y126075D02*
G03X683373I-277J-288D01*
G02X681056Y126686I-973J1010D01*
G03X680501Y126933I-383J-114D01*
G02X681244Y128599I-601J1267D01*
G03X681799Y128352I383J114D01*
G02X683373Y128095I601J-1267D01*
G03X683927I277J288D01*
G02Y126075I973J-1010D01*
G37*
G36*
G01X1595158Y129073D02*
G03X1595550Y128680I400J7D01*
G02X1594120Y127253I-28J-1402D01*
G03X1593728Y127646I-400J-7D01*
G02X1595158Y129073I28J1402D01*
G37*
G36*
G01X625831Y129840D02*
G03X626364Y129595I380J125D01*
G02X625569Y127860I536J-1295D01*
G03X625036Y128105I-380J-125D01*
G02X625831Y129840I-536J1295D01*
G37*
G36*
G01X1469646Y130132D02*
G03X1469667Y129543I281J-285D01*
G02X1467721Y129425I-912J-1065D01*
G03X1467671Y130012I-295J271D01*
G02X1469646Y130132I919J1188D01*
G37*
G36*
G01X1580430Y130126D02*
G03X1580434Y129600I303J-261D01*
G02X1578170Y129582I-1124J-996D01*
G03X1578166Y130108I-303J261D01*
G02X1580430Y130126I1124J996D01*
G37*
G36*
G01X1287527Y130990D02*
G03X1286973I-277J-288D01*
G02X1284990Y132973I-973J1010D01*
G03Y133527I-288J277D01*
G02Y135473I1010J973D01*
G03Y136027I-288J277D01*
G02Y137973I1010J973D01*
G03Y138527I-288J277D01*
G02X1286973Y140510I1010J973D01*
G03X1287527I277J288D01*
G02X1289510Y138527I973J-1010D01*
G03Y137973I288J-277D01*
G02Y136027I-1010J-973D01*
G03Y135473I288J-277D01*
G02Y133527I-1010J-973D01*
G03Y132973I288J-277D01*
G02X1287527Y130990I-1010J-973D01*
G37*
G36*
G01X1324841Y132400D02*
G03X1324211I-315J-246D01*
G02Y134246I-1185J923D01*
G03X1324841I315J246D01*
G02Y132400I1185J-923D01*
G37*
G36*
G01X1513478Y133014D02*
G03X1512879Y132903I-252J-310D01*
G02X1512497Y134731I-1215J700D01*
G03X1513090Y134869I238J321D01*
G02X1513478Y133014I1335J-689D01*
G37*
G36*
G01X1568936Y138448D02*
G03X1568933Y137833I254J-309D01*
G02X1567013Y137841I-965J-1151D01*
G03X1567016Y138456I-254J309D01*
G02X1568936Y138448I965J1151D01*
G37*
G36*
G01X1514293Y140037D02*
G03X1514607Y139471I363J-169D01*
G02X1513143Y137197I-182J-1491D01*
G03X1512562Y137309I-341J-208D01*
G02X1511329Y139975I-902J1201D01*
G03X1511636Y140424I-89J390D01*
G02X1514293Y140037I1387J206D01*
G37*
G36*
G01X1452399Y140490D02*
G03X1452493Y139950I334J-220D01*
G02X1450385Y139647I-903J-1200D01*
G03X1450322Y140191I-321J238D01*
G02X1450207Y142221I906J1070D01*
G03X1450200Y142776I-292J274D01*
G02X1450259Y144802I998J985D01*
G03X1450267Y145389I-268J297D01*
G02X1450239Y147394I966J1016D01*
G03X1450248Y147949I-284J282D01*
G02X1452267Y147916I1025J956D01*
G03X1452258Y147361I284J-282D01*
G02X1452172Y145364I-1025J-956D01*
G03X1452164Y144777I268J-297D01*
G02X1452219Y142801I-966J-1016D01*
G03X1452226Y142246I292J-274D01*
G02X1452399Y140490I-998J-985D01*
G37*
G36*
G01X1240948Y143581D02*
G03X1240950Y142954I249J-313D01*
G02X1239084Y142946I-928J-1181D01*
G03X1239082Y143573I-249J313D01*
G02X1240948Y143581I928J1181D01*
G37*
G36*
G01X1533362Y146400D02*
G03X1533559Y145879I367J-159D01*
G02X1531546Y145118I-636J-1361D01*
G03X1531349Y145639I-367J159D01*
G02X1533362Y146400I636J1361D01*
G37*
G36*
G01X1490726Y145108D02*
G03X1490285Y144772I-46J-397D01*
G02X1488974Y146492I-1485J228D01*
G03X1489415Y146828I46J397D01*
G02X1490726Y145108I1485J-228D01*
G37*
G36*
G01X1497090Y149755D02*
G03X1497153Y149233I331J-225D01*
G02X1494908Y148960I-1003J-1118D01*
G03X1494845Y149482I-331J225D01*
G02X1497090Y149755I1003J1118D01*
G37*
G36*
G01X1575096Y151073D02*
G03Y150527I292J-273D01*
G02X1572904I-1096J-1027D01*
G03Y151073I-292J273D01*
G02X1575096I1096J1027D01*
G37*
G36*
G01X1563010Y162532D02*
G03X1563039Y161911I266J-299D01*
G02X1561202Y161865I-889J-1211D01*
G03X1561201Y162487I-252J311D01*
G02X1563010Y162532I878J1093D01*
G37*
G36*
G01X1596648Y171344D02*
G03X1596036I-306J-258D01*
G02Y173024I-994J840D01*
G03X1596648I306J258D01*
G02Y171344I994J-840D01*
G37*
G36*
G01X1614863Y174222D02*
G03X1615392Y173999I373J145D01*
G02X1614687Y172328I508J-1199D01*
G03X1614158Y172551I-373J-145D01*
G02X1613179Y172536I-508J1199D01*
G03X1612674Y172336I-144J-373D01*
G02X1610429Y172159I-1174J564D01*
G03X1609894Y172274I-329J-228D01*
G02X1610293Y174130I-672J1115D01*
G03X1610828Y174015I329J228D01*
G02X1611971Y174114I672J-1115D01*
G03X1612476Y174314I144J373D01*
G02X1614863Y174222I1174J-564D01*
G37*
G36*
G01X1615377Y178062D02*
G03X1615891Y177756I393J75D01*
G02X1615021Y176207I395J-1241D01*
G03X1614492Y176487I-389J-94D01*
G02X1615377Y178062I-492J1313D01*
G37*
G36*
G01X1656005Y183496D02*
G03X1656044Y182887I277J-288D01*
G02X1654235Y182770I-835J-1126D01*
G03X1654196Y183379I-277J288D01*
G02X1656005Y183496I835J1126D01*
G37*
G36*
G01X1626926Y184554D02*
G03X1627326Y184161I400J7D01*
G02X1625924Y182736I0J-1402D01*
G03X1625524Y183129I-400J-7D01*
G02X1626926Y184554I0J1402D01*
G37*
G36*
G01X1636197Y184326D02*
G03X1636141Y183739I241J-319D01*
G02X1634254Y183918I-1041J-939D01*
G03X1634310Y184505I-241J319D01*
G02X1636197Y184326I1041J939D01*
G37*
G36*
G01X1609625Y183827D02*
G03X1609071Y183803I-265J-300D01*
G02X1608985Y185821I-1015J968D01*
G03X1609539Y185845I265J300D01*
G02X1611497Y185914I1014J-968D01*
G03X1612052Y185930I269J296D01*
G02X1614042Y185943I1001J-981D01*
G03X1614597Y185934I282J283D01*
G02X1614564Y183914I956J-1026D01*
G03X1614009Y183923I-282J-283D01*
G02X1612110Y183912I-955J1026D01*
G03X1611555Y183896I-269J-296D01*
G02X1609625Y183827I-1001J981D01*
G37*
G36*
G01X1621217Y184110D02*
G03X1620607Y184084I-294J-271D01*
G02X1620531Y185894I-1107J860D01*
G03X1621141Y185920I294J271D01*
G02X1621217Y184110I1107J-860D01*
G37*
G36*
G01X98966Y184654D02*
G03X98434I-266J-298D01*
G02X96689Y186844I-934J1046D01*
G03X96725Y187467I-231J326D01*
G02X98871Y189561I1005J1117D01*
G03X99469Y189550I304J260D01*
G02X100761Y187223I1031J-950D01*
G03X100687Y186861I38J-196D01*
G02X100873Y186710I-788J-1160D01*
G03X101427I277J288D01*
G02X103334Y186746I973J-1010D01*
G03X103866I266J298D01*
G02Y184654I934J-1046D01*
G03X103334I-266J-298D01*
G02X101427Y184690I-934J1046D01*
G03X100873I-277J-288D01*
G02X98966Y184654I-973J1010D01*
G37*
G36*
G01X1708794Y193293D02*
G02X1712894Y191735I3218J2294D01*
G02X1708794Y193293I-882J3852D01*
G37*
G36*
G01X89730Y210873D02*
G03X89409Y210404I72J-393D01*
G02X85674Y210400I-1867J-362D01*
G03X85259Y210875I-393J76D01*
G02X83317Y213261I-103J1899D01*
G03X83006Y213756I-386J102D01*
G02X85066Y216477I360J1868D01*
G03X85770Y216456I358J179D01*
G02X89222Y214908I1646J-953D01*
G03X89410Y214646I190J-62D01*
G02X89572Y214637I-24J-1902D01*
G03X89785Y214886I19J199D01*
G02X91659Y213462I1841J478D01*
G03X91270Y213007I7J-400D01*
G02X89730Y210873I-1884J-263D01*
G37*
G36*
G01X1612802Y215167D02*
G03Y214590I277J-289D01*
G02X1610720I-1041J-1083D01*
G03Y215167I-277J288D01*
G02X1612802I1041J1083D01*
G37*
G36*
G01X1594029Y216794D02*
G03X1594046Y216226I290J-276D01*
G02X1591527Y215292I-1026J-1097D01*
G03X1590995Y215712I-398J43D01*
G02X1590941Y218372I-470J1321D01*
G03X1591421Y218583I118J382D01*
G02X1594029Y216794I1449J-683D01*
G37*
G36*
G01X1628596Y216742D02*
G03X1628021Y216738I-286J-280D01*
G02X1628059Y218771I-1086J1037D01*
G03X1628633Y218745I300J265D01*
G02X1628596Y216742I962J-1020D01*
G37*
G36*
G01X1622290Y224916D02*
G03Y224386I300J-265D01*
G02X1620038I-1126J-994D01*
G03Y224916I-300J265D01*
G02X1622290I1126J994D01*
G37*
G36*
G01X1627010Y226336D02*
G03X1627549Y226367I253J310D01*
G02X1627608Y224212I1075J-1049D01*
G03X1627068Y224213I-271J-295D01*
G02X1627010Y226336I-944J1037D01*
G37*
G36*
G01X1597653Y247276D02*
G03X1598245Y247267I300J264D01*
G02X1598217Y245384I1025J-957D01*
G03X1597625Y245393I-300J-264D01*
G02X1597653Y247276I-1025J957D01*
G37*
G36*
G01X1621207Y256511D02*
G03X1621209Y255897I257J-306D01*
G02X1619283Y255890I-959J-1156D01*
G03X1619281Y256504I-257J306D01*
G02X1621207Y256511I959J1156D01*
G37*
G36*
G01X1625181Y272297D02*
G03X1624583Y272290I-296J-269D01*
G02X1624557Y274285I-1136J983D01*
G03X1625155Y274292I296J269D01*
G02X1625181Y272297I1136J-983D01*
G37*
G36*
G01X69327Y282696D02*
G03X69873I273J292D01*
G02Y280504I1027J-1096D01*
G03X69327I-273J-292D01*
G02Y282696I-1027J1096D01*
G37*
G36*
G01X1572936Y283783D02*
G03X1572398Y283737I-244J-317D01*
G02X1570684Y286128I-1105J1018D01*
G03X1570903Y286613I-163J365D01*
G02X1573802Y286738I1433J450D01*
G03X1574103Y286262I391J-86D01*
G02X1572936Y283783I-313J-1367D01*
G37*
G36*
G01X1580173Y283753D02*
G03X1579634Y283732I-258J-306D01*
G02X1579611Y285888I-1057J1067D01*
G03X1580151Y285878I275J290D01*
G02X1580173Y283753I926J-1053D01*
G37*
G36*
G01X1548006Y287663D02*
G03X1548358Y287223I398J-43D01*
G02X1546805Y285979I-159J-1393D01*
G03X1546453Y286419I-398J43D01*
G02X1548006Y287663I159J1393D01*
G37*
G36*
G01X1534897Y287640D02*
G03X1534898Y287072I282J-284D01*
G02X1532874Y287013I-984J-999D01*
G03X1532843Y287581I-296J269D01*
G02X1534897Y287640I996J1125D01*
G37*
G36*
G01X1579694Y292517D02*
G03X1579730Y291960I304J-260D01*
G02X1577726Y291833I-940J-1040D01*
G03X1577690Y292390I-304J260D01*
G02X1579694Y292517I940J1040D01*
G37*
G36*
G01X1527833Y294544D02*
G03X1527887Y293999I317J-244D01*
G02X1525765Y293849I-986J-1133D01*
G03X1525742Y294397I-302J262D01*
G02X1527833Y294544I980J1003D01*
G37*
G36*
G01X1513194Y294288D02*
G03X1513757Y294274I289J277D01*
G02X1513710Y292286I965J-1017D01*
G03X1513147Y292300I-289J-277D01*
G02X1513194Y294288I-965J1017D01*
G37*
G36*
G01X1584611Y302109D02*
G03Y301571I296J-269D01*
G02X1582389I-1111J-1011D01*
G03Y302109I-296J269D01*
G02X1584611I1111J1011D01*
G37*
G36*
G01X1566255Y302632D02*
G03X1566257Y302043I272J-294D01*
G02X1564224Y302036I-1013J-1109D01*
G03X1564222Y302625I-272J294D01*
G02X1566255Y302632I1013J1109D01*
G37*
G36*
G01X1537484Y305414D02*
G03X1537946Y305119I388J98D01*
G02X1536868Y303322I260J-1378D01*
G03X1536390Y303590I-381J-120D01*
G02X1537484Y305414I-363J1458D01*
G37*
G36*
G01X69730Y337488D02*
G03X69590Y336919I195J-350D01*
G02X67676Y337339I-1172J-769D01*
G03X67787Y337914I-212J339D01*
G02X70185Y339723I1213J886D01*
G03X70815I315J246D01*
G02X73087Y339836I1185J-923D01*
G03X73676Y339847I289J276D01*
G02X73713Y337814I1124J-996D01*
G03X73124Y337803I-289J-276D01*
G02X70815Y337877I-1124J997D01*
G03X70185I-315J-246D01*
G02X69730Y337488I-1184J924D01*
G37*
G36*
G01X61723Y381799D02*
G03X61642Y381177I206J-343D01*
G02X59846Y381450I-1078J-1046D01*
G03X59953Y382067I-191J351D01*
G02X61723Y381799I1047J933D01*
G37*
G36*
G01X702089Y383198D02*
G03X701524Y383102I-236J-323D01*
G02X699040Y385110I-1320J907D01*
G03X699055Y385643I-291J275D01*
G02X699427Y387896I1149J967D01*
G03X699467Y388553I-207J342D01*
G02X699381Y390849I924J1184D01*
G03X699360Y391458I-269J296D01*
G02X699373Y393826I931J1179D01*
G03X699408Y394429I-244J317D01*
G02X701347Y396714I1050J1075D01*
G03X701917Y396815I237J322D01*
G02X704303Y396971I1252J-829D01*
G03X704933Y397004I302J262D01*
G02X707207Y397224I1231J-861D01*
G03X707783Y397244I278J287D01*
G02X710027Y397383I1193J-1070D01*
G03X710546Y397378I262J302D01*
G02X712636Y394950I1028J-1229D01*
G03Y394350I265J-300D01*
G02Y391950I-1061J-1200D01*
G03Y391350I265J-300D01*
G02X712388Y388770I-1061J-1200D01*
G03X712308Y388143I203J-345D01*
G02X712356Y385932I-1135J-1131D01*
G03Y385392I295J-270D01*
G02X709958Y383268I-1183J-1080D01*
G03X709385Y383302I-303J-261D01*
G02X707307Y383354I-1012J1110D01*
G03X706739I-284J-282D01*
G02X704607I-1066J1058D01*
G03X704039I-284J-282D01*
G02X702089Y383198I-1066J1058D01*
G37*
G36*
G01X680410Y387607D02*
G03X680439Y386998I273J-292D01*
G02X678498Y386906I-916J-1190D01*
G03X678469Y387515I-273J292D01*
G02X680410Y387607I916J1190D01*
G37*
G36*
G01X66806Y392960D02*
G02X66435Y390673I594J-1270D01*
G03X65860Y390647I-275J-291D01*
G02X63214Y391645I-1135J998D01*
G01Y396645D01*
G02X65481Y397954I1511J0D01*
G03X66025Y398096I200J346D01*
G02X66768Y396056I1205J-716D01*
G03X66236Y395679I-132J-378D01*
G01Y393322D01*
G03X66806Y392960I400J0D01*
G37*
G36*
G01X77567Y398451D02*
G03X78113I273J292D01*
G02X79918Y398640I1027J-1096D01*
G03X80498Y398839I207J342D01*
G02X81122Y397015I1402J-539D01*
G03X80542Y396816I-207J-342D01*
G02X78113Y396259I-1402J539D01*
G03X77567I-273J-292D01*
G02Y398451I-1027J1096D01*
G37*
G36*
G01X66839Y403667D02*
G03X67332Y403390I385J108D01*
G02X66385Y401582I378J-1350D01*
G03X65877Y401829I-378J-131D01*
G02X64311Y402193I-493J1429D01*
G01X61973Y404550D01*
X61972Y404551D01*
G02X62537Y407067I1052J1085D01*
G03X62763Y407630I-129J379D01*
G02X64573Y406993I1244J646D01*
G03X64450Y406345I161J-366D01*
G01X65153Y405638D01*
X66457Y404323D01*
G02X66839Y403667I-1073J-1064D01*
G37*
G36*
G01X79385Y408231D02*
G03X78902Y407832I-83J-391D01*
G02X77715Y409269I-1502J-32D01*
G03X78198Y409668I83J391D01*
G02X79672Y411202I1502J32D01*
G03X80050Y411706I-8J400D01*
G02X81528Y410598I1450J394D01*
G03X81150Y410094I8J-400D01*
G02X79385Y408231I-1450J-394D01*
G37*
G36*
G01X76103Y422436D02*
G03X76513Y422891I14J400D01*
G02X78156Y424594I1487J209D01*
G03X78598Y424993I42J398D01*
G02X79767Y426465I1502J7D01*
G03X80061Y426969I-89J390D01*
G02X81833Y425935I1439J431D01*
G03X81539Y425431I89J-390D01*
G02X79944Y423506I-1439J-431D01*
G03X79502Y423107I-42J-398D01*
G02X77949Y421599I-1502J-7D01*
G03X77539Y421144I-14J-400D01*
G02X76103Y422436I-1487J-209D01*
G37*
G36*
G01X747092Y431907D02*
G03X747088Y431287I251J-312D01*
G02X745189Y431300I-957J-1157D01*
G03X745193Y431920I-251J312D01*
G02X747092Y431907I957J1157D01*
G37*
G36*
G01X86857Y434877D02*
G03X86415Y434478I-42J-398D01*
G02X85069Y435965I-1502J-7D01*
G03X85511Y436364I42J398D01*
G02X86857Y434877I1502J7D01*
G37*
G36*
G01X777237Y435326D02*
G03X776669Y435167I-211J-339D01*
G02X776159Y436989I-1252J632D01*
G03X776727Y437148I211J339D01*
G02X777237Y435326I1252J-632D01*
G37*
G36*
G01X750525Y439327D02*
G03X749900Y438975I-226J-330D01*
G02X747354Y439707I-1400J-75D01*
G03X747221Y440287I-327J230D01*
G02X748465Y443011I729J1313D01*
G03X748991Y443294I137J376D01*
G02X750525Y439327I3650J-869D01*
G37*
G36*
G01X575657Y460293D02*
G03X575269Y459895I12J-400D01*
G02X573824Y461304I-1402J8D01*
G03X574212Y461702I-12J400D01*
G02X575657Y460293I1402J-8D01*
G37*
G36*
G01X619041Y464629D02*
G03X618801Y465180I-362J170D01*
G02X618314Y467777I459J1430D01*
G03X618342Y468374I-251J311D01*
G02X620336Y468283I1048J1076D01*
G03X620308Y467686I251J-311D01*
G02X620619Y465971I-1048J-1076D01*
G03X620859Y465420I362J-170D01*
G02X619041Y464629I-459J-1430D01*
G37*
G36*
G01X582851Y467547D02*
G03X582433Y467160I-18J-400D01*
G02X581093Y468603I-1401J42D01*
G03X581511Y468990I18J400D01*
G02X582851Y467547I1401J-42D01*
G37*
G36*
G01X1257966Y468047D02*
G03X1257526Y467687I-42J-398D01*
G02X1256204Y469220I-1396J133D01*
G03X1256625Y469603I21J399D01*
G02X1257966Y468047I1501J-63D01*
G37*
G36*
G01X1327785Y470347D02*
G03X1328334Y470375I260J304D01*
G02X1328382Y468250I1085J-1039D01*
G03X1327833Y468254I-277J-289D01*
G02X1327785Y470347I-956J1025D01*
G37*
G36*
G01X607651Y472507D02*
G03X607026Y472490I-306J-257D01*
G02X604694Y474381I-1199J905D01*
G03Y474907I-302J263D01*
G02X606958I1132J987D01*
G03Y474381I302J-263D01*
G02X606975Y474362I-1111J-1011D01*
G03X607600Y474379I306J257D01*
G02X607651Y472507I1200J-904D01*
G37*
G36*
G01X13539Y474346D02*
G03X13007Y474329I-256J-307D01*
G02X12933Y476571I-1035J1088D01*
G03X13465Y476588I256J307D01*
G02X15487Y476632I1035J-1088D01*
G03X16013I263J302D01*
G02Y474368I987J-1132D01*
G03X15487I-263J-302D01*
G02X13539Y474346I-987J1132D01*
G37*
G36*
G01X34223Y509289D02*
G03X34058Y509518I-197J32D01*
G02X33490Y509735I241J1482D01*
G03X32964Y509651I-216J-337D01*
G02X32610Y511865I-1164J949D01*
G03X33136Y511949I216J337D01*
G02X35288Y512131I1164J-949D01*
G03X35856Y512173I263J301D01*
G02X38495Y511340I1144J-973D01*
G03X38958Y510982I399J37D01*
G02X39428Y508015I241J-1483D01*
G03X39092Y507574I61J-395D01*
G02X36111Y507205I-1492J-174D01*
G03X35713Y507553I-397J-52D01*
G02X34223Y509289I-6J1502D01*
G37*
G36*
G01X1515250Y92707D02*
G02X1513910Y91081I44J-1401D01*
G03X1513496Y91416I-394J-64D01*
G02X1511829Y92785I-161J1504D01*
G01X1511819Y92784D01*
X1511496Y96414D01*
X1511506Y96415D01*
G02X1511539Y96887I1507J132D01*
G03X1511256Y97330I-395J59D01*
G02X1513038Y98469I395J1345D01*
G03X1513316Y98028I396J-59D01*
G02X1514519Y96682I-303J-1482D01*
G01X1514529Y96683D01*
X1514541Y96554D01*
X1514534D01*
X1514535Y96548D01*
X1514541D01*
X1514852Y93055D01*
X1514851Y93054D01*
X1514857Y92983D01*
G03X1515250Y92707I380J124D01*
G37*
G36*
G01X1684985Y192156D02*
G02X1685249Y190074I1198J-906D01*
G03X1684682Y190002I-248J-314D01*
G02X1684418Y192084I-1198J906D01*
G03X1684985Y192156I248J314D01*
G37*
G36*
G01X1559984Y361960D02*
G03X1560003Y361362I275J-291D01*
G02X1557931Y361341I-1024J-1232D01*
G03X1557939Y361939I-261J303D01*
G02X1557998Y364212I1011J1111D01*
G03X1558022Y364809I-254J309D01*
G02X1559936Y364777I974J1008D01*
G03X1559940Y364179I268J-297D01*
G02X1559984Y361960I-990J-1130D01*
G37*
G36*
G01X1928253Y529840D02*
G02Y535242I0J2701D01*
G01X1930653D01*
G02Y529840I0J-2701D01*
G01X1928253D01*
G37*
G36*
G01X1926853Y508500D02*
G02Y513904I0J2702D01*
G01X1932053D01*
G02Y508500I0J-2702D01*
G01X1926853D01*
G37*
G36*
G01X1884727Y529840D02*
G02Y535242I0J2701D01*
G01X1889927D01*
G02Y529840I0J-2701D01*
G01X1884727D01*
G37*
G36*
G01X1886127Y508500D02*
G02Y513904I0J2702D01*
G01X1888527D01*
G02Y508500I0J-2702D01*
G01X1886127D01*
G37*
G36*
G01X1777969Y620885D02*
G03X1778368Y620402I391J-83D01*
G02X1776931Y619215I32J-1502D01*
G03X1776532Y619698I-391J83D01*
G02X1777969Y620885I-32J1502D01*
G37*
G36*
G01X1591944Y619849D02*
G03X1592499Y619838I283J283D01*
G02X1592456Y617675I1020J-1102D01*
G03X1591901Y617686I-283J-283D01*
G02X1591944Y619849I-1020J1102D01*
G37*
G36*
G01X1602523Y617154D02*
G03X1601977I-273J-292D01*
G02Y619346I-1027J1096D01*
G03X1602523I273J292D01*
G02Y617154I1027J-1096D01*
G37*
G36*
G01X1472321Y617759D02*
G03X1471780Y617521I-162J-366D01*
G02X1468983Y617391I-1424J479D01*
G03X1468454Y617594I-366J-162D01*
G02X1466961Y617745I-616J1370D01*
G03X1466418Y617675I-234J-324D01*
G02X1466087Y619747I-1084J889D01*
G03X1466625Y619848I215J337D01*
G02X1469212Y619573I1214J-884D01*
G03X1469741Y619370I366J162D01*
G02X1470967Y619372I615J-1370D01*
G03X1471508Y619610I162J366D01*
G02X1474070Y620112I1424J-479D01*
G03X1474690Y620130I303J261D01*
G02X1476882Y620339I1193J-913D01*
G03X1477432Y620356I266J299D01*
G02X1477501Y618178I1068J-1056D01*
G03X1476951Y618161I-266J-299D01*
G02X1474745Y618236I-1068J1056D01*
G03X1474125Y618218I-303J-261D01*
G02X1472321Y617759I-1193J913D01*
G37*
G36*
G01X1962657Y618342D02*
G03X1962643Y617738I255J-308D01*
G02X1960757I-943J-1038D01*
G03X1960743Y618342I-269J296D01*
G02X1962657I957J1158D01*
G37*
G36*
G01X1931517Y617794D02*
G03Y617206I270J-294D01*
G02X1929483I-1017J-1106D01*
G03Y617794I-270J294D01*
G02X1931517I1017J1106D01*
G37*
G36*
G01X1375108Y616962D02*
G03X1375693Y616861I338J214D01*
G02X1375408Y614951I863J-1105D01*
G03X1374819Y615024I-327J-230D01*
G02X1375108Y616962I-981J1137D01*
G37*
G36*
G01X1515380Y611807D02*
G03X1514854I-263J-302D01*
G02X1512846Y611837I-987J1132D01*
G03X1512317Y611850I-272J-293D01*
G02X1512371Y614102I-967J1150D01*
G03X1512900Y614089I272J293D01*
G02X1514854Y614071I966J-1150D01*
G03X1515380I263J302D01*
G02Y611807I987J-1132D01*
G37*
G36*
G01X1479322Y612798D02*
G03X1479833Y612784I264J300D01*
G02X1479767Y610475I927J-1182D01*
G03X1479256Y610489I-264J-300D01*
G02X1477308Y610569I-927J1182D01*
G03X1476779Y610582I-272J-293D01*
G02X1476833Y612834I-967J1150D01*
G03X1477362Y612821I272J293D01*
G02X1479322Y612798I967J-1150D01*
G37*
G36*
G01X1535833Y611603D02*
G02X1534793Y609137I-905J-1071D01*
G02X1529389Y611608I-2523J1627D01*
G03X1529159Y612089I-384J112D01*
G02X1528864Y612257I541J1293D01*
G03X1528294Y612159I-238J-322D01*
G02X1528149Y614024I-1244J841D01*
G03X1528470Y614063I146J136D01*
G02X1528563Y614209I1227J-679D01*
G03X1528485Y614509I-161J118D01*
G02X1530356Y616335I582J1275D01*
G03X1530893Y616129I368J157D01*
G02X1534869Y614702I1267J-2721D01*
G02X1535992Y614238I79J-1400D01*
G03X1536605Y614259I298J267D01*
G02X1537141Y614678I1106J-862D01*
G03X1537356Y615176I-162J365D01*
G02X1540080Y615601I1323J465D01*
G03X1540526Y615192I400J-12D01*
G02X1539558Y612725I174J-1492D01*
G03X1538911Y612672I-304J-260D01*
G02X1536667Y612461I-1200J725D01*
G03X1536054Y612440I-298J-267D01*
G02X1535837Y612218I-1105J863D01*
G03X1535833Y611603I254J-309D01*
G37*
G36*
G01X1652380Y614210D02*
Y609115D01*
X1652371Y609031D01*
G02X1649358Y609200I-1502J169D01*
G01Y614201D01*
G02X1652380Y614210I1511J-1D01*
G37*
G36*
G01X1672742Y611631D02*
G03X1672054Y611661I-353J-188D01*
G02X1670566Y614749I-1676J1095D01*
G03X1671000Y615200I38J398D01*
G02X1675404Y616622I2331J312D01*
G01X1676872Y613881D01*
G03X1677560Y613851I353J188D01*
G02X1679424Y614749I1676J-1095D01*
G03X1679859Y615200I38J398D01*
G02X1684261Y616623I2330J312D01*
G01X1685730Y613881D01*
G03X1686418Y613851I353J188D01*
G02X1688541Y614707I1676J-1095D01*
G03X1689025Y615165I90J390D01*
G02X1690561Y613518I2023J346D01*
G03X1690072Y613067I-94J-388D01*
G02X1687906Y610763I-1978J-311D01*
G03X1687472Y610312I-37J-398D01*
G02X1683070Y608889I-2330J-312D01*
G01X1681600Y611632D01*
G03X1680913Y611662I-352J-189D01*
G02X1679048Y610763I-1677J1094D01*
G03X1678614Y610312I-38J-398D01*
G02X1674210Y608890I-2331J-312D01*
G01X1672742Y611631D01*
G37*
G36*
G01X1625498D02*
G03X1624810Y611661I-353J-188D01*
G02X1623322Y614749I-1676J1095D01*
G03X1623756Y615200I37J398D01*
G02X1628179Y616586I2331J311D01*
G01X1628180Y616585D01*
X1629628Y613881D01*
G03X1630316Y613851I353J188D01*
G02X1632180Y614749I1676J-1095D01*
G03X1632614Y615200I37J398D01*
G02X1637045Y616571I2331J312D01*
G01X1637046Y616569D01*
X1638486Y613881D01*
G03X1639174Y613851I353J188D01*
G02X1641297Y614707I1676J-1095D01*
G03X1641781Y615165I90J390D01*
G02X1643317Y613518I2023J346D01*
G03X1642828Y613067I-94J-388D01*
G02X1640663Y610763I-1978J-311D01*
G03X1640229Y610312I-37J-398D01*
G02X1635798Y608941I-2331J-312D01*
G01X1635797Y608943D01*
X1634356Y611632D01*
G03X1633669Y611662I-352J-189D01*
G02X1631804Y610763I-1677J1094D01*
G03X1631370Y610312I-37J-398D01*
G02X1626947Y608926I-2331J-311D01*
G01X1626946Y608927D01*
X1625498Y611631D01*
G37*
G36*
G01X1553606Y608496D02*
G03X1554131Y608390I321J238D01*
G02X1553694Y606204I769J-1290D01*
G03X1553169Y606310I-321J-238D01*
G02X1553606Y608496I-769J1290D01*
G37*
G36*
G01X1589031Y604486D02*
G03X1588477I-277J-288D01*
G02X1586494Y606469I-973J1010D01*
G03Y607023I-288J277D01*
G02X1588477Y609006I1010J973D01*
G03X1589031I277J288D01*
G02X1589159Y609114I966J-1016D01*
G03X1589240Y609671I-241J319D01*
G02X1591355Y609247I1290J949D01*
G03X1591215Y608702I206J-343D01*
G02X1591014Y607023I-1211J-707D01*
G03Y606469I288J-277D01*
G02X1589031Y604486I-1010J-973D01*
G37*
G36*
G01X1545196Y606629D02*
G03X1545556Y606208I399J-23D01*
G02X1543908Y604803I-149J-1495D01*
G03X1543548Y605224I-399J23D01*
G02X1542265Y606265I149J1495D01*
G03X1541732Y606513I-381J-122D01*
G02X1542594Y608357I-570J1390D01*
G03X1543127Y608109I381J122D01*
G02X1545196Y606629I570J-1390D01*
G37*
G36*
G01X1758595Y606373D02*
G03X1758873Y605817I364J-165D01*
G02X1757211Y605031I-323J-1467D01*
G03X1756958Y605598I-357J181D01*
G02X1758595Y606373I361J1355D01*
G37*
G36*
G01X1377032Y605669D02*
G03Y605143I302J-263D01*
G02X1374768I-1132J-987D01*
G03Y605669I-302J263D01*
G02X1374798Y607677I1132J987D01*
G03X1374811Y608206I-293J272D01*
G02X1377063Y608152I1150J967D01*
G03X1377050Y607623I293J-272D01*
G02X1377032Y605669I-1150J-966D01*
G37*
G36*
G01X1603405Y603012D02*
G03X1602884Y602671I-123J-381D01*
G02X1602083Y604082I-1395J141D01*
G03X1602367Y604285I85J181D01*
G02X1602358Y604450I1502J165D01*
G01Y608451D01*
G02X1602404Y608824I1512J3D01*
G03X1602046Y609322I-387J99D01*
G02X1603524Y610441I104J1398D01*
G03X1603906Y609961I392J-80D01*
G02X1605380Y608460I-37J-1511D01*
G01Y604365D01*
X1605371Y604281D01*
G02X1603405Y603012I-1502J169D01*
G37*
G36*
G01X1572237Y600367D02*
G03X1571718Y600360I-255J-308D01*
G02X1571683Y602796I-1058J1203D01*
G03X1572202Y602803I255J308D01*
G02X1572237Y600367I1058J-1203D01*
G37*
G36*
G01X1804772Y601902D02*
G03X1804178Y601662I-207J-342D01*
G02X1803850Y604145I-3193J841D01*
G03X1804486Y604068I347J199D01*
G02X1804772Y601902I1014J-968D01*
G37*
G36*
G01X1788425Y599446D02*
G03Y598845I263J-300D01*
G02X1786575I-925J-1054D01*
G03Y599446I-263J300D01*
G02X1788425I925J1054D01*
G37*
G36*
G01X1520505Y597038D02*
G03X1520268Y596884I-41J-196D01*
G02X1517342Y596839I-1468J316D01*
G03X1516921Y597142I-388J-96D01*
G02X1516432Y597183I-121J1497D01*
G03X1515948Y596901I-98J-388D01*
G02X1513027Y597008I-1448J399D01*
G03X1512792Y597166I-196J-38D01*
G02X1512319Y597148I-293J1473D01*
G03X1511888Y596866I-48J-397D01*
G02X1509463Y596168I-1438J434D01*
G03X1508937I-263J-302D01*
G02X1506895Y598369I-986J1133D01*
G03X1506912Y598920I-281J284D01*
G02X1508609Y601308I1119J1002D01*
G03X1509117Y601493I153J369D01*
G02X1511937Y600590I1333J-693D01*
G03X1512368Y600135I396J-56D01*
G02X1513973Y598931I132J-1496D01*
G03X1514208Y598773I196J38D01*
G02X1514868Y598756I292J-1473D01*
G03X1515352Y599038I98J388D01*
G02X1518258Y599000I1448J-399D01*
G03X1518679Y598697I388J96D01*
G02X1519108Y598670I121J-1497D01*
G03X1519345Y598824I41J196D01*
G02X1522265Y598892I1468J-316D01*
G03X1522510Y598751I193J52D01*
G02X1523086Y598790I388J-1451D01*
G03X1523310Y598964I25J199D01*
G02X1526268Y599095I1490J-187D01*
G03X1526720Y598784I391J84D01*
G02X1525482Y596983I230J-1484D01*
G03X1525030Y597294I-391J-84D01*
G02X1524614Y597288I-229J1484D01*
G03X1524390Y597114I-25J-199D01*
G02X1521448Y596916I-1490J186D01*
G03X1521203Y597057I-193J-52D01*
G02X1520505Y597038I-389J1451D01*
G37*
G36*
G01X1614804Y598842D02*
G03X1615081Y598349I385J-108D01*
G02X1613330Y597298I-381J-1349D01*
G03X1613025Y597774I-391J85D01*
G02X1611838Y599250I324J1476D01*
G01Y603251D01*
G02X1614860Y603260I1511J-1D01*
G01Y599165D01*
X1614851Y599081D01*
G02X1614804Y598842I-1502J171D01*
G37*
G36*
G01X1589280Y595798D02*
G03X1588727Y595792I-273J-293D01*
G02X1586676Y595749I-1048J1075D01*
G03X1586150Y595756I-267J-298D01*
G02X1586182Y598020I-971J1146D01*
G03X1586708Y598013I267J298D01*
G02X1588703Y597965I971J-1146D01*
G03X1589256Y597971I273J293D01*
G02X1589280Y595798I1048J-1075D01*
G37*
G36*
G01X1473925Y594900D02*
G03X1473399I-263J-302D01*
G02X1471191Y595158I-987J1132D01*
G03X1470622Y595242I-325J-233D01*
G02X1469098Y597585I-855J1111D01*
G03X1469083Y598295I-191J351D01*
G02X1470710Y600527I618J1259D01*
G03X1471296Y600537I288J277D01*
G02X1473399Y600664I1116J-1005D01*
G03X1473925I263J302D01*
G02X1476414Y599532I987J-1132D01*
G03X1476880Y599137I400J0D01*
G02X1478601Y597954I249J-1481D01*
G03X1479001Y597634I392J80D01*
G02X1479303Y597609I28J-1502D01*
G03X1479766Y597911I74J393D01*
G02X1482721Y597741I1463J-340D01*
G03X1482942Y597565I199J23D01*
G02X1483463Y597530I161J-1493D01*
G03X1483952Y597846I96J388D01*
G02X1486903Y597857I1477J-275D01*
G03X1487303Y597534I393J77D01*
G02X1487355I26J-1502D01*
G03X1487755Y597857I7J400D01*
G02X1490707Y597837I1474J-287D01*
G03X1491166Y597514I394J72D01*
G02X1489934Y595766I246J-1482D01*
G03X1489475Y596089I-394J-72D01*
G02X1489203Y596069I-246J1482D01*
G03X1488803Y595746I-7J-400D01*
G02X1485855I-1474J286D01*
G03X1485455Y596069I-393J-77D01*
G02X1485070Y596113I-23J1502D01*
G03X1484581Y595797I-96J-388D01*
G02X1481612Y595902I-1477J275D01*
G03X1481391Y596078I-199J-23D01*
G02X1480955Y596094I-164J1493D01*
G03X1480492Y595792I-74J-393D01*
G02X1477557Y595834I-1463J340D01*
G03X1477157Y596154I-392J-80D01*
G02X1476867Y596177I-27J1502D01*
G03X1476401Y595835I-69J-394D01*
G02X1473925Y594900I-1489J197D01*
G37*
G36*
G01X1938946Y596153D02*
G03X1938918Y595556I251J-311D01*
G02X1936924Y595647I-1048J-1076D01*
G03X1936952Y596244I-251J311D01*
G02X1938946Y596153I1048J1076D01*
G37*
G36*
G01X1672742Y596670D02*
G03X1672054Y596700I-353J-188D01*
G02X1670566Y599788I-1676J1095D01*
G03X1671000Y600239I38J398D01*
G02X1675404Y601661I2331J312D01*
G01X1676872Y598920D01*
G03X1677560Y598890I353J188D01*
G02X1679424Y599788I1676J-1095D01*
G03X1679859Y600239I38J398D01*
G02X1684261Y601662I2330J312D01*
G01X1685730Y598920D01*
G03X1686418Y598890I353J188D01*
G02X1688541Y599746I1676J-1095D01*
G03X1689025Y600204I90J390D01*
G02X1690561Y598557I2023J346D01*
G03X1690072Y598106I-94J-388D01*
G02X1687906Y595802I-1978J-311D01*
G03X1687472Y595351I-37J-398D01*
G02X1683070Y593928I-2330J-312D01*
G01X1681600Y596671D01*
G03X1680913Y596701I-352J-189D01*
G02X1679048Y595802I-1677J1094D01*
G03X1678614Y595351I-38J-398D01*
G02X1674210Y593929I-2331J-312D01*
G01X1672742Y596670D01*
G37*
G36*
G01X1629628Y598920D02*
G03X1630316Y598890I353J188D01*
G02X1632180Y599788I1676J-1095D01*
G03X1632614Y600239I37J398D01*
G02X1637045Y601610I2331J312D01*
G01X1637046Y601608D01*
X1638486Y598920D01*
G03X1639174Y598890I353J188D01*
G02X1641297Y599746I1676J-1095D01*
G03X1641781Y600204I90J390D01*
G02X1643317Y598557I2023J346D01*
G03X1642828Y598106I-94J-388D01*
G02X1640663Y595802I-1978J-311D01*
G03X1640229Y595351I-37J-398D01*
G02X1635798Y593980I-2331J-312D01*
G01X1635797Y593982D01*
X1634356Y596671D01*
G03X1633669Y596701I-352J-189D01*
G02X1631804Y595802I-1677J1094D01*
G03X1631370Y595351I-37J-398D01*
G02X1626947Y593965I-2331J-311D01*
G01X1626946Y593966D01*
X1625498Y596670D01*
G03X1624810Y596700I-353J-188D01*
G02X1623322Y599788I-1676J1095D01*
G03X1623756Y600239I37J398D01*
G02X1628179Y601625I2331J311D01*
G01X1628180Y601624D01*
X1629628Y598920D01*
G37*
G36*
G01X1801343Y595110D02*
G03X1801349Y594538I283J-283D01*
G02X1799387Y594518I-971J-1011D01*
G03X1799381Y595090I-283J283D01*
G02X1801343Y595110I971J1011D01*
G37*
G36*
G01X1711076Y594452D02*
G03X1711066Y593906I287J-278D01*
G02X1708874Y593948I-1116J-1006D01*
G03X1708884Y594494I-287J278D01*
G02X1711076Y594452I1116J1006D01*
G37*
G36*
G01X1719091Y593613D02*
G03X1719084Y593049I280J-286D01*
G02X1716954Y593073I-1077J-1047D01*
G03X1716961Y593637I-280J286D01*
G02X1716905Y595671I1076J1047D01*
G03Y596197I-302J263D01*
G02X1719169I1132J987D01*
G03Y595671I302J-263D01*
G02X1719091Y593613I-1132J-988D01*
G37*
G36*
G01X29158Y590493D02*
G03X28555Y590491I-301J-264D01*
G02X28549Y592333I-1060J918D01*
G03X29152Y592335I301J264D01*
G02X31092Y592509I1060J-918D01*
G03X31624Y592535I251J311D01*
G02X33538Y592588I985J-997D01*
G03X34088Y592606I265J299D01*
G02X34156Y590571I997J-985D01*
G03X33606Y590553I-265J-299D01*
G02X31729Y590446I-998J985D01*
G03X31197Y590420I-251J-311D01*
G02X29158Y590493I-985J997D01*
G37*
G36*
G01X1653605Y592919D02*
G03X1653632Y592348I293J-272D01*
G02X1651621Y592195I-932J-1048D01*
G03X1651561Y592764I-308J255D01*
G02X1650988Y593950I939J1185D01*
G01Y597951D01*
G02X1651672Y599215I1511J-1D01*
G03X1651729Y599838I-220J334D01*
G02X1653522Y599714I971J1012D01*
G03X1653493Y599089I234J-324D01*
G02X1654010Y597960I-994J-1138D01*
G01Y593865D01*
X1654001Y593781D01*
G02X1653605Y592919I-1502J168D01*
G37*
G36*
G01X1554589Y590129D02*
G03X1554011I-289J-277D01*
G02Y592071I-1011J971D01*
G03X1554589I289J277D01*
G02Y590129I1011J-971D01*
G37*
G36*
G01X1763216Y590944D02*
G03Y590666I144J-139D01*
G02X1760908I-1154J-1111D01*
G03Y590944I-144J139D01*
G02X1763216I1154J1111D01*
G37*
G36*
G01X1602489Y590528D02*
G03X1602511Y589939I281J-284D01*
G02X1600539Y589913I-971J-1146D01*
G03X1600546Y590503I-267J298D01*
G02X1601896Y592872I958J1023D01*
G03X1602408Y593256I112J384D01*
G01Y595556D01*
G03X1601844Y595921I-400J0D01*
G02X1602409Y598017I-574J1279D01*
G03X1602982Y597936I325J233D01*
G02X1605430Y596760I937J-1186D01*
G01Y592665D01*
X1605421Y592581D01*
G02X1603365Y591344I-1502J169D01*
G03X1602838Y591095I-146J-372D01*
G02X1602489Y590528I-1334J430D01*
G37*
G36*
G01X1379544Y591226D02*
G02X1384556Y591074I2556J1574D01*
G02X1379544Y591226I-2556J-1574D01*
G37*
G36*
G01X1544173Y584628D02*
G03X1543627I-273J-292D01*
G02Y586820I-1027J1096D01*
G03X1544173I273J292D01*
G02Y584628I1027J-1096D01*
G37*
G36*
G01X1421670Y583521D02*
G02X1419170I-1250J2729D01*
G02X1416467Y583623I-1250J2729D01*
G02X1412514Y584939I-1294J2709D01*
G02Y587725I159J1393D01*
G02X1416626Y588959I2659J-1393D01*
G02X1419170Y588979I1293J-2709D01*
G02X1421670I1250J-2729D01*
G02Y583521I1250J-2729D01*
G37*
G36*
G01X1815269Y582819D02*
G03X1814723Y582693I-209J-341D01*
G02X1814239Y584782I-1267J807D01*
G03X1814785Y584908I209J341D01*
G02X1815269Y582819I1267J-807D01*
G37*
G36*
G01X1462731Y582205D02*
G03X1462719Y581672I292J-273D01*
G02X1460629Y581719I-1066J-910D01*
G03X1460641Y582252I-292J273D01*
G02X1460730Y584168I1066J911D01*
G03X1460768Y584699I-278J287D01*
G02X1460853Y586512I1110J856D01*
G03X1460864Y587045I-293J273D01*
G02X1460928Y588936I1066J911D01*
G03X1460952Y589469I-286J280D01*
G02X1461043Y591341I1087J885D01*
G03X1461069Y591875I-284J281D01*
G02X1463151Y591774I1086J886D01*
G03X1463125Y591240I284J-281D01*
G02X1463041Y589374I-1086J-886D01*
G03X1463017Y588841I286J-280D01*
G02X1462955Y587000I-1087J-885D01*
G03X1462944Y586467I293J-273D01*
G02X1462855Y584550I-1066J-911D01*
G03X1462817Y584019I278J-287D01*
G02X1462731Y582205I-1110J-856D01*
G37*
G36*
G01X1731837Y581021D02*
G03X1732383Y581002I283J283D01*
G02X1732305Y578807I985J-1134D01*
G03X1731759Y578826I-283J-283D01*
G02X1731837Y581021I-985J1134D01*
G37*
G36*
G01X1435450Y583638D02*
G02X1432718Y578792I-2350J-1868D01*
G02X1428859Y578423I-2148J2098D01*
G02X1429211Y583567I-1359J2677D01*
G02X1429693Y583761I1358J-2677D01*
G02X1435450Y583638I2897J789D01*
G37*
G36*
G01X1880764Y580661D02*
G03X1880737Y580043I240J-320D01*
G02X1878909Y580083I-937J-1043D01*
G03Y580701I-254J309D01*
G02X1880764Y580661I953J1161D01*
G37*
G36*
G01X1383791Y580643D02*
G03X1383671Y580041I191J-351D01*
G02X1381783Y580420I-1171J-941D01*
G03X1381903Y581022I-191J351D01*
G02X1383791Y580643I1171J941D01*
G37*
G36*
G01X1784643Y578162D02*
G03X1784657Y577558I269J-296D01*
G02X1782743I-957J-1158D01*
G03X1782757Y578162I-255J308D01*
G02X1784643I943J1038D01*
G37*
G36*
G01X1389662Y573965D02*
G03X1389093Y573945I-275J-291D01*
G02X1389073Y575997I-1107J1015D01*
G03X1389642Y575987I289J276D01*
G02X1389662Y573965I981J-1001D01*
G37*
G36*
G01X2602Y575579D02*
G03X2589Y575050I293J-272D01*
G02X337Y575104I-1150J-967D01*
G03X350Y575633I-293J272D01*
G02X368Y577587I1150J966D01*
G03Y578113I-302J263D01*
G02X2632I1132J987D01*
G03Y577587I302J-263D01*
G02X2602Y575579I-1132J-987D01*
G37*
G36*
G01X1829887Y574715D02*
G03X1829998Y574116I310J-252D01*
G02X1828213Y573785I-698J-1216D01*
G03X1828102Y574384I-310J252D01*
G02X1829887Y574715I698J1216D01*
G37*
G36*
G01X1377132Y574469D02*
G03Y573943I302J-263D01*
G02X1374868I-1132J-987D01*
G03Y574469I-302J263D01*
G02X1374859Y576432I1132J987D01*
G03X1374850Y576962I-304J260D01*
G02X1377102Y576997I1111J1011D01*
G03X1377111Y576467I304J-260D01*
G02X1377132Y574469I-1111J-1011D01*
G37*
G36*
G01X1443641Y571089D02*
G03X1443199Y570735I-44J-398D01*
G02X1441961Y572280I-1394J152D01*
G03X1442403Y572634I44J398D01*
G02X1443954Y573875I1394J-152D01*
G03X1444398Y574279I44J398D01*
G02X1446028Y575683I1402J21D01*
G03X1446483Y575991I65J395D01*
G02X1447624Y574304I1369J-304D01*
G03X1447169Y573996I-65J-395D01*
G02X1445643Y572907I-1369J304D01*
G03X1445199Y572503I-44J-398D01*
G02X1443641Y571089I-1402J-21D01*
G37*
G36*
G01X1809558Y573173D02*
G03X1810053Y572797I400J12D01*
G02X1811351Y570417I334J-1362D01*
G03Y569837I275J-290D01*
G02X1809038Y568431I-966J-1016D01*
G03X1808529Y568699I-384J-112D01*
G02X1807134Y571310I-472J1426D01*
G03Y571940I-246J315D01*
G02X1809558Y573173I923J1185D01*
G37*
G36*
G01X1726617Y570629D02*
G03Y569999I246J-315D01*
G02X1724771I-923J-1185D01*
G03Y570629I-246J315D01*
G02X1726617I923J1185D01*
G37*
G36*
G01X1935870Y569709D02*
G03X1936396Y569415I391J83D01*
G02X1935430Y567691I504J-1415D01*
G03X1934904Y567985I-391J-83D01*
G02X1935870Y569709I-504J1415D01*
G37*
G36*
G01X1794000Y567398D02*
G03X1793600Y566977I-1J-400D01*
G02X1792177Y568400I-1500J-77D01*
G03X1792598Y568800I21J399D01*
G02X1794000Y567398I1402J0D01*
G37*
G36*
G01X20421Y567710D02*
G03X20975I277J288D01*
G02X23037Y567583I973J-1010D01*
G03X23659I311J252D01*
G02Y565817I1089J-883D01*
G03X23037I-311J-252D01*
G02X20975Y565690I-1089J883D01*
G03X20421I-277J-288D01*
G02Y567710I-973J1010D01*
G37*
G36*
G01X1676872Y568999D02*
G03X1677560Y568969I353J188D01*
G02X1679424Y569867I1676J-1095D01*
G03X1679858Y570318I37J398D01*
G02X1684289Y571689I2331J312D01*
G01X1684290Y571687D01*
X1685730Y568999D01*
G03X1686418Y568969I353J188D01*
G02X1688541Y569825I1676J-1095D01*
G03X1689025Y570283I90J390D01*
G02X1690561Y568636I2023J346D01*
G03X1690072Y568185I-94J-388D01*
G02X1687907Y565881I-1978J-311D01*
G03X1687473Y565430I-37J-398D01*
G02X1683042Y564059I-2331J-312D01*
G01X1683041Y564061D01*
X1681600Y566750D01*
G03X1680913Y566780I-352J-189D01*
G02X1679048Y565881I-1677J1094D01*
G03X1678614Y565430I-37J-398D01*
G02X1674191Y564044I-2331J-311D01*
G01X1674190Y564045D01*
X1672742Y566749D01*
G03X1672054Y566779I-353J-188D01*
G02X1670566Y569867I-1676J1095D01*
G03X1671000Y570318I37J398D01*
G02X1675423Y571704I2331J311D01*
G01X1675424Y571703D01*
X1676872Y568999D01*
G37*
G36*
G01X1629628D02*
G03X1630316Y568969I353J188D01*
G02X1632180Y569867I1676J-1095D01*
G03X1632614Y570318I37J398D01*
G02X1637045Y571689I2331J312D01*
G01X1637046Y571687D01*
X1638486Y568999D01*
G03X1639174Y568969I353J188D01*
G02X1641297Y569825I1676J-1095D01*
G03X1641781Y570283I90J390D01*
G02X1643317Y568636I2023J346D01*
G03X1642828Y568185I-94J-388D01*
G02X1640663Y565881I-1978J-311D01*
G03X1640229Y565430I-37J-398D01*
G02X1635798Y564059I-2331J-312D01*
G01X1635797Y564061D01*
X1634356Y566750D01*
G03X1633669Y566780I-352J-189D01*
G02X1631804Y565881I-1677J1094D01*
G03X1631370Y565430I-37J-398D01*
G02X1626947Y564044I-2331J-311D01*
G01X1626946Y564045D01*
X1625498Y566749D01*
G03X1624810Y566779I-353J-188D01*
G02X1623322Y569867I-1676J1095D01*
G03X1623756Y570318I37J398D01*
G02X1628179Y571704I2331J311D01*
G01X1628180Y571703D01*
X1629628Y568999D01*
G37*
G36*
G01X1766317Y564724D02*
G03X1766435Y565324I-194J350D01*
G02X1768212Y564976I1094J876D01*
G03X1768094Y564376I194J-350D01*
G02X1766317Y564724I-1094J-876D01*
G37*
G36*
G01X1655997Y562874D02*
G03X1655426Y562604I-181J-357D01*
G02X1653519Y564366I-1466J326D01*
G03X1653743Y564956I-118J382D01*
G02X1655997Y562874I4784J2918D01*
G37*
G36*
G01X1934250Y563906D02*
G03X1934628Y563402I386J-104D01*
G02X1933150Y562294I-28J-1502D01*
G03X1932772Y562798I-386J104D01*
G02X1934250Y563906I28J1502D01*
G37*
G36*
G01X1744336Y563252D02*
G03X1744252Y562664I223J-332D01*
G02X1742264Y562948I-1152J-964D01*
G03X1742348Y563536I-223J332D01*
G02X1742378Y565498I1152J964D01*
G03X1742314Y566087I-299J265D01*
G02X1742069Y568288I886J1213D01*
G03X1742027Y568856I-301J263D01*
G02X1744131Y569012I973J1144D01*
G03X1744173Y568444I301J-263D01*
G02X1744322Y566302I-973J-1144D01*
G03X1744386Y565713I299J-265D01*
G02X1744336Y563252I-886J-1213D01*
G37*
G36*
G01X1383118Y561641D02*
G03X1383081Y561073I262J-302D01*
G02X1381114Y561202I-1049J-930D01*
G03X1381151Y561770I-262J302D01*
G02X1383118Y561641I1049J930D01*
G37*
G36*
G01X1794481Y559433D02*
G03X1794405Y558856I234J-324D01*
G02X1792499Y559105I-1085J-888D01*
G03X1792575Y559682I-234J324D01*
G02X1794481Y559433I1085J888D01*
G37*
G36*
G01X1739262Y559755D02*
G03X1739418Y559206I348J-198D01*
G02X1737393Y558633I-721J-1318D01*
G03X1737237Y559182I-348J198D01*
G02X1739262Y559755I721J1318D01*
G37*
G36*
G01X34369Y558678D02*
G03X34923I277J288D01*
G02X36985Y558551I973J-1010D01*
G03X37607I311J252D01*
G02Y556785I1089J-883D01*
G03X36985I-311J-252D01*
G02X34923Y556658I-1089J883D01*
G03X34369I-277J-288D01*
G02Y558678I-973J1010D01*
G37*
G36*
G01X28825Y556680D02*
G03X28203I-311J-252D01*
G02Y558446I-1089J883D01*
G03X28825I311J252D01*
G02Y556680I1089J-883D01*
G37*
G36*
G01X1859563Y558005D02*
G03X1859284Y557542I113J-384D01*
G02X1857473Y558708I-1472J-297D01*
G03X1857779Y559154I-90J390D01*
G02X1859563Y558005I1388J196D01*
G37*
G36*
G01X1897789Y556580D02*
G03X1897687Y556045I237J-322D01*
G02X1895744Y556481I-1188J-745D01*
G03X1895784Y556783I-108J168D01*
G02X1895696Y556891I1119J1002D01*
G03X1895381Y556899I-161J-119D01*
G02X1895255Y558815I-1082J891D01*
G03X1895816Y558831I272J293D01*
G02X1897789Y556580I1083J-1041D01*
G37*
G36*
G01X1810785Y555991D02*
G03X1811295Y555682I393J74D01*
G02X1810340Y554016I409J-1341D01*
G03X1809816Y554299I-389J-93D01*
G02X1810785Y555991I-507J1414D01*
G37*
G36*
G01X2393Y555510D02*
G03X2416Y554924I283J-282D01*
G02X430Y554895I-977J-1141D01*
G03X436Y555482I-269J296D01*
G02X389Y555529I968J1015D01*
G03X-189I-289J-277D01*
G02Y557471I-1011J971D01*
G03X389I289J277D01*
G02X2393Y555510I1012J-971D01*
G37*
G36*
G01X1755907Y553120D02*
G03X1755381Y552910I-158J-367D01*
G02X1754593Y554880I-1381J590D01*
G03X1755119Y555090I158J367D01*
G02X1757685Y555423I1381J-590D01*
G03X1758315I315J246D01*
G02Y553577I1185J-923D01*
G03X1757685I-315J-246D01*
G02X1755907Y553120I-1185J923D01*
G37*
G36*
G01X1829978Y553196D02*
G03X1830604Y553209I308J255D01*
G02Y551391I1196J-909D01*
G03X1829978Y551404I-318J-242D01*
G02Y553196I-1078J896D01*
G37*
G36*
G01X1794888Y551715D02*
G03X1794866Y551116I254J-309D01*
G02X1793012Y551185I-966J-1016D01*
G03X1793034Y551784I-254J309D01*
G02X1794888Y551715I966J1016D01*
G37*
G36*
G01X1936798Y551349D02*
G03X1937303Y551117I373J146D01*
G02X1936402Y549151I497J-1417D01*
G03X1935897Y549383I-373J-146D01*
G02X1936798Y551349I-497J1417D01*
G37*
G36*
G01X1660076Y549588D02*
G03X1659719Y549009I0J-400D01*
G02X1657567Y549455I-1253J-629D01*
G03X1657614Y550023I-257J307D01*
G02X1659237Y552422I1141J977D01*
G01X1659269Y552412D01*
X1663239D01*
X1663271Y552422D01*
G02X1664917Y550050I483J-1422D01*
G03X1664980Y549482I310J-253D01*
G02X1662860Y549009I-867J-1102D01*
G03X1662503Y549588I-357J179D01*
G01X1660076D01*
G37*
G36*
G01X1923217Y545380D02*
G03X1923112Y544760I191J-351D01*
G02X1921283Y545070I-1112J-1010D01*
G03X1921388Y545690I-191J351D01*
G02X1923217Y545380I1112J1010D01*
G37*
G36*
G01X1679893Y546520D02*
G03X1679469Y546037I-33J-399D01*
G02X1671633Y548350I-4548J-978D01*
G03X1671350Y549032I-283J282D01*
G01X1670777D01*
G03X1670410Y548475I0J-400D01*
G02X1668308Y549065I-1289J-552D01*
G03X1668395Y549632I-232J326D01*
G02X1669600Y552056I1205J912D01*
G01X1674600D01*
G02X1675852Y551390I-1J-1512D01*
G03X1676431Y551301I331J225D01*
G02X1678169I869J-1101D01*
G03X1678748Y551390I248J314D01*
G02X1680000Y552056I1253J-846D01*
G01X1685000D01*
G02X1686512Y550554I0J-1512D01*
G01Y550459D01*
X1686502Y550375D01*
G02X1686419Y550023I-1502J168D01*
G03X1686626Y549523I376J-137D01*
G02X1684666Y548548I-590J-1272D01*
G03X1684275Y549032I-391J84D01*
G01X1681661D01*
G03X1681294Y548474I0J-400D01*
G02X1679893Y546520I-1287J-557D01*
G37*
G36*
G01X1940776Y542558D02*
G03X1940755Y541969I260J-304D01*
G02X1938435Y540090I-1055J-1069D01*
G03X1937931Y540237I-336J-216D01*
G02X1938130Y542852I-631J1363D01*
G03X1938424Y543099I111J167D01*
G02X1938324Y543419I1375J605D01*
G03X1937778Y543714I-393J-74D01*
G02X1937812Y546472I-578J1386D01*
G03X1938359Y546724I163J365D01*
G02X1940896Y545273I1441J-424D01*
G03Y544727I292J-273D01*
G02X1940776Y542558I-1096J-1027D01*
G37*
G36*
G01X1391434Y540655D02*
G03X1391428Y540051I259J-305D01*
G02X1389543Y540025I-928J-1051D01*
G03X1389521Y540629I-273J292D01*
G02X1391434Y540655I941J1171D01*
G37*
G36*
G01X2602Y539579D02*
G03X2589Y539050I293J-272D01*
G02X337Y539104I-1150J-967D01*
G03X350Y539633I-293J272D01*
G02X368Y541587I1150J966D01*
G03Y542113I-302J263D01*
G02X2632I1132J987D01*
G03Y541587I302J-263D01*
G02X2602Y539579I-1132J-987D01*
G37*
G36*
G01X1367792Y536427D02*
G03X1367238I-277J-288D01*
G02X1365244Y536476I-973J1010D01*
G03X1364669Y536483I-291J-274D01*
G02X1362701Y536461I-995J988D01*
G03X1362147I-277J-288D01*
G02X1360137Y536527I-973J1010D01*
G03X1359550Y536532I-296J-269D01*
G02X1357556Y536482I-1022J960D01*
G03X1357002I-277J-288D01*
G02X1355058Y536481I-973J1010D01*
G03X1354501Y536478I-277J-289D01*
G02X1354491Y538491I-981J1002D01*
G03X1355048Y538494I277J289D01*
G02X1355194Y538618I978J-1004D01*
G03X1355192Y538940I-120J160D01*
G02X1356991Y541083I827J1132D01*
G03X1357545I277J288D01*
G02X1359555Y541017I973J-1010D01*
G03X1360142Y541012I296J269D01*
G02X1362136Y541062I1022J-960D01*
G03X1362690I277J288D01*
G02X1364678Y541019I973J-1010D01*
G03X1365219Y540982I291J275D01*
G02X1367069Y540899I878J-1093D01*
G03X1367623I277J288D01*
G02X1369569I973J-1010D01*
G03X1370123I277J288D01*
G02X1372185Y539006I974J-1009D01*
G03X1372222Y538461I310J-253D01*
G02X1370292Y536427I-958J-1024D01*
G03X1369738I-277J-288D01*
G02X1367792I-973J1010D01*
G37*
G36*
G01X1743894Y534951D02*
G03X1743351I-271J-294D01*
G02Y538631I-1697J1840D01*
G03X1743894I272J294D01*
G02X1747288I1697J-1840D01*
G03X1747831I272J294D01*
G02X1751225I1697J-1840D01*
G03X1751768I271J294D01*
G02X1755162I1697J-1840D01*
G03X1755705I271J294D01*
G02X1759099I1697J-1840D01*
G03X1759642I272J294D01*
G02Y534951I1697J-1840D01*
G03X1759099I-271J-294D01*
G02X1755705I-1697J1840D01*
G03X1755162I-272J-294D01*
G02X1751768I-1697J1840D01*
G03X1751225I-272J-294D01*
G02X1747831I-1697J1840D01*
G03X1747288I-271J-294D01*
G02X1743894I-1697J1840D01*
G37*
G36*
G01X1377097Y534222D02*
G03X1376564Y534217I-264J-301D01*
G02X1374553Y536162I-942J1038D01*
G03X1374526Y536709I-305J259D01*
G02X1374446Y538641I974J1008D01*
G03X1374441Y539174I-301J264D01*
G02X1376452Y541127I1038J943D01*
G03X1377006I277J288D01*
G02X1378952I973J-1010D01*
G03X1379506I277J288D01*
G02X1381525Y539183I973J-1010D01*
G03Y538651I298J-266D01*
G02X1381526Y536785I-1046J-934D01*
G03X1381536Y536243I299J-266D01*
G02X1379548Y534266I-1015J-967D01*
G03X1378994I-277J-288D01*
G02X1377097Y534222I-972J1010D01*
G37*
G36*
G01X1714590Y538630D02*
G03X1715203Y538606I317J244D01*
G02Y534976I2002J-1815D01*
G03X1714590Y534952I-296J-268D01*
G02X1712205Y533780I-2384J1839D01*
G01X1707205D01*
G02X1704820Y534952I-1J3011D01*
G03X1704207Y534977I-317J-244D01*
G02X1700203Y534976I-2002J1814D01*
G03X1699590Y534952I-296J-268D01*
G02X1697205Y533780I-2384J1839D01*
G01X1692205D01*
G02X1689820Y534952I-1J3011D01*
G03X1689207Y534977I-317J-244D01*
G02Y538605I-2002J1814D01*
G03X1689820Y538630I296J269D01*
G02X1692205Y539802I2384J-1839D01*
G01X1697205D01*
G02X1699590Y538630I1J-3011D01*
G03X1700203Y538606I317J244D01*
G02X1704207Y538605I2002J-1815D01*
G03X1704820Y538630I296J269D01*
G02X1707205Y539802I2384J-1839D01*
G01X1712205D01*
G02X1714590Y538630I1J-3011D01*
G37*
G36*
G01X27934Y533346D02*
G03X28466I266J298D01*
G02Y531254I934J-1046D01*
G03X27934I-266J-298D01*
G02Y533346I-934J1046D01*
G37*
G36*
G01X2636Y530282D02*
G03X2067Y530264I-276J-290D01*
G02X2004Y532236I-1027J954D01*
G03X2573Y532254I276J290D01*
G02X2636Y530282I1027J-954D01*
G37*
G36*
G01X687517Y528591D02*
G02X685000Y527505I-1142J-813D01*
G02X683118Y532663I200J2995D01*
G02X685793Y533443I1382J238D01*
G02X687517Y528591I-593J-2943D01*
G37*
G36*
G01X1818626Y526496D02*
G03X1818269Y526014I34J-398D01*
G02X1816745Y527201I-1469J-314D01*
G03X1817126Y527666I-14J400D01*
G02X1818626Y526496I1383J227D01*
G37*
G36*
G01X1438204Y525685D02*
G03X1437755Y525255I-50J-397D01*
G02X1436471Y526539I-1397J-113D01*
G03X1436900Y526988I32J399D01*
G02X1438204Y525685I1490J187D01*
G37*
G36*
G01X1638820Y528684D02*
G03X1639021Y528123I352J-190D01*
G02X1636529Y527668I-890J-2177D01*
G03X1636518Y528263I-273J293D01*
G02X1638820Y528684I982J1137D01*
G37*
G36*
G01X1785015Y521466D02*
G03X1784469Y521445I-262J-302D01*
G02X1782362Y521415I-1069J1055D01*
G03X1781823Y521428I-277J-289D01*
G02X1781876Y523647I-985J1134D01*
G03X1782415Y523634I277J289D01*
G02X1784385I985J-1134D01*
G03X1784931Y523655I262J302D01*
G02X1785015Y521466I1069J-1055D01*
G37*
G36*
G01X702144Y523214D02*
G03X702156Y522612I270J-296D01*
G02X700311Y522574I-901J-1074D01*
G03X700299Y523176I-270J296D01*
G02X702144Y523214I901J1074D01*
G37*
G36*
G01X1419200Y522044D02*
G03X1419712Y521814I373J145D01*
G02X1418923Y519921I488J-1314D01*
G03X1418399Y520123I-364J-165D01*
G02X1416646Y520538I-600J1377D01*
G03X1416015Y520517I-307J-256D01*
G02X1415954Y522362I-1215J883D01*
G03X1416585Y522383I307J256D01*
G02X1419200Y522044I1215J-883D01*
G37*
G36*
G01X1629241Y519549D02*
G03X1628648Y519472I-262J-302D01*
G02X1628444Y521404I-1241J846D01*
G03X1629040Y521453I276J289D01*
G02X1629241Y519549I1119J-844D01*
G37*
G36*
G01X1698834Y519096D02*
G03X1698288I-273J-292D01*
G02Y521288I-1027J1096D01*
G03X1698834I273J292D01*
G02Y519096I1027J-1096D01*
G37*
G36*
G01X1790913Y521002D02*
G03X1790713Y520508I177J-359D01*
G02X1788637Y521348I-1413J-508D01*
G03X1788837Y521842I-177J359D01*
G02X1790913Y521002I1413J508D01*
G37*
G36*
G01X1728189Y518029D02*
G03X1727611I-289J-277D01*
G02Y519971I-1011J971D01*
G03X1728189I289J277D01*
G02Y518029I1011J-971D01*
G37*
G36*
G01X63617Y519235D02*
G03X63596Y519857I-262J303D01*
G02X63343Y522008I907J1197D01*
G03X63317Y522545I-309J254D01*
G02X63282Y524631I1063J1061D01*
G03Y525177I-292J273D01*
G02X65087Y527527I1098J1025D01*
G03X65604Y527653I188J353D01*
G02X67972Y525813I1237J-852D01*
G03Y525287I302J-263D01*
G02X67864Y523201I-1132J-987D01*
G03X67853Y522919I136J-147D01*
G02X67882Y520913I-1103J-1019D01*
G03Y520387I302J-263D01*
G02Y518413I-1132J-987D01*
G03Y517887I302J-263D01*
G02X66485Y515422I-1132J-987D01*
G03X66032Y515148I-71J-394D01*
G02X63468Y516587I-1432J452D01*
G03Y517113I-302J263D01*
G02X63617Y519235I1132J987D01*
G37*
G36*
G01X1338529Y518605D02*
G02X1341188Y518347I1371J295D01*
G02X1338529Y518605I-1589J-2547D01*
G37*
G36*
G01X1750836Y514598D02*
G03X1750455Y514108I9J-400D01*
G02X1748995Y515189I-1365J-318D01*
G03X1749353Y515696I-27J399D01*
G02X1750836Y514598I1447J404D01*
G37*
G36*
G01X1811406Y514823D02*
G03X1811355Y514260I256J-307D01*
G02X1809302Y514504I-1155J-960D01*
G03X1809383Y515063I-240J320D01*
G02X1811406Y514823I1125J837D01*
G37*
G36*
G01X1828930Y515048D02*
G03X1828909Y514396I221J-333D01*
G02X1826503Y513075I-909J-1196D01*
G03X1826020Y513432I-398J-34D01*
G02X1826131Y516339I-320J1468D01*
G03X1826635Y516633I114J383D01*
G02X1827083Y517405I1464J-334D01*
G03X1827104Y517973I-271J294D01*
G02X1829217Y517895I1096J1027D01*
G03X1829196Y517327I271J-294D01*
G02X1828930Y515048I-1096J-1027D01*
G37*
G36*
G01X1775258Y513867D02*
G03X1775782Y513833I282J284D01*
G02X1775637Y511573I913J-1193D01*
G03X1775113Y511607I-282J-284D01*
G02X1775258Y513867I-913J1193D01*
G37*
G36*
G01X730615Y510466D02*
G03X730069Y510445I-262J-302D01*
G02X729985Y512634I-1069J1055D01*
G03X730531Y512655I262J302D01*
G02X730615Y510466I1069J-1055D01*
G37*
G36*
G01X1911615Y509777D02*
G03X1910985I-315J-246D01*
G02Y511623I-1185J923D01*
G03X1911615I315J246D01*
G02Y509777I1185J-923D01*
G37*
G36*
G01X1402175Y509363D02*
G03X1401648Y509260I-207J-342D01*
G02X1401220Y511446I-1203J899D01*
G03X1401747Y511549I207J342D01*
G02X1404135Y511573I1203J-899D01*
G03X1404765I315J246D01*
G02X1406063Y512148I1185J-923D01*
G03X1406491Y512592I31J399D01*
G02X1407841Y511350I1393J159D01*
G03X1407433Y510887I-13J-400D01*
G02X1404765Y509727I-1483J-237D01*
G03X1404135I-315J-246D01*
G02X1402175Y509363I-1185J923D01*
G37*
G36*
G01X721965Y510794D02*
G03X722143Y510299I373J-146D01*
G02X720014Y509530I-729J-1313D01*
G03X719836Y510025I-373J146D01*
G02X721965Y510794I729J1313D01*
G37*
G36*
G01X703472Y505634D02*
G03X702988Y505298I-88J-390D01*
G02X701828Y506966I-1488J202D01*
G03X702312Y507302I88J390D01*
G02X703472Y505634I1488J-202D01*
G37*
G36*
G01X712263Y504457D02*
G03X711711Y504440I-267J-298D01*
G02X709418Y504626I-1068J1056D01*
G03X708817Y504684I-326J-232D01*
G02X708954Y506564I-967J1015D01*
G03X709558Y506534I315J247D01*
G02X711708Y506555I1085J-1038D01*
G03X712260Y506540I284J282D01*
G02X714143Y506538I940J-1040D01*
G03X714724Y506585I268J296D01*
G02X714835Y504591I1176J-935D01*
G03X714252Y504573I-283J-283D01*
G02X712263Y504457I-1052J927D01*
G37*
G36*
G01X1843621Y506748D02*
G03X1843743Y506189I334J-220D01*
G02X1841829Y505772I-743J-1189D01*
G03X1841707Y506331I-334J220D01*
G02X1842559Y508918I743J1189D01*
G03X1842990Y509298I31J399D01*
G02X1844295Y507741I1500J-68D01*
G03X1843845Y507383I-52J-397D01*
G02X1843621Y506748I-1396J135D01*
G37*
G36*
G01X1650104Y503802D02*
G03X1649565Y503689I-210J-340D01*
G02X1649048Y505863I-1235J855D01*
G03X1649579Y506005I190J352D01*
G02X1650104Y503802I1365J-839D01*
G37*
G36*
G01X76096Y501061D02*
G03X75564Y501046I-258J-306D01*
G02X73515Y502952I-964J1018D01*
G03X73489Y503489I-309J254D01*
G02X75416Y505524I991J991D01*
G03X75975Y505547I268J297D01*
G02X78023Y505541I1021J-960D01*
G03X78608Y505540I293J272D01*
G02X80567Y503537I1021J-961D01*
G03X80516Y502998I268J-297D01*
G02X78474Y501098I-1116J-848D01*
G03X77941Y501094I-264J-301D01*
G02X76096Y501061I-941J1039D01*
G37*
G36*
G01X675615Y500166D02*
G03X675069Y500145I-262J-302D01*
G02X672968Y500109I-1069J1055D01*
G03X672442Y500130I-275J-290D01*
G02X672532Y502391I-942J1170D01*
G03X673058Y502370I275J290D01*
G02X674985Y502334I942J-1170D01*
G03X675531Y502355I262J302D01*
G02X675615Y500166I1069J-1055D01*
G37*
G36*
G01X1875015Y501490D02*
G03X1875507Y501266I368J156D01*
G02X1874590Y499252I466J-1428D01*
G03X1874098Y499476I-368J-156D01*
G02X1875015Y501490I-466J1428D01*
G37*
G36*
G01X648086Y500074D02*
G03X647702Y499680I16J-400D01*
G02X646139Y501201I-1502J20D01*
G03X646523Y501595I-16J400D01*
G02X648086Y500074I1502J-20D01*
G37*
G36*
G01X1269419Y500290D02*
G03X1269078Y499852I57J-396D01*
G02X1267374Y501181I-1494J-158D01*
G03X1267715Y501619I-57J396D01*
G02X1269419Y500290I1494J158D01*
G37*
G36*
G01X745037Y498542D02*
G03X744511I-263J-302D01*
G02X742392Y500661I-987J1132D01*
G03Y501187I-302J263D01*
G02X744511Y503306I1132J987D01*
G03X745037I263J302D01*
G02X747011I987J-1132D01*
G03X747537I263J302D01*
G02X749985Y501827I987J-1132D01*
G03X750492Y501352I389J-92D01*
G02X749975Y498758I439J-1436D01*
G03X749692Y498729I-127J-154D01*
G02X747537Y498542I-1168J945D01*
G03X747011I-263J-302D01*
G02X745037I-987J1132D01*
G37*
G36*
G01X1336011Y498417D02*
G03X1335389I-311J-252D01*
G02Y500183I-1089J883D01*
G03X1336011I311J252D01*
G02Y498417I1089J-883D01*
G37*
G36*
G01X710329Y498366D02*
G03X709774Y498350I-269J-296D01*
G02X709710Y500512I-1074J1050D01*
G03X710265Y500528I269J296D01*
G02X710329Y498366I1074J-1050D01*
G37*
G36*
G01X1385071Y497791D02*
G03X1384469Y497731I-275J-291D01*
G02X1384322Y499638I-1228J864D01*
G03X1384925Y499671I287J278D01*
G02X1387049Y499777I1108J-860D01*
G03X1387629Y499778I290J276D01*
G02X1387579Y497767I1090J-1033D01*
G03X1387000Y497796I-303J-261D01*
G02X1385071Y497791I-967J1015D01*
G37*
G36*
G01X1084723Y498000D02*
G03X1084301Y497611I-22J-399D01*
G02X1082961Y499143I-1501J39D01*
G03X1083402Y499510I42J398D01*
G02X1084723Y498000I1398J-110D01*
G37*
G36*
G01X435115D02*
G03X434693Y497611I-22J-399D01*
G02X433353Y499143I-1501J39D01*
G03X433794Y499510I42J398D01*
G02X435115Y498000I1398J-110D01*
G37*
G36*
G01X1366733Y498513D02*
G03X1367320Y498523I289J277D01*
G02X1367304Y496541I1121J-1000D01*
G03X1366717Y496560I-302J-262D01*
G02X1364662Y496624I-998J985D01*
G03X1364049Y496613I-302J-262D01*
G02X1364056Y498490I-1169J943D01*
G03X1364669Y498474I313J249D01*
G02X1366733Y498513I1050J-929D01*
G37*
G36*
G01X-15685Y499063D02*
G03X-15671Y498494I288J-278D01*
G02X-17781Y498443I-1029J-1094D01*
G03X-17795Y499012I-288J278D01*
G02X-15685Y499063I1029J1094D01*
G37*
G36*
G01X977506Y498730D02*
G03X977514Y498168I289J-277D01*
G02X975465Y498082I-984J-998D01*
G03X975427Y498642I-303J261D01*
G02X975319Y498748I997J1123D01*
G03X974752Y498768I-293J-272D01*
G02X974771Y500799I-957J1025D01*
G03X975338Y500809I279J287D01*
G02X977506Y498730I1083J-1041D01*
G37*
G36*
G01X327889Y498735D02*
G03X327900Y498174I290J-275D01*
G02X325852Y498076I-978J-1004D01*
G03X325809Y498635I-306J258D01*
G02X325700Y498741I991J1129D01*
G03X325137Y498762I-292J-273D01*
G02X325157Y500805I-950J1031D01*
G03X325721Y500815I277J289D01*
G02X327889Y498735I1076J-1048D01*
G37*
G36*
G01X113190Y499013D02*
G03X113288Y498456I327J-230D01*
G02X111198Y498089I-861J-1231D01*
G03X111100Y498646I-327J230D01*
G02X113190Y499013I861J1231D01*
G37*
G36*
G01X1279133Y497801D02*
G03X1279720Y497660I355J184D01*
G02X1279262Y495746I875J-1221D01*
G03X1278675Y495887I-355J-184D01*
G02X1279133Y497801I-875J1221D01*
G37*
G36*
G01X928165Y497524D02*
G03X928151Y496941I267J-298D01*
G02X926179I-986J-997D01*
G03X926165Y497524I-281J285D01*
G02X928165I1000J1120D01*
G37*
G36*
G01X921700D02*
G03X921686Y496941I267J-298D01*
G02X919714I-986J-997D01*
G03X919700Y497524I-281J285D01*
G02X921700I1000J1120D01*
G37*
G36*
G01X276571Y496941D02*
G03X276557Y497524I-281J285D01*
G02X278557I1000J1120D01*
G03X278543Y496941I267J-298D01*
G02X276571I-986J-997D01*
G37*
G36*
G01X272092Y497524D02*
G03X272078Y496941I267J-298D01*
G02X270106I-986J-997D01*
G03X270092Y497524I-281J285D01*
G02X272092I1000J1120D01*
G37*
G36*
G01X883941Y497417D02*
G03X883925Y496856I277J-289D01*
G02X881875I-1025J-956D01*
G03X881859Y497417I-293J272D01*
G02X883941I1041J1083D01*
G37*
G36*
G01X234333D02*
G03X234317Y496856I277J-289D01*
G02X232267I-1025J-956D01*
G03X232251Y497417I-293J272D01*
G02X234333I1041J1083D01*
G37*
G36*
G01X1205441Y497404D02*
G03X1205425Y496843I277J-289D01*
G02X1203375I-1025J-956D01*
G03X1203359Y497404I-293J272D01*
G02X1205441I1041J1083D01*
G37*
G36*
G01X1145426D02*
G03X1145410Y496843I277J-289D01*
G02X1143360I-1025J-956D01*
G03X1143344Y497404I-293J272D01*
G02X1145426I1041J1083D01*
G37*
G36*
G01X1139033D02*
G03X1139017Y496843I277J-289D01*
G02X1136967I-1025J-956D01*
G03X1136951Y497404I-293J272D01*
G02X1139033I1041J1083D01*
G37*
G36*
G01X555833D02*
G03X555817Y496843I277J-289D01*
G02X553767I-1025J-956D01*
G03X553751Y497404I-293J272D01*
G02X555833I1041J1083D01*
G37*
G36*
G01X493752Y496843D02*
G03X493736Y497404I-293J272D01*
G02X495818I1041J1083D01*
G03X495802Y496843I277J-289D01*
G02X493752I-1025J-956D01*
G37*
G36*
G01X489425Y497404D02*
G03X489409Y496843I277J-289D01*
G02X487359I-1025J-956D01*
G03X487343Y497404I-293J272D01*
G02X489425I1041J1083D01*
G37*
G36*
G01X1199141Y497317D02*
G03X1199125Y496756I277J-289D01*
G02X1197075I-1025J-956D01*
G03X1197059Y497317I-293J272D01*
G02X1199141I1041J1083D01*
G37*
G36*
G01X1168512Y497368D02*
G03X1168495Y496788I267J-298D01*
G02X1166513Y496795I-995J-988D01*
G03X1166500Y497375I-282J284D01*
G02X1168512Y497368I1010J1112D01*
G37*
G36*
G01X1162381Y497335D02*
G03X1162345Y496756I257J-307D01*
G02X1160366Y496827I-1025J-956D01*
G03X1160372Y497408I-272J293D01*
G02X1162381Y497335I1045J1079D01*
G37*
G36*
G01X914794Y497379D02*
G03X914783Y496799I270J-295D01*
G02X912801Y496784I-983J-999D01*
G03X912782Y497364I-285J281D01*
G02X914794Y497379I998J1123D01*
G37*
G36*
G01X908055Y497339D02*
G03X908022Y496760I258J-305D01*
G02X906042Y496823I-1022J-960D01*
G03X906045Y497404I-274J292D01*
G02X908055Y497339I1041J1083D01*
G37*
G36*
G01X890161Y497583D02*
G03X890198Y497023I303J-261D01*
G02X888119Y496943I-998J-1123D01*
G03X888113Y497505I-288J278D01*
G02X890161Y497583I988J995D01*
G37*
G36*
G01X549533Y497317D02*
G03X549517Y496756I277J-289D01*
G02X547467I-1025J-956D01*
G03X547451Y497317I-293J272D01*
G02X549533I1041J1083D01*
G37*
G36*
G01X518904Y497368D02*
G03X518887Y496788I267J-298D01*
G02X516905Y496795I-995J-988D01*
G03X516892Y497375I-282J284D01*
G02X518904Y497368I1010J1112D01*
G37*
G36*
G01X512773Y497335D02*
G03X512737Y496756I257J-307D01*
G02X510758Y496827I-1025J-956D01*
G03X510764Y497408I-272J293D01*
G02X512773Y497335I1045J1079D01*
G37*
G36*
G01X265186Y497379D02*
G03X265175Y496799I270J-295D01*
G02X263193Y496784I-983J-999D01*
G03X263174Y497364I-285J281D01*
G02X265186Y497379I998J1123D01*
G37*
G36*
G01X258447Y497339D02*
G03X258414Y496760I258J-305D01*
G02X256434Y496823I-1022J-960D01*
G03X256437Y497404I-274J292D01*
G02X258447Y497339I1041J1083D01*
G37*
G36*
G01X240553Y497583D02*
G03X240590Y497023I303J-261D01*
G02X238511Y496943I-998J-1123D01*
G03X238505Y497505I-288J278D01*
G02X240553Y497583I988J995D01*
G37*
G36*
G01X1181441Y497304D02*
G03X1181425Y496743I277J-289D01*
G02X1179375I-1025J-956D01*
G03X1179359Y497304I-293J272D01*
G02X1181441I1041J1083D01*
G37*
G36*
G01X1175244D02*
G03X1175228Y496743I277J-289D01*
G02X1173178I-1025J-956D01*
G03X1173162Y497304I-293J272D01*
G02X1175244I1041J1083D01*
G37*
G36*
G01X531833D02*
G03X531817Y496743I277J-289D01*
G02X529767I-1025J-956D01*
G03X529751Y497304I-293J272D01*
G02X531833I1041J1083D01*
G37*
G36*
G01X525636D02*
G03X525620Y496743I277J-289D01*
G02X523570I-1025J-956D01*
G03X523554Y497304I-293J272D01*
G02X525636I1041J1083D01*
G37*
G36*
G01X948429Y496647D02*
G03X948443Y496064I281J-285D01*
G02X946443I-1000J-1120D01*
G03X946457Y496647I-267J298D01*
G02X948429I986J997D01*
G37*
G36*
G01X298821D02*
G03X298835Y496064I281J-285D01*
G02X296835I-1000J-1120D01*
G03X296849Y496647I-267J298D01*
G02X298821I986J997D01*
G37*
G36*
G01X955025Y496344D02*
G03X955041Y495783I293J-272D01*
G02X952959I-1041J-1083D01*
G03X952975Y496344I-277J289D01*
G02X955025I1025J956D01*
G37*
G36*
G01X305417D02*
G03X305433Y495783I293J-272D01*
G02X303351I-1041J-1083D01*
G03X303367Y496344I-277J289D01*
G02X305417I1025J956D01*
G37*
G36*
G01X1387075Y494670D02*
G03X1387658Y494664I294J271D01*
G02X1387584Y492665I1083J-1041D01*
G03X1387002Y492702I-308J-255D01*
G02X1385029Y492752I-961J1021D01*
G03X1384430Y492727I-288J-277D01*
G02X1384395Y494660I-1167J946D01*
G03X1384995Y494657I301J263D01*
G02X1387075Y494670I1046J-934D01*
G37*
G36*
G01X1209267Y495024D02*
G03X1209253Y494441I267J-298D01*
G02X1207281I-986J-997D01*
G03X1207267Y495024I-281J285D01*
G02X1209267I1000J1120D01*
G37*
G36*
G01X559659D02*
G03X559645Y494441I267J-298D01*
G02X557673I-986J-997D01*
G03X557659Y495024I-281J285D01*
G02X559659I1000J1120D01*
G37*
G36*
G01X894041Y494611D02*
G03X894025Y494050I277J-289D01*
G02X891975I-1025J-956D01*
G03X891959Y494611I-293J272D01*
G02X894041I1041J1083D01*
G37*
G36*
G01X242367Y494050D02*
G03X242351Y494611I-293J272D01*
G02X244433I1041J1083D01*
G03X244417Y494050I277J-289D01*
G02X242367I-1025J-956D01*
G37*
G36*
G01X1296367Y494352D02*
G03X1296922Y494308I300J264D01*
G02X1296751Y492157I956J-1158D01*
G03X1296196Y492201I-300J-264D01*
G02X1296367Y494352I-956J1158D01*
G37*
G36*
G01X1366738Y493709D02*
G03X1367321Y493723I285J281D01*
G02Y491723I1120J-1000D01*
G03X1366738Y491737I-298J-267D01*
G02X1364632Y491866I-997J986D01*
G03X1364005Y491874I-317J-245D01*
G02X1364068Y493690I-1164J949D01*
G03X1364693Y493655I326J231D01*
G02X1366738Y493709I1048J-932D01*
G37*
G36*
G01X89350Y490392D02*
G03X88830I-260J-304D01*
G02X86572Y492650I-1040J1218D01*
G03Y493170I-304J260D01*
G02X86592Y495274I1218J1041D01*
G03X86602Y495793I-299J265D01*
G02X86622Y497850I1238J1017D01*
G03Y498370I-304J260D01*
G02X88880Y500628I1218J1040D01*
G03X89400I260J304D01*
G02X91480I1040J-1218D01*
G03X92000I260J304D01*
G02X94080I1040J-1218D01*
G03X94600I260J304D01*
G02X96680I1040J-1218D01*
G03X97200I260J304D01*
G02X99458Y498370I1040J-1218D01*
G03Y497850I304J-260D01*
G02X97776Y495277I-1218J-1040D01*
G03X97283Y494758I-117J-383D01*
G02X94663Y493062I-1506J-545D01*
G03X94106Y493061I-278J-288D01*
G02X91834Y493101I-1116J1149D01*
G03X91546I-144J-139D01*
G02X91499Y493054I-1156J1109D01*
G03Y492766I139J-144D01*
G02X89350Y490392I-1109J-1156D01*
G37*
G36*
G01X1842073Y490404D02*
G03X1841527I-273J-292D01*
G02X1839404Y492527I-1027J1096D01*
G03Y493073I-292J273D01*
G02X1841527Y495196I1096J1027D01*
G03X1842073I273J292D01*
G02X1844196Y493073I1027J-1096D01*
G03Y492527I292J-273D01*
G02X1842073Y490404I-1096J-1027D01*
G37*
G36*
G01X918192Y492799D02*
G03X918178Y492216I267J-298D01*
G02X916206I-986J-997D01*
G03X916192Y492799I-281J285D01*
G02X918192I1000J1120D01*
G37*
G36*
G01X268584D02*
G03X268570Y492216I267J-298D01*
G02X266598I-986J-997D01*
G03X266584Y492799I-281J285D01*
G02X268584I1000J1120D01*
G37*
G36*
G01X1171656Y492724D02*
G03X1171642Y492141I267J-298D01*
G02X1169670I-986J-997D01*
G03X1169656Y492724I-281J285D01*
G02X1171656I1000J1120D01*
G37*
G36*
G01X924641Y492661D02*
G03X924625Y492100I277J-289D01*
G02X922575I-1025J-956D01*
G03X922559Y492661I-293J272D01*
G02X924641I1041J1083D01*
G37*
G36*
G01X522048Y492724D02*
G03X522034Y492141I267J-298D01*
G02X520062I-986J-997D01*
G03X520048Y492724I-281J285D01*
G02X522048I1000J1120D01*
G37*
G36*
G01X275033Y492661D02*
G03X275017Y492100I277J-289D01*
G02X272967I-1025J-956D01*
G03X272951Y492661I-293J272D01*
G02X275033I1041J1083D01*
G37*
G36*
G01X1165363Y492624D02*
G03X1165349Y492041I267J-298D01*
G02X1163377I-986J-997D01*
G03X1163363Y492624I-281J285D01*
G02X1165363I1000J1120D01*
G37*
G36*
G01X1142031Y492808D02*
G03X1142058Y492247I298J-267D01*
G02X1139977Y492207I-1020J-1103D01*
G03X1139981Y492768I-283J283D01*
G02X1142031Y492808I1006J976D01*
G37*
G36*
G01X911432Y492624D02*
G03X911418Y492041I267J-298D01*
G02X909446I-986J-997D01*
G03X909432Y492624I-281J285D01*
G02X911432I1000J1120D01*
G37*
G36*
G01X515755D02*
G03X515741Y492041I267J-298D01*
G02X513769I-986J-997D01*
G03X513755Y492624I-281J285D01*
G02X515755I1000J1120D01*
G37*
G36*
G01X492423Y492808D02*
G03X492450Y492247I298J-267D01*
G02X490369Y492207I-1020J-1103D01*
G03X490373Y492768I-283J283D01*
G02X492423Y492808I1006J976D01*
G37*
G36*
G01X261824Y492624D02*
G03X261810Y492041I267J-298D01*
G02X259838I-986J-997D01*
G03X259824Y492624I-281J285D01*
G02X261824I1000J1120D01*
G37*
G36*
G01X1178860Y492481D02*
G03X1178856Y491920I283J-283D01*
G02X1176806Y491880I-1006J-976D01*
G03X1176779Y492441I-298J267D01*
G02X1178860Y492481I1020J1103D01*
G37*
G36*
G01X529252D02*
G03X529248Y491920I283J-283D01*
G02X527198Y491880I-1006J-976D01*
G03X527171Y492441I-298J267D01*
G02X529252Y492481I1020J1103D01*
G37*
G36*
G01X1194104Y492426D02*
G03X1194088Y491865I277J-289D01*
G02X1192038I-1025J-956D01*
G03X1192022Y492426I-293J272D01*
G02X1192005Y494575I1041J1083D01*
G03Y495143I-282J284D01*
G02X1192063Y497329I1058J1066D01*
G03X1192077Y497912I-267J298D01*
G02X1194049I986J997D01*
G03X1194063Y497329I281J-285D01*
G02X1194121Y495143I-1000J-1120D01*
G03Y494575I282J-284D01*
G02X1194104Y492426I-1058J-1066D01*
G37*
G36*
G01X544496D02*
G03X544480Y491865I277J-289D01*
G02X542430I-1025J-956D01*
G03X542414Y492426I-293J272D01*
G02X542397Y494575I1041J1083D01*
G03Y495143I-282J284D01*
G02X542455Y497329I1058J1066D01*
G03X542469Y497912I-267J298D01*
G02X544441I986J997D01*
G03X544455Y497329I281J-285D01*
G02X544513Y495143I-1000J-1120D01*
G03Y494575I282J-284D01*
G02X544496Y492426I-1058J-1066D01*
G37*
G36*
G01X1157252Y492447D02*
G03X1157238Y491864I267J-298D01*
G02X1155266I-986J-997D01*
G03X1155252Y492447I-281J285D01*
G02X1155156Y494594I1000J1120D01*
G03Y495140I-292J273D01*
G02X1155252Y497287I1096J1027D01*
G03X1155266Y497870I-267J298D01*
G02X1157238I986J997D01*
G03X1157252Y497287I281J-285D01*
G02X1157348Y495140I-1000J-1120D01*
G03Y494594I292J-273D01*
G02X1157252Y492447I-1096J-1027D01*
G37*
G36*
G01X1152209Y492384D02*
G03X1152193Y491823I277J-289D01*
G02X1150143I-1025J-956D01*
G03X1150127Y492384I-293J272D01*
G02X1150110Y494533I1041J1083D01*
G03Y495101I-282J284D01*
G02X1150168Y497287I1058J1066D01*
G03X1150182Y497870I-267J298D01*
G02X1152154I986J997D01*
G03X1152168Y497287I281J-285D01*
G02X1152226Y495101I-1000J-1120D01*
G03Y494533I282J-284D01*
G02X1152209Y492384I-1058J-1066D01*
G37*
G36*
G01X507644Y492447D02*
G03X507630Y491864I267J-298D01*
G02X505658I-986J-997D01*
G03X505644Y492447I-281J285D01*
G02X505548Y494594I1000J1120D01*
G03Y495140I-292J273D01*
G02X505644Y497287I1096J1027D01*
G03X505658Y497870I-267J298D01*
G02X507630I986J997D01*
G03X507644Y497287I281J-285D01*
G02X507740Y495140I-1000J-1120D01*
G03Y494594I292J-273D01*
G02X507644Y492447I-1096J-1027D01*
G37*
G36*
G01X502601Y492384D02*
G03X502585Y491823I277J-289D01*
G02X500535I-1025J-956D01*
G03X500519Y492384I-293J272D01*
G02X500502Y494533I1041J1083D01*
G03Y495101I-282J284D01*
G02X500560Y497287I1058J1066D01*
G03X500574Y497870I-267J298D01*
G02X502546I986J997D01*
G03X502560Y497287I281J-285D01*
G02X502618Y495101I-1000J-1120D01*
G03Y494533I282J-284D01*
G02X502601Y492384I-1058J-1066D01*
G37*
G36*
G01X1185183Y492311D02*
G03X1185167Y491750I277J-289D01*
G02X1183117I-1025J-956D01*
G03X1183101Y492311I-293J272D01*
G02X1185183I1041J1083D01*
G37*
G36*
G01X1148356Y492538D02*
G03X1148372Y491977I293J-272D01*
G02X1146290I-1041J-1083D01*
G03X1146306Y492538I-277J289D01*
G02X1148356I1025J956D01*
G37*
G36*
G01X535575Y492311D02*
G03X535559Y491750I277J-289D01*
G02X533509I-1025J-956D01*
G03X533493Y492311I-293J272D01*
G02X535575I1041J1083D01*
G37*
G36*
G01X498748Y492538D02*
G03X498764Y491977I293J-272D01*
G02X496682I-1041J-1083D01*
G03X496698Y492538I-277J289D01*
G02X498748I1025J956D01*
G37*
G36*
G01X1202015Y492261D02*
G03X1201999Y491700I277J-289D01*
G02X1199949I-1025J-956D01*
G03X1199933Y492261I-293J272D01*
G02X1202015I1041J1083D01*
G37*
G36*
G01X552407D02*
G03X552391Y491700I277J-289D01*
G02X550341I-1025J-956D01*
G03X550325Y492261I-293J272D01*
G02X552407I1041J1083D01*
G37*
G36*
G01X951741Y492217D02*
G03X951725Y491656I277J-289D01*
G02X949675I-1025J-956D01*
G03X949659Y492217I-293J272D01*
G02X951741I1041J1083D01*
G37*
G36*
G01X887525Y492444D02*
G03X887541Y491883I293J-272D01*
G02X885459I-1041J-1083D01*
G03X885475Y492444I-277J289D01*
G02X887525I1025J956D01*
G37*
G36*
G01X302133Y492217D02*
G03X302117Y491656I277J-289D01*
G02X300067I-1025J-956D01*
G03X300051Y492217I-293J272D01*
G02X302133I1041J1083D01*
G37*
G36*
G01X235851Y491883D02*
G03X235867Y492444I-277J289D01*
G02X237917I1025J956D01*
G03X237933Y491883I293J-272D01*
G02X235851I-1041J-1083D01*
G37*
G36*
G01X939732Y492224D02*
G03X939718Y491641I267J-298D01*
G02X937746I-986J-997D01*
G03X937732Y492224I-281J285D01*
G02X937636Y494371I1000J1120D01*
G03Y494917I-292J273D01*
G02X937732Y497064I1096J1027D01*
G03X937746Y497647I-267J298D01*
G02X939718I986J997D01*
G03X939732Y497064I281J-285D01*
G02X939828Y494917I-1000J-1120D01*
G03Y494371I292J-273D01*
G02X939732Y492224I-1096J-1027D01*
G37*
G36*
G01X934623Y497652D02*
G03X934641Y497070I283J-283D01*
G02X934743Y494917I-994J-1126D01*
G03Y494371I292J-273D01*
G02X934641Y492218I-1096J-1027D01*
G03X934623Y491636I265J-299D01*
G02X932652Y491646I-991J-992D01*
G03X932640Y492229I-280J286D01*
G02X932551Y494371I1007J1115D01*
G03Y494917I-292J273D01*
G02X932640Y497059I1096J1027D01*
G03X932652Y497642I-268J297D01*
G02X934623Y497652I980J1002D01*
G37*
G36*
G01X930852Y492161D02*
G03X930836Y491600I277J-289D01*
G02X928786I-1025J-956D01*
G03X928770Y492161I-293J272D01*
G02X930852I1041J1083D01*
G37*
G36*
G01X288138Y491641D02*
G03X288124Y492224I-281J285D01*
G02X288028Y494371I1000J1120D01*
G03Y494917I-292J273D01*
G02X288124Y497064I1096J1027D01*
G03X288138Y497647I-267J298D01*
G02X290110I986J997D01*
G03X290124Y497064I281J-285D01*
G02X290220Y494917I-1000J-1120D01*
G03Y494371I292J-273D01*
G02X290124Y492224I-1096J-1027D01*
G03X290110Y491641I267J-298D01*
G02X288138I-986J-997D01*
G37*
G36*
G01X285033Y492218D02*
G03X285015Y491636I265J-299D01*
G02X283044Y491646I-991J-992D01*
G03X283032Y492229I-280J286D01*
G02X282943Y494371I1007J1115D01*
G03Y494917I-292J273D01*
G02X283032Y497059I1096J1027D01*
G03X283044Y497642I-268J297D01*
G02X285015Y497652I980J1002D01*
G03X285033Y497070I283J-283D01*
G02X285135Y494917I-994J-1126D01*
G03Y494371I292J-273D01*
G02X285033Y492218I-1096J-1027D01*
G37*
G36*
G01X281244Y492161D02*
G03X281228Y491600I277J-289D01*
G02X279178I-1025J-956D01*
G03X279162Y492161I-293J272D01*
G02X281244I1041J1083D01*
G37*
G36*
G01X1189019Y492126D02*
G03X1189003Y491565I277J-289D01*
G02X1186953I-1025J-956D01*
G03X1186937Y492126I-293J272D01*
G02X1186920Y494275I1041J1083D01*
G03Y494843I-282J284D01*
G02X1186978Y497029I1058J1066D01*
G03X1186992Y497612I-267J298D01*
G02X1188964I986J997D01*
G03X1188978Y497029I281J-285D01*
G02X1189036Y494843I-1000J-1120D01*
G03Y494275I282J-284D01*
G02X1189019Y492126I-1058J-1066D01*
G37*
G36*
G01X539411D02*
G03X539395Y491565I277J-289D01*
G02X537345I-1025J-956D01*
G03X537329Y492126I-293J272D01*
G02X537312Y494275I1041J1083D01*
G03Y494843I-282J284D01*
G02X537370Y497029I1058J1066D01*
G03X537384Y497612I-267J298D01*
G02X539356I986J997D01*
G03X539370Y497029I281J-285D01*
G02X539428Y494843I-1000J-1120D01*
G03Y494275I282J-284D01*
G02X539411Y492126I-1058J-1066D01*
G37*
G36*
G01X1258024Y491691D02*
G03X1257734Y491166I87J-390D01*
G02X1256064Y492140I-1414J-506D01*
G03X1256379Y492651I-68J394D01*
G02X1258024Y491691I1341J409D01*
G37*
G36*
G01X902921Y492094D02*
G03X902907Y491511I267J-298D01*
G02X900935I-986J-997D01*
G03X900921Y492094I-281J285D01*
G02X900825Y494241I1000J1120D01*
G03Y494787I-292J273D01*
G02X900921Y496934I1096J1027D01*
G03X900935Y497517I-267J298D01*
G02X902907I986J997D01*
G03X902921Y496934I281J-285D01*
G02X903017Y494787I-1000J-1120D01*
G03Y494241I292J-273D01*
G02X902921Y492094I-1096J-1027D01*
G37*
G36*
G01X897817Y492072D02*
G03X897791Y491490I261J-303D01*
G02X895816Y491528I-1007J-976D01*
G03X895813Y492110I-276J290D01*
G02X895778Y494275I1023J1099D01*
G03Y494843I-282J284D01*
G02X895776Y496973I1058J1066D01*
G03X895781Y497536I-282J284D01*
G02X897827Y497576I1004J978D01*
G03X897853Y497014I297J-268D01*
G02X897894Y494843I-1017J-1105D01*
G03Y494275I282J-284D01*
G02X897817Y492072I-1058J-1066D01*
G37*
G36*
G01X253313Y492094D02*
G03X253299Y491511I267J-298D01*
G02X251327I-986J-997D01*
G03X251313Y492094I-281J285D01*
G02X251217Y494241I1000J1120D01*
G03Y494787I-292J273D01*
G02X251313Y496934I1096J1027D01*
G03X251327Y497517I-267J298D01*
G02X253299I986J997D01*
G03X253313Y496934I281J-285D01*
G02X253409Y494787I-1000J-1120D01*
G03Y494241I292J-273D01*
G02X253313Y492094I-1096J-1027D01*
G37*
G36*
G01X248209Y492072D02*
G03X248183Y491490I261J-303D01*
G02X246208Y491528I-1007J-976D01*
G03X246205Y492110I-276J290D01*
G02X246170Y494275I1023J1099D01*
G03Y494843I-282J284D01*
G02X246168Y496973I1058J1066D01*
G03X246173Y497536I-282J284D01*
G02X248219Y497576I1004J978D01*
G03X248245Y497014I297J-268D01*
G02X248286Y494843I-1017J-1105D01*
G03Y494275I282J-284D01*
G02X248209Y492072I-1058J-1066D01*
G37*
G36*
G01X944974Y491957D02*
G03X944937Y491384I260J-304D01*
G02X942933Y491462I-1040J-940D01*
G03X942940Y492036I-275J290D01*
G02X944974Y491957I1060J1064D01*
G37*
G36*
G01X295366D02*
G03X295329Y491384I260J-304D01*
G02X293325Y491462I-1040J-940D01*
G03X293332Y492036I-275J290D01*
G02X295366Y491957I1060J1064D01*
G37*
G36*
G01X1414585Y488498D02*
G03X1414024Y488482I-272J-293D01*
G02Y490564I-1083J1041D01*
G03X1414585Y490548I289J277D01*
G02X1416538Y490509I956J-1025D01*
G03X1417121Y490523I285J281D01*
G02Y488523I1120J-1000D01*
G03X1416538Y488537I-298J-267D01*
G02X1414585Y488498I-997J986D01*
G37*
G36*
G01X1824125Y487418D02*
X1819124D01*
G02X1818209Y490132I1J1512D01*
G03X1818223Y490756I-243J318D01*
G02X1820297Y491061I902J1074D01*
G03X1820632Y490442I335J-219D01*
G01X1822618D01*
G03X1822953Y491061I0J400D01*
G02X1825027Y490756I1172J769D01*
G03X1825041Y490132I257J-306D01*
G02X1825636Y488940I-916J-1202D01*
G01Y488845D01*
X1825627Y488761D01*
G02X1824125Y487418I-1502J169D01*
G37*
G36*
G01X1249993Y490037D02*
G03X1249842Y489533I213J-338D01*
G02X1247674Y490184I-1368J-620D01*
G03X1247825Y490688I-213J338D01*
G02X1249993Y490037I1368J620D01*
G37*
G36*
G01X1384569Y488374D02*
G03X1385157Y488363I299J265D01*
G02X1385068Y486385I1084J-1040D01*
G03X1384481Y486426I-312J-250D01*
G02X1382475Y486509I-963J1019D01*
G03X1381875Y486504I-298J-267D01*
G02X1381906Y488437I-1134J985D01*
G03X1382505Y488413I310J253D01*
G02X1384569Y488374I1014J-968D01*
G37*
G36*
G01X1270829Y486076D02*
G03X1270262Y485945I-222J-333D01*
G02X1269767Y487855I-1212J705D01*
G03X1270327Y488015I205J343D01*
G02X1270829Y486076I1335J-689D01*
G37*
G36*
G01X1852090Y486211D02*
G03X1851560Y486017I-168J-363D01*
G02X1850807Y487913I-1270J593D01*
G03X1851326Y488136I148J372D01*
G02X1852090Y486211I1393J-561D01*
G37*
G36*
G01X721918Y486830D02*
G03X721707Y486326I164J-365D01*
G02X719683Y487170I-1407J-526D01*
G03X719894Y487674I-164J365D01*
G02X721903Y489576I1407J526D01*
G03X722427Y489775I161J366D01*
G02X723190Y487772I1365J-627D01*
G03X722666Y487573I-161J-366D01*
G02X721918Y486830I-1365J627D01*
G37*
G36*
G01X1256886Y484677D02*
G03X1256664Y484137I142J-374D01*
G02X1254822Y484840I-1276J-580D01*
G03X1255016Y485390I-161J366D01*
G02X1256886Y484677I1334J690D01*
G37*
G36*
G01X1382632Y481490D02*
G03X1382079I-277J-289D01*
G02X1382138Y483601I-1038J1085D01*
G03X1382690Y483570I292J273D01*
G02X1384528Y483555I910J-1066D01*
G03X1385097Y483596I264J300D01*
G02X1385189Y481551I1144J-973D01*
G03X1384618Y481540I-280J-286D01*
G02X1382632Y481490I-1018J964D01*
G37*
G36*
G01X1291632Y481713D02*
G03Y481187I302J-263D01*
G02X1289368I-1132J-987D01*
G03Y481713I-302J263D01*
G02X1291632I1132J987D01*
G37*
G36*
G01X1270997Y480678D02*
G03X1271240Y480465I199J-18D01*
G02X1270069Y478999I331J-1465D01*
G03X1269654Y479399I-400J0D01*
G02X1269715Y482197I-55J1401D01*
G03X1270147Y482576I32J399D01*
G02X1271253Y481050I1500J-76D01*
G03X1271001Y480850I-52J-193D01*
G02X1270997Y480678I-1401J-53D01*
G37*
G36*
G01X1416805Y478478D02*
G03X1417354Y478455I287J279D01*
G02X1417207Y476338I987J-1132D01*
G03X1416659Y476392I-302J-262D01*
G02X1414806Y476512I-859J1108D01*
G03X1414211Y476481I-284J-282D01*
G02X1414156Y478429I-1170J942D01*
G03X1414752Y478431I297J268D01*
G02X1416805Y478478I1048J-931D01*
G37*
G36*
G01X1842565Y474801D02*
G03X1841935I-315J-246D01*
G02Y476647I-1185J923D01*
G03X1842565I315J246D01*
G02Y474801I1185J-923D01*
G37*
G36*
G01X-13433Y472543D02*
G03X-13555Y471963I202J-345D01*
G02X-15455Y472315I-1135J-823D01*
G03X-15362Y472900I-219J335D01*
G02X-13124Y474898I1171J941D01*
G03X-12556I284J282D01*
G02Y472782I1066J-1058D01*
G03X-13124I-284J-282D01*
G02X-13433Y472543I-1066J1058D01*
G37*
G36*
G01X1803007Y472444D02*
G03X1802672Y471824I-1J-400D01*
G02X1800608Y472136I-1172J-769D01*
G03X1800598Y472761I-255J309D01*
G02X1801525Y475466I927J1194D01*
G01X1806525D01*
G02X1808036Y473965I0J-1511D01*
G01Y473870D01*
X1808027Y473786D01*
G02X1807472Y472777I-1502J169D01*
G03X1807473Y472152I250J-312D01*
G02X1805428Y471824I-873J-1097D01*
G03X1805093Y472444I-334J220D01*
G01X1803007D01*
G37*
G36*
G01X1895773Y469104D02*
G03X1895227I-273J-292D01*
G02X1893093Y471215I-1027J1096D01*
G03X1893081Y471497I-148J135D01*
G02X1895127Y473696I1019J1103D01*
G03X1895673I273J292D01*
G02X1897759Y473665I1027J-1096D01*
G03X1898041I141J142D01*
G02X1900127Y473696I1059J-1065D01*
G03X1900673I273J292D01*
G02X1902642Y473770I1027J-1096D01*
G03X1903168Y473791I251J311D01*
G02X1905307Y471685I1032J-1091D01*
G03X1905319Y471403I148J-135D01*
G02X1903358Y469130I-1020J-1102D01*
G03X1902832Y469109I-251J-311D01*
G02X1900773Y469104I-1032J1091D01*
G03X1900227I-273J-292D01*
G02X1898141Y469135I-1027J1096D01*
G03X1897859I-141J-142D01*
G02X1895773Y469104I-1059J1065D01*
G37*
G36*
G01X1378802Y457185D02*
G03X1378191Y457175I-301J-263D01*
G02X1378202Y459061I-1163J950D01*
G03X1378813Y459044I313J250D01*
G02X1378802Y457185I1044J-936D01*
G37*
G36*
G01X1641076Y458558D02*
G03X1641055Y457969I260J-304D01*
G02X1639024Y458042I-1055J-1069D01*
G03X1639045Y458631I-260J304D01*
G02X1641076Y458558I1055J1069D01*
G37*
G36*
G01X1412503Y453247D02*
G03X1411898Y453052I-228J-329D01*
G02X1408964Y453561I-1423J510D01*
G01Y457561D01*
G02X1411565Y458608I1511J0D01*
G03X1412124Y458592I288J278D01*
G02X1413829Y456379I950J-1031D01*
G03X1413878Y455677I214J-338D01*
G02X1412503Y453247I-577J-1278D01*
G37*
G36*
G01X1404424Y452530D02*
G03X1403865Y452514I-271J-294D01*
G02X1401264Y453561I-1090J1047D01*
G01Y457561D01*
G02X1404191Y458091I1511J0D01*
G03X1404797Y457904I375J139D01*
G02X1404891Y455556I811J-1143D01*
G03X1404286Y455212I-205J-344D01*
G01Y454894D01*
G03X1404597Y454728I200J0D01*
G02X1404424Y452530I778J-1167D01*
G37*
G36*
G01X1397201Y452659D02*
G03X1396577Y452645I-306J-257D01*
G02X1393864Y453561I-1202J916D01*
G01Y457562D01*
G02X1396465Y458608I1511J-1D01*
G03X1397024Y458592I288J278D01*
G02X1397439Y456265I951J-1031D01*
G03X1396886Y455896I-153J-370D01*
G01Y455068D01*
G03X1397506Y454733I400J-1D01*
G02X1397201Y452659I769J-1172D01*
G37*
G36*
G01X1430776Y452503D02*
G03X1430171Y452496I-299J-265D01*
G02X1430104Y454378I-1071J904D01*
G03X1430708Y454414I286J279D01*
G02X1430776Y452503I1192J-914D01*
G37*
G36*
G01X1430078Y448896D02*
G03X1430704Y448909I308J255D01*
G02Y447091I1196J-909D01*
G03X1430078Y447104I-318J-242D01*
G02Y448896I-1078J896D01*
G37*
G36*
G01X-15859Y446824D02*
G03X-15841Y447426I-254J309D01*
G02X-13489Y449585I1088J1175D01*
G03X-12870Y449571I315J246D01*
G02X-10591Y447330I1218J-1041D01*
G03Y446730I265J-300D01*
G02X-12945Y444584I-1061J-1200D01*
G03X-13582Y444595I-323J-236D01*
G02X-15859Y446824I-1257J994D01*
G37*
G36*
G01X1430078Y443496D02*
G03X1430704Y443509I308J255D01*
G02Y441691I1196J-909D01*
G03X1430078Y441704I-318J-242D01*
G02Y443496I-1078J896D01*
G37*
G36*
G01X1413434Y442480D02*
G03X1413457Y441892I282J-283D01*
G02X1411425Y441813I-973J-1144D01*
G03X1411402Y442401I-282J283D01*
G02X1413434Y442480I973J1144D01*
G37*
G36*
G01X1409123Y439924D02*
G03Y439309I257J-307D01*
G02X1407327I-898J-1076D01*
G03Y439924I-257J307D01*
G02X1409123I898J1076D01*
G37*
G36*
G01X1430066Y437970D02*
G03X1430692Y437992I304J260D01*
G02X1430717Y436174I1208J-893D01*
G03X1430091Y436179I-315J-246D01*
G02X1430066Y437970I-1091J880D01*
G37*
G36*
G01X1622082Y434967D02*
G03X1622106Y434426I306J-257D01*
G02X1619954Y434397I-1062J-1062D01*
G03X1619962Y434938I-290J275D01*
G02X1622082Y434967I1047J932D01*
G37*
G36*
G01X1640632Y434713D02*
G03Y434187I302J-263D01*
G02X1638368I-1132J-987D01*
G03Y434713I-302J263D01*
G02X1640632I1132J987D01*
G37*
G36*
G01X1410949Y428744D02*
G03X1410390Y428728I-271J-294D01*
G02X1407788Y429775I-1090J1047D01*
G01Y434776D01*
G02X1410390Y435822I1512J-1D01*
G03X1410949Y435806I288J278D01*
G02X1411364Y433479I951J-1031D01*
G03X1410812Y433110I-152J-369D01*
G01Y431440D01*
G03X1411364Y431071I400J0D01*
G02X1410949Y428744I536J-1296D01*
G37*
G36*
G01X1408670Y416575D02*
Y416490D01*
X1408660Y416406D01*
G02X1406068Y415528I-1502J169D01*
G03X1405509Y415544I-288J-278D01*
G02X1405094Y417871I-951J1031D01*
G03X1405646Y418240I152J369D01*
G01Y419910D01*
G03X1405094Y420279I-400J0D01*
G02X1405509Y422606I-536J1296D01*
G03X1406068Y422622I271J294D01*
G02X1408670Y421585I1090J-1047D01*
G01Y416575D01*
G37*
G36*
G01X1414187Y415755D02*
G03X1413637Y415626I-210J-340D01*
G02X1412950Y417677I-1190J742D01*
G03X1413493Y418037I143J373D01*
G01X1413568Y420270D01*
G03X1413030Y420658I-400J13D01*
G02X1413507Y422994I-485J1316D01*
G03X1414067Y423005I274J291D01*
G02X1416647Y422124I1079J-1059D01*
G01X1416668Y421948D01*
X1416504Y417042D01*
X1416505D01*
X1416502Y416988D01*
X1416477Y416817D01*
G02X1414187Y415755I-1495J223D01*
G37*
G36*
G01X1395715Y411577D02*
G03X1395085I-315J-246D01*
G02X1392768Y413487I-1185J923D01*
G03Y414013I-302J263D01*
G02X1393857Y416501I1132J987D01*
G03X1394241Y416963I-11J400D01*
G02X1397190Y416864I1484J231D01*
G03X1397438Y416403I390J-87D01*
G02X1398032Y414013I-538J-1403D01*
G03Y413487I302J-263D01*
G02X1395715Y411577I-1132J-987D01*
G37*
G36*
G01X1469246Y411044D02*
G03X1468646Y410912I-245J-316D01*
G02X1468261Y412665I-1245J645D01*
G03X1468861Y412797I245J316D01*
G02X1471147Y413091I1245J-645D01*
G03X1471720Y413069I297J268D01*
G02X1471647Y411116I968J-1014D01*
G03X1471074Y411138I-297J-268D01*
G02X1469246Y411044I-969J1014D01*
G37*
G36*
G01X1613619Y410798D02*
G03X1613687Y410204I298J-267D01*
G02X1611706Y409976I-862J-1230D01*
G03X1611638Y410570I-298J267D01*
G02X1613619Y410798I862J1230D01*
G37*
G36*
G01X1404351Y407216D02*
G03X1403769Y407201I-284J-282D01*
G02X1403337Y409397I-1044J935D01*
G03X1403912Y409757I175J360D01*
G01Y411741D01*
G03X1403291Y412075I-400J0D01*
G02X1403584Y414159I-771J1171D01*
G03X1404209Y414181I304J260D01*
G02X1406934Y413291I1214J-900D01*
G01Y408281D01*
Y408196D01*
X1406925Y408112D01*
G02X1404351Y407216I-1502J169D01*
G37*
G36*
G01X1444170Y407840D02*
G03X1444081Y407303I245J-316D01*
G02X1441912Y407661I-1251J-831D01*
G03X1442001Y408198I-245J316D01*
G02X1444170Y407840I1251J831D01*
G37*
G36*
G01X1439722Y402344D02*
G03X1439270Y402030I-60J-395D01*
G02X1438109Y403701I-1373J285D01*
G03X1438561Y404015I60J395D01*
G02X1439722Y402344I1373J-285D01*
G37*
G36*
G01X1600934Y399614D02*
G03X1600499Y399190I-36J-399D01*
G02X1599226Y400496I-1399J-90D01*
G03X1599661Y400920I36J399D01*
G02X1600934Y399614I1399J90D01*
G37*
G36*
G01X1586703Y396411D02*
G03X1586141Y396408I-279J-286D01*
G02X1586130Y398403I-991J992D01*
G03X1586692Y398406I279J286D01*
G02X1586703Y396411I991J-992D01*
G37*
G36*
G01X1483330Y395541D02*
G03X1483907Y395319I380J126D01*
G02X1483270Y393657I693J-1219D01*
G03X1482693Y393879I-380J-126D01*
G02X1483330Y395541I-693J1219D01*
G37*
G36*
G01X1390389Y388000D02*
G03X1390877Y387664I396J53D01*
G02X1389821Y386045I323J-1364D01*
G03X1389317Y386357I-393J-72D01*
G02X1390389Y388000I-417J1443D01*
G37*
G36*
G01X1465489Y384283D02*
G03X1465497Y383746I300J-264D01*
G02X1463272Y383712I-1097J-1026D01*
G03X1463264Y384249I-300J264D01*
G02X1465489Y384283I1097J1026D01*
G37*
G36*
G01X1571657Y384060D02*
G03X1571944Y383585I390J-89D01*
G02X1570217Y382538I-359J-1355D01*
G03X1569930Y383013I-390J89D01*
G02X1571657Y384060I359J1355D01*
G37*
G36*
G01X1598084Y374944D02*
G03X1597506Y374715I-196J-348D01*
G02X1596711Y376427I-1338J419D01*
G03X1597266Y376796I155J369D01*
G01Y379733D01*
G03X1596708Y380100I-400J0D01*
G02X1597452Y381908I-557J1286D01*
G03X1598033Y381716I371J149D01*
G02X1600490Y380354I845J-1372D01*
G01Y376261D01*
X1600480Y376176D01*
G02X1598084Y374944I-1602J170D01*
G37*
G36*
G01X1419006Y374775D02*
G03X1419614Y374659I351J191D01*
G02X1419282Y372917I901J-1074D01*
G03X1418674Y373033I-351J-191D01*
G02X1419006Y374775I-901J1074D01*
G37*
G36*
G01X1611178Y373839D02*
G03X1610982Y373273I152J-370D01*
G02X1609225Y373880I-1221J-689D01*
G03X1609421Y374446I-152J370D01*
G02X1609377Y374530I1219J692D01*
G03X1608843Y374718I-361J-172D01*
G02X1606534Y376171I-697J1453D01*
G01Y380322D01*
G02X1608956Y381715I1612J0D01*
G03X1609528Y381911I201J346D01*
G02X1610306Y380086I1300J-524D01*
G03X1609758Y379714I-148J-371D01*
G01Y376871D01*
G03X1610265Y376485I400J-1D01*
G02X1611178Y373839I377J-1350D01*
G37*
G36*
G01X1598949Y368925D02*
G03X1598939Y368364I280J-286D01*
G02X1596801Y368404I-1089J-1035D01*
G03X1596811Y368965I-280J286D01*
G02X1598949Y368925I1089J1035D01*
G37*
G36*
G01X1568092Y364806D02*
G03Y364228I277J-289D01*
G02X1566150I-971J-1011D01*
G03Y364806I-277J289D01*
G02X1568092I971J1011D01*
G37*
G36*
G01X1544362Y362485D02*
G03X1544378Y361946I303J-261D01*
G02X1542222I-1078J-1046D01*
G03X1542238Y362485I-287J278D01*
G02X1544362I1062J915D01*
G37*
G36*
G01X1534878Y361828D02*
G03X1534893Y361302I309J-254D01*
G02X1532631Y361238I-1103J-1019D01*
G03X1532616Y361764I-309J254D01*
G02X1534878Y361828I1103J1019D01*
G37*
G36*
G01X1571900Y361457D02*
G03X1572073Y360906I350J-193D01*
G02X1570222Y360327I-623J-1256D01*
G03X1570049Y360878I-350J193D01*
G02X1571900Y361457I623J1256D01*
G37*
G36*
G01X1539569Y360921D02*
G03X1539590Y360396I312J-250D01*
G02X1537328Y360303I-1090J-1033D01*
G03X1537307Y360828I-312J250D01*
G02X1537382Y362968I1090J1033D01*
G03X1537354Y363582I-270J295D01*
G02X1539193Y363710I846J1118D01*
G03X1539249Y363098I283J-283D01*
G02X1539569Y360921I-852J-1237D01*
G37*
G36*
G01X1479711Y360646D02*
G03X1479710Y360102I293J-273D01*
G02X1477508Y360106I-1103J-1020D01*
G03X1477509Y360650I-293J273D01*
G02X1479711Y360646I1103J1020D01*
G37*
G36*
G01X1588073Y357304D02*
G03X1587527I-273J-292D01*
G02Y359496I-1027J1096D01*
G03X1588073I273J292D01*
G02Y357304I1027J-1096D01*
G37*
G36*
G01X1489450Y359356D02*
G03Y358778I277J-289D01*
G02X1487508I-971J-1011D01*
G03Y359356I-277J289D01*
G02Y361378I971J1011D01*
G03Y361956I-277J289D01*
G02X1487437Y363905I971J1011D01*
G03X1487418Y364460I-297J268D01*
G02X1489436Y364528I976J1006D01*
G03X1489455Y363973I297J-268D01*
G02X1489450Y361956I-976J-1006D01*
G03Y361378I277J-289D01*
G02Y359356I-971J-1011D01*
G37*
G36*
G01X1521344Y356119D02*
G03X1521384Y355539I294J-271D01*
G02X1519378Y355452I-955J-1160D01*
G03X1519368Y356033I-280J286D01*
G02X1521344Y356119I945J1036D01*
G37*
G36*
G01X1525756Y355744D02*
G03Y355190I288J-277D01*
G02X1523736I-1010J-973D01*
G03Y355744I-288J277D01*
G02Y357690I1010J973D01*
G03Y358244I-288J277D01*
G02X1525756I1010J973D01*
G03Y357690I288J-277D01*
G02Y355744I-1010J-973D01*
G37*
G36*
G01X1508090Y354790D02*
G03X1508067Y354164I237J-322D01*
G02X1506276Y354193I-913J-1064D01*
G03X1506272Y354819I-251J311D01*
G02X1506142Y357066I928J1181D01*
G03Y357634I-282J284D01*
G02X1508258I1058J1066D01*
G03Y357066I282J-284D01*
G02X1508090Y354790I-1058J-1066D01*
G37*
G36*
G01X1539574Y352267D02*
G03Y351721I292J-273D01*
G02X1537382I-1096J-1027D01*
G03Y352267I-292J273D01*
G02Y354321I1096J1027D01*
G03Y354867I-292J273D01*
G02X1539574I1096J1027D01*
G03Y354321I292J-273D01*
G02Y352267I-1096J-1027D01*
G37*
G36*
G01X1416557Y352133D02*
G03X1416547Y351576I282J-284D01*
G02X1414393Y351617I-1097J-1026D01*
G03X1414403Y352174I-282J284D01*
G02X1416557Y352133I1097J1026D01*
G37*
G36*
G01X1447471Y350639D02*
G03X1447011Y350262I-61J-395D01*
G02X1445811Y351799I-1501J65D01*
G03X1446289Y352154I80J392D01*
G02X1447471Y350639I1396J-129D01*
G37*
G36*
G01X1482962Y350420D02*
G03X1482502Y350019I-60J-395D01*
G02X1481293Y351473I-1502J-19D01*
G03X1481771Y351852I78J392D01*
G02X1482962Y350420I1401J-46D01*
G37*
G36*
G01X1526799Y351103D02*
G03X1527355Y350999I330J226D01*
G02X1527035Y348987I791J-1157D01*
G03X1526475Y349061I-317J-244D01*
G02X1526799Y351103I-914J1192D01*
G37*
G36*
G01X1491025Y351625D02*
G03Y351087I296J-269D01*
G02X1488716Y351155I-1187J-1076D01*
G03X1488747Y351692I-280J286D01*
G02X1491025Y351625I1168J945D01*
G37*
G36*
G01X1556464Y340062D02*
G03X1555886I-289J-276D01*
G02Y342138I-1086J1038D01*
G03X1556464I289J276D01*
G02Y340062I1086J-1038D01*
G37*
G36*
G01X1564815Y340077D02*
G03X1564185I-315J-246D01*
G02Y341923I-1185J923D01*
G03X1564815I315J246D01*
G02Y340077I1185J-923D01*
G37*
G36*
G01X1582772Y337666D02*
G03X1582218Y337657I-272J-293D01*
G02X1579665Y339528I-1129J1137D01*
G03X1579532Y340043I-355J183D01*
G02X1581432Y342350I833J1250D01*
G03X1581956Y342312I284J282D01*
G02X1584272Y340602I903J-1200D01*
G03X1584468Y340109I376J-136D01*
G02X1582772Y337666I-674J-1342D01*
G37*
G36*
G01X1488901Y339331D02*
G03X1488924Y338735I278J-288D01*
G02X1486845Y338702I-1020J-1235D01*
G03X1486850Y339299I-264J301D01*
G02X1488901Y339331I1008J1113D01*
G37*
G36*
G01X1621029Y337649D02*
G03Y337123I302J-263D01*
G02X1618765I-1132J-987D01*
G03Y337649I-302J263D01*
G02Y339623I1132J987D01*
G03Y340149I-302J263D01*
G02X1621029I1132J987D01*
G03Y339623I302J-263D01*
G02Y337649I-1132J-987D01*
G37*
G36*
G01X1473398Y336467D02*
G03X1473409Y335868I270J-295D01*
G02X1471552Y335833I-909J-1068D01*
G03X1471541Y336432I-270J295D01*
G02X1473398Y336467I909J1068D01*
G37*
G36*
G01X1417025Y334544D02*
G03X1417041Y333983I293J-272D01*
G02X1414959I-1041J-1083D01*
G03X1414975Y334544I-277J289D01*
G02X1415029Y336511I1025J956D01*
G03Y337089I-277J289D01*
G02X1416971I971J1011D01*
G03Y336511I277J-289D01*
G02X1417025Y334544I-971J-1011D01*
G37*
G36*
G01X1526831Y328837D02*
G03X1526297Y328715I-202J-345D01*
G02X1525881Y330805I-1246J838D01*
G03X1526421Y330896I222J333D01*
G02X1526831Y328837I1116J-848D01*
G37*
G36*
G01X1493897Y327606D02*
G03X1494044Y327097I361J-171D01*
G02X1491883Y326472I-804J-1269D01*
G03X1491736Y326981I-361J171D01*
G02X1493897Y327606I804J1269D01*
G37*
G36*
G01X1402557Y320058D02*
G03X1402014Y319787I-155J-369D01*
G02X1401204Y321513I-1456J370D01*
G03X1401759Y321758I172J361D01*
G02X1402557Y320058I1341J-408D01*
G37*
G36*
G01X1390804Y320819D02*
G03X1391374Y320695I343J205D01*
G02X1390899Y318754I852J-1237D01*
G03X1390336Y318907I-353J-188D01*
G02X1390804Y320819I-736J1193D01*
G37*
G36*
G01X1412363Y315134D02*
G03X1411804Y315121I-273J-292D01*
G02X1411698Y317177I-1004J979D01*
G03X1412255Y317221I256J307D01*
G02X1412363Y315134I1132J-988D01*
G37*
G36*
G01X1399769Y315079D02*
G03X1399226Y314962I-211J-340D01*
G02X1398731Y316975I-1164J781D01*
G03X1399266Y317123I191J352D01*
G02X1399769Y315079I1292J-766D01*
G37*
G36*
G01X1382261Y316591D02*
G03X1382848Y316432I361J171D01*
G02X1382401Y314616I791J-1158D01*
G03X1381808Y314747I-353J-189D01*
G02X1382261Y316591I-904J1200D01*
G37*
G36*
G01X1391309Y314468D02*
G03X1390740Y314384I-244J-317D01*
G02X1390397Y316354I-1140J816D01*
G03X1390961Y316467I227J329D01*
G02X1391309Y314468I1265J-810D01*
G37*
G36*
G01X4991Y303270D02*
G03X5621I315J246D01*
G02Y301424I1185J-923D01*
G03X4991I-315J-246D01*
G02Y303270I-1185J923D01*
G37*
G36*
G01X1399674Y283320D02*
G03X1399796Y282806I353J-188D01*
G02X1397599Y282285I-870J-1224D01*
G03X1397477Y282799I-353J188D01*
G02X1399674Y283320I870J1224D01*
G37*
G36*
G01X1494802Y282343D02*
G03X1495428Y282340I314J247D01*
G02X1495381Y280523I1172J-939D01*
G03X1494755Y280553I-325J-234D01*
G02X1494802Y282343I-1055J923D01*
G37*
G36*
G01X1434494Y279757D02*
G03Y279231I302J-263D01*
G02X1432230I-1132J-987D01*
G03Y279757I-302J263D01*
G02X1434494I1132J987D01*
G37*
G36*
G01X1412460Y270222D02*
G03X1412796Y269759I394J-67D01*
G02X1411098Y268524I-217J-1486D01*
G03X1410762Y268987I-394J67D01*
G02X1412460Y270222I217J1486D01*
G37*
G36*
G01X1455263Y261007D02*
G03X1455172Y260470I243J-317D01*
G02X1452695Y260212I-1172J-770D01*
G03X1452223Y260745I-373J146D01*
G02X1452837Y263332I-373J1455D01*
G03X1453363I263J302D01*
G02X1455263Y261007I987J-1133D01*
G37*
G36*
G01X1465935Y255246D02*
G03X1466012Y254708I329J-227D01*
G02X1463722Y252867I-949J-1164D01*
G03X1463226Y253062I-357J-180D01*
G02X1462793Y255969I-523J1408D01*
G03X1463213Y256312I24J399D01*
G02X1465935Y255246I1487J-212D01*
G37*
G36*
G01X1469388Y253942D02*
G03X1469928Y253946I268J297D01*
G02X1469881Y251791I1022J-1100D01*
G03X1469342Y251818I-284J-281D01*
G02X1469388Y253942I-892J1082D01*
G37*
G36*
G01X1588951Y251113D02*
G03X1588396Y250860I-170J-362D01*
G02X1587591Y252626I-1446J407D01*
G03X1588146Y252879I170J362D01*
G02X1588951Y251113I1446J-407D01*
G37*
G36*
G01X1501399Y249908D02*
G03X1500833Y249734I-204J-344D01*
G02X1500238Y251662I-1361J636D01*
G03X1500804Y251836I204J344D01*
G02X1501399Y249908I1361J-636D01*
G37*
G36*
G01X1510804Y246222D02*
G03X1510800Y245658I282J-284D01*
G02X1508810Y245669I-1000J-982D01*
G03X1508814Y246233I-282J284D01*
G02X1510804Y246222I1000J982D01*
G37*
G36*
G01X1548542Y245073D02*
G03X1548652Y244519I333J-222D01*
G02X1546702Y244133I-783J-1163D01*
G03X1546592Y244687I-333J222D01*
G02X1548542Y245073I783J1163D01*
G37*
G36*
G01X1515570Y244955D02*
G03Y244424I299J-266D01*
G02X1513172Y244422I-1198J-1063D01*
G03Y244953I-299J265D01*
G02X1513153Y247057I1198J1063D01*
G03Y247577I-304J260D01*
G02X1515589Y247575I1219J1039D01*
G03Y247055I304J-260D01*
G02X1515570Y244955I-1219J-1039D01*
G37*
G36*
G01X1572177Y234534D02*
G03X1571660Y234315I-147J-372D01*
G02X1569495Y236175I-1388J574D01*
G03X1569505Y236853I-207J342D01*
G02X1570758Y239552I813J1263D01*
G03X1571259Y239822I117J383D01*
G02X1573042Y240863I1442J-422D01*
G03X1573525Y241174I91J389D01*
G02X1575454Y239612I1375J-274D01*
G03X1575391Y238911I158J-368D01*
G02X1574611Y236159I-831J-1251D01*
G03X1574226Y235795I13J-400D01*
G02X1572177Y234534I-1496J136D01*
G37*
G36*
G01X1560964Y236097D02*
G03X1561303Y235643I396J-58D01*
G02X1559717Y234458I-199J-1388D01*
G03X1559378Y234912I-396J58D01*
G02X1560964Y236097I199J1388D01*
G37*
G36*
G01X1499773Y233137D02*
G03X1500019Y232603I369J-154D01*
G02X1498202Y231818I-460J-1430D01*
G03X1497982Y232363I-361J171D01*
G02X1499773Y233137I496J1312D01*
G37*
G36*
G01X-10353Y231081D02*
G03X-10281Y230458I283J-283D01*
G02X-13953Y229950I-1530J-2466D01*
G03X-14215Y230618I-295J270D01*
G02X-15160Y233402I131J1597D01*
G03X-15169Y234002I-269J296D01*
G02X-13068Y236421I1040J1219D01*
G03X-12540Y236420I265J300D01*
G02X-10423Y234015I1056J-1205D01*
G03Y233415I265J-300D01*
G02X-10353Y231081I-1061J-1200D01*
G37*
G36*
G01X1401311Y222717D02*
G03X1400689I-311J-252D01*
G02Y224483I-1089J883D01*
G03X1401311I311J252D01*
G02Y222717I1089J-883D01*
G37*
G36*
G01X1492365Y219956D02*
G03X1492298Y219394I247J-314D01*
G02X1490272Y219582I-1102J-867D01*
G03X1490309Y220146I-264J301D01*
G02X1492365Y219956I1128J991D01*
G37*
G36*
G01X1768Y225347D02*
G03X1854Y225972I-201J346D01*
G02X6019Y225971I2083J2020D01*
G03X6080Y225363I287J-278D01*
G02X6304Y222908I-907J-1320D01*
G03X6325Y222322I282J-283D01*
G02X6573Y220169I-1048J-1212D01*
G03X6618Y219647I324J-235D01*
G02X4305Y219567I-1118J-1147D01*
G03X4280Y219856I-150J133D01*
G02X4161Y219961I999J1252D01*
G03X3873Y219951I-139J-144D01*
G02X1553Y222158I-1195J1067D01*
G03X1532Y222746I-281J284D01*
G02X1525Y222752I1039J1219D01*
G03X1005Y222756I-262J-302D01*
G02X1023Y225193I-1031J1226D01*
G03X1543Y225189I262J302D01*
G02X1768Y225347I1030J-1227D01*
G37*
G36*
G01X1517619Y204557D02*
G03X1517615Y204002I286J-280D01*
G02X1515595Y204017I-1017J-965D01*
G03X1515599Y204572I-286J280D01*
G02X1517619Y204557I1017J965D01*
G37*
G36*
G01X2340Y206793D02*
G03X2368Y207104I-110J167D01*
G02X2281Y207194I1107J1158D01*
G03X1992Y207204I-149J-133D01*
G02X-193Y209546I-1117J1148D01*
G03Y210142I-267J298D01*
G02X1949Y212525I1068J1194D01*
G03X2468Y212510I268J296D01*
G02X4500Y212493I1006J-1247D01*
G03X5020Y212499I256J307D01*
G02X7148Y210104I1054J-1206D01*
G03Y209510I268J-297D01*
G02X6461Y206767I-1074J-1189D01*
G03X6240Y206135I97J-388D01*
G02X2340Y206793I-2303J-1765D01*
G37*
G36*
G01X-6028Y201618D02*
G03X-5934Y202265I-181J357D01*
G02X-1974Y202233I1997J2105D01*
G03X-1902Y201591I271J-295D01*
G02X-3735Y198979I-798J-1389D01*
G03X-4255Y198977I-259J-305D01*
G02X-6340Y198973I-1045J1214D01*
G03X-6860I-260J-304D01*
G02Y201409I-1040J1218D01*
G03X-6340I260J304D01*
G02X-6028Y201618I1041J-1217D01*
G37*
G36*
G01X1546924Y199009D02*
G03X1546944Y198437I289J-276D01*
G02X1544986Y198368I-944J-1037D01*
G03X1544966Y198940I-289J276D01*
G02X1546924Y199009I944J1037D01*
G37*
G36*
G01X-12582Y201244D02*
G03X-12649Y201592I-125J156D01*
G02X-10427Y201819I839J2778D01*
G03X-10506Y201172I191J-352D01*
G02X-10525Y198789I-1080J-1183D01*
G03Y198189I265J-300D01*
G02X-12626Y195771I-1061J-1200D01*
G03X-13146I-260J-304D01*
G02X-15247Y198189I-1040J1218D01*
G03Y198789I-265J300D01*
G02X-13146Y201207I1061J1200D01*
G03X-12626I260J304D01*
G02X-12582Y201244I1053J-1207D01*
G37*
G36*
G01X1211058Y194169D02*
G03X1211044Y193580I264J-301D01*
G02X1209012Y193631I-1044J-1080D01*
G03X1209026Y194220I-264J301D01*
G02X1211058Y194169I1044J1080D01*
G37*
G36*
G01X1494307Y176588D02*
G03X1493800Y176362I-136J-376D01*
G02X1491426Y177789I-1300J526D01*
G03X1491404Y178328I-306J257D01*
G02X1493956Y179600I1065J1059D01*
G03X1494447Y179268I396J56D01*
G02X1494307Y176588I336J-1361D01*
G37*
G36*
G01X1472982Y172651D02*
G03X1472443Y172631I-259J-305D01*
G02X1472425Y174787I-1055J1069D01*
G03X1472964Y174776I276J290D01*
G02X1472982Y172651I924J-1055D01*
G37*
G36*
G01X1503113Y165928D02*
G03X1503655Y165944I262J302D01*
G02Y163798I1051J-1073D01*
G03X1503113Y163814I-280J-286D01*
G02Y165928I-921J1057D01*
G37*
G36*
G01X1536462Y164418D02*
G03X1536958Y164063I399J33D01*
G02X1535901Y162585I340J-1360D01*
G03X1535405Y162940I-399J-33D01*
G02X1536462Y164418I-340J1360D01*
G37*
G36*
G01X1265136Y151576D02*
G03X1265691Y151567I282J284D01*
G02X1265656Y149548I955J-1026D01*
G03X1265101Y149557I-282J-284D01*
G02X1263135Y149613I-955J1027D01*
G03X1262557I-289J-277D01*
G02Y151555I-1011J971D01*
G03X1263135I289J277D01*
G02X1265136Y151576I1011J-971D01*
G37*
G36*
G01X1921Y93995D02*
G03X2176Y94476I-131J378D01*
G02X4503Y95850I1354J364D01*
G03X5057I277J288D01*
G02X7003I973J-1010D01*
G03X7557I277J288D01*
G02X9503I973J-1010D01*
G03X10057I277J288D01*
G02X12003I973J-1010D01*
G03X12557I277J288D01*
G02X14503I973J-1010D01*
G03X15057I277J288D01*
G02X17003I973J-1010D01*
G03X17557I277J288D01*
G02X19503I973J-1010D01*
G03X20057I277J288D01*
G02X22003I973J-1010D01*
G03X22557I277J288D01*
G02X24895Y94518I973J-1010D01*
G03X25194Y94036I389J-92D01*
G02X23907Y91660I-314J-1366D01*
G03X23353I-277J-288D01*
G02X21407I-973J1010D01*
G03X20853I-277J-288D01*
G02X18907I-973J1010D01*
G03X18353I-277J-288D01*
G02X16407I-973J1010D01*
G03X15853I-277J-288D01*
G02X13907I-973J1010D01*
G03X13353I-277J-288D01*
G02X11407I-973J1010D01*
G03X10853I-277J-288D01*
G02X8907I-973J1010D01*
G03X8353I-277J-288D01*
G02X6407I-973J1010D01*
G03X5853I-277J-288D01*
G02X3907I-973J1010D01*
G03X3353I-277J-288D01*
G02X1921Y93995I-972J1010D01*
G37*
G36*
G01X2629Y57596D02*
G02X1052Y57616I-803J-1149D01*
G03X1060Y58277I-221J333D01*
G02X2637Y58257I803J1149D01*
G03X2629Y57596I221J-333D01*
G37*
G36*
G01X-7239Y59518D02*
G02X-9396Y60971I-1371J292D01*
G03X-9343Y61590I-224J331D01*
G02X-9771Y62657I973J1010D01*
G03X-10237Y63068I-400J16D01*
G02X-11672Y63728I-234J1382D01*
G03X-12369Y63708I-343J-206D01*
G02X-12408Y65082I-1241J652D01*
G03X-11711Y65102I343J206D01*
G02X-10689Y65835I1241J-652D01*
G03X-10449Y66492I-62J395D01*
G02X-9171Y66025I1060J918D01*
G03X-9411Y65368I62J-395D01*
G02X-9069Y64393I-1059J-919D01*
G03X-8603Y63982I400J-16D01*
G02X-6972Y62710I233J-1382D01*
G03X-6449Y62362I398J32D01*
G02X-6662Y59789I439J-1332D01*
G03X-7239Y59518I-186J-354D01*
G37*
G36*
G01X6314Y78585D02*
G02X4763Y78637I-815J-1141D01*
G03X4786Y79303I-210J341D01*
G02X6337Y79251I815J1141D01*
G03X6314Y78585I210J-341D01*
G37*
G36*
G01X12726Y79724D02*
G02X10804Y79558I-862J-1230D01*
G03X10767Y80158I-282J284D01*
G02X10652Y80257I856J1111D01*
G03X10098I-277J-288D01*
G02X8520Y82532I-972J1010D01*
G03X8543Y83242I-172J361D01*
G02X8187Y83524I681J1226D01*
G03X7583Y83509I-296J-269D01*
G02X7538Y85343I-1083J891D01*
G03X8142Y85358I296J269D01*
G02X10198Y85477I1083J-891D01*
G03X10752I277J288D01*
G02X12330Y83202I972J-1010D01*
G03X12307Y82492I172J-361D01*
G02X12660Y80321I-682J-1225D01*
G03X12726Y79724I295J-269D01*
G37*
G36*
G01X-10313Y78490D02*
G02X-12501Y78378I-1139J818D01*
G03X-13089Y78389I-299J-266D01*
G02X-15075Y78348I-1013J969D01*
G03X-15629I-277J-288D01*
G02X-17612Y80331I-973J1010D01*
G03Y80885I-288J277D01*
G02X-15629Y82868I1010J973D01*
G03X-15075I277J288D01*
G02X-13053Y82788I973J-1010D01*
G03X-12465Y82777I299J266D01*
G02X-10342Y82665I1013J-969D01*
G03X-9701Y82676I316J244D01*
G02X-9678Y82707I1137J-820D01*
G03X-9733Y83251I-318J243D01*
G02X-7669Y85121I922J1057D01*
G03X-7026Y85109I326J232D01*
G02X-4846Y83347I1114J-852D01*
G03X-4835Y82814I304J-260D01*
G02X-4878Y80857I-1025J-956D01*
G03X-4894Y80302I280J-286D01*
G02X-6954Y78400I-1036J-944D01*
G03X-7538I-292J-273D01*
G02X-9672Y78501I-1024J958D01*
G03X-10313Y78490I-316J-244D01*
G37*
G36*
G01X7750Y87098D02*
G02X7648Y88832I-1150J802D01*
G03X8275Y88869I299J265D01*
G02X10398Y89077I1150J-802D01*
G03X10952I277J288D01*
G02Y87057I973J-1010D01*
G03X10398I-277J-288D01*
G02X8377Y87135I-973J1010D01*
G03X7750Y87098I-299J-265D01*
G37*
G36*
G01X-8748Y98907D02*
G02X-12807Y100241I-1488J2314D01*
G03X-13547Y100259I-374J-143D01*
G02Y102183I-2201J962D01*
G03X-12807Y102201I366J161D01*
G02X-8764Y103545I2571J-980D01*
G03X-7510Y103132I1283J1786D01*
G01X-7487D01*
X-7480D01*
G03X-6213Y103535I-2J2199D01*
G02X-2154Y102201I1488J-2314D01*
G03X-1414Y102183I374J143D01*
G02X2988I2201J-962D01*
G03X3728Y102201I366J161D01*
G02X7771Y103545I2571J-980D01*
G03X9025Y103132I1283J1786D01*
G01X9049D01*
X9056D01*
G03X10323Y103535I-2J2199D01*
G02X14382Y102201I1488J-2314D01*
G03X15122Y102183I374J143D01*
G02X19524I2201J-962D01*
G03X20264Y102201I366J161D01*
G02X24307Y103545I2571J-980D01*
G03X25561Y103132I1283J1786D01*
G01X25584D01*
X25591D01*
G03X26858Y103535I-2J2199D01*
G02X30917Y102201I1488J-2314D01*
G03X31657Y102183I374J143D01*
G02Y100259I2201J-962D01*
G03X30917Y100241I-366J-161D01*
G02X26874Y98897I-2571J980D01*
G03X25620Y99310I-1283J-1786D01*
G01X25597D01*
X25590D01*
G03X24323Y98907I2J-2199D01*
G02X20264Y100241I-1488J2314D01*
G03X19524Y100259I-374J-143D01*
G02X15122I-2201J962D01*
G03X14382Y100241I-366J-161D01*
G02X10339Y98897I-2571J980D01*
G03X9085Y99310I-1283J-1786D01*
G01X9061D01*
X9054D01*
G03X7787Y98907I2J-2199D01*
G02X3728Y100241I-1488J2314D01*
G03X2988Y100259I-374J-143D01*
G02X-1414I-2201J962D01*
G03X-2154Y100241I-366J-161D01*
G02X-6197Y98897I-2571J980D01*
G03X-7451Y99310I-1283J-1786D01*
G01X-7474D01*
X-7481D01*
G03X-8748Y98907I2J-2199D01*
G37*
G36*
G01X-13866Y106781D02*
G02X-13882Y111419I-1488J2314D01*
G03X-12628Y111006I1283J1786D01*
G01X-12605D01*
X-12598D01*
G03X-11331Y111409I-2J2199D01*
G02X-7272Y110075I1488J-2314D01*
G03X-6532Y110057I374J143D01*
G02X-2130I2201J-962D01*
G03X-1390Y110075I366J161D01*
G02X2653Y111419I2571J-980D01*
G03X3907Y111006I1283J1786D01*
G01X3931D01*
X3938D01*
G03X5205Y111409I-2J2199D01*
G02X9264Y110075I1488J-2314D01*
G03X10004Y110057I374J143D01*
G02X14405Y110058I2201J-962D01*
G03X15145Y110076I366J161D01*
G02X19188Y111419I2570J-981D01*
G03X20442Y111006I1283J1786D01*
G01X20466D01*
X20473D01*
G03X21740Y111409I-2J2199D01*
G02X25799Y110075I1488J-2314D01*
G03X26539Y110057I374J143D01*
G02Y108133I2201J-962D01*
G03X25799Y108115I-366J-161D01*
G02X21756Y106771I-2571J980D01*
G03X20502Y107184I-1283J-1786D01*
G01X20478D01*
X20471D01*
G03X19204Y106781I2J-2199D01*
G02X15145Y108114I-1488J2314D01*
G03X14405Y108132I-374J-143D01*
G02X10004Y108133I-2200J963D01*
G03X9264Y108115I-366J-161D01*
G02X5221Y106771I-2571J980D01*
G03X3967Y107184I-1283J-1786D01*
G01X3943D01*
X3936D01*
G03X2669Y106781I2J-2199D01*
G02X-1390Y108115I-1488J2314D01*
G03X-2130Y108133I-374J-143D01*
G02X-6532I-2201J962D01*
G03X-7272Y108115I-366J-161D01*
G02X-11315Y106771I-2571J980D01*
G03X-12569Y107184I-1283J-1786D01*
G01X-12592D01*
X-12599D01*
G03X-13866Y106781I2J-2199D01*
G37*
G36*
G01X7787Y114655D02*
G02X3728Y115989I-1488J2314D01*
G03X2988Y116007I-374J-143D01*
G02Y117931I-2201J962D01*
G03X3728Y117949I366J161D01*
G02X7771Y119293I2571J-980D01*
G03X9025Y118880I1283J1786D01*
G01X9049D01*
X9056D01*
G03X10323Y119283I-2J2199D01*
G02X14382Y117949I1488J-2314D01*
G03X15122Y117931I374J143D01*
G02X19524I2201J-962D01*
G03X20264Y117949I366J161D01*
G02X24307Y119293I2571J-980D01*
G03X25561Y118880I1283J1786D01*
G01X25584D01*
X25591D01*
G03X26858Y119283I-2J2199D01*
G02X30917Y117949I1488J-2314D01*
G03X31657Y117931I374J143D01*
G02Y116007I2201J-962D01*
G03X30917Y115989I-366J-161D01*
G02X26874Y114645I-2571J980D01*
G03X25620Y115058I-1283J-1786D01*
G01X25597D01*
X25590D01*
G03X24323Y114655I2J-2199D01*
G02X20264Y115989I-1488J2314D01*
G03X19524Y116007I-374J-143D01*
G02X15122I-2201J962D01*
G03X14382Y115989I-366J-161D01*
G02X10339Y114645I-2571J980D01*
G03X9085Y115058I-1283J-1786D01*
G01X9061D01*
X9054D01*
G03X7787Y114655I2J-2199D01*
G37*
G36*
G01X-13866Y122529D02*
G02X-13882Y127167I-1488J2314D01*
G03X-12628Y126754I1283J1786D01*
G01X-12605D01*
X-12598D01*
G03X-11331Y127157I-2J2199D01*
G02X-7272Y125823I1488J-2314D01*
G03X-6532Y125805I374J143D01*
G02X-2130I2201J-962D01*
G03X-1390Y125823I366J161D01*
G02X2653Y127167I2571J-980D01*
G03X3907Y126754I1283J1786D01*
G01X3931D01*
X3938D01*
G03X5205Y127157I-2J2199D01*
G02X9264Y125823I1488J-2314D01*
G03X10004Y125805I374J143D01*
G02Y123881I2201J-962D01*
G03X9264Y123863I-366J-161D01*
G02X5221Y122519I-2571J980D01*
G03X3967Y122932I-1283J-1786D01*
G01X3943D01*
X3936D01*
G03X2669Y122529I2J-2199D01*
G02X-1390Y123863I-1488J2314D01*
G03X-2130Y123881I-374J-143D01*
G02X-6532I-2201J962D01*
G03X-7272Y123863I-366J-161D01*
G02X-11315Y122519I-2571J980D01*
G03X-12569Y122932I-1283J-1786D01*
G01X-12592D01*
X-12599D01*
G03X-13866Y122529I2J-2199D01*
G37*
G36*
G01X24323Y130403D02*
G02X20264Y131737I-1488J2314D01*
G03X19524Y131755I-374J-143D01*
G02Y133679I-2201J962D01*
G03X20264Y133697I366J161D01*
G02X24307Y135041I2571J-980D01*
G03X25561Y134628I1283J1786D01*
G01X25584D01*
X25591D01*
G03X26858Y135031I-2J2199D01*
G02X30917Y133697I1488J-2314D01*
G03X31657Y133679I374J143D01*
G02Y131755I2201J-962D01*
G03X30917Y131737I-366J-161D01*
G02X26874Y130393I-2571J980D01*
G03X25620Y130806I-1283J-1786D01*
G01X25597D01*
X25590D01*
G03X24323Y130403I2J-2199D01*
G37*
G36*
G01X-13866Y138277D02*
G02X-13882Y142915I-1488J2314D01*
G03X-12628Y142502I1283J1786D01*
G01X-12605D01*
X-12598D01*
G03X-11331Y142905I-2J2199D01*
G02X-7272Y141571I1488J-2314D01*
G03X-6532Y141553I374J143D01*
G02X-2130I2201J-962D01*
G03X-1390Y141571I366J161D01*
G02X2653Y142915I2571J-980D01*
G03X3907Y142502I1283J1786D01*
G01X3931D01*
X3938D01*
G03X5205Y142905I-2J2199D01*
G02X9264Y141571I1488J-2314D01*
G03X10004Y141553I374J143D01*
G02Y139629I2201J-962D01*
G03X9264Y139611I-366J-161D01*
G02X5221Y138267I-2571J980D01*
G03X3967Y138680I-1283J-1786D01*
G01X3943D01*
X3936D01*
G03X2669Y138277I2J-2199D01*
G02X-1390Y139611I-1488J2314D01*
G03X-2130Y139629I-374J-143D01*
G02X-6532I-2201J962D01*
G03X-7272Y139611I-366J-161D01*
G02X-11315Y138267I-2571J980D01*
G03X-12569Y138680I-1283J-1786D01*
G01X-12592D01*
X-12599D01*
G03X-13866Y138277I2J-2199D01*
G37*
G36*
G01X-8748Y146151D02*
G02X-12807Y147485I-1488J2314D01*
G03X-13547Y147503I-374J-143D01*
G02Y149427I-2201J962D01*
G03X-12807Y149445I366J161D01*
G02X-8764Y150789I2571J-980D01*
G03X-7510Y150376I1283J1786D01*
G01X-7487D01*
X-7480D01*
G03X-6213Y150779I-2J2199D01*
G02X-2154Y149445I1488J-2314D01*
G03X-1414Y149427I374J143D01*
G02X2988I2201J-962D01*
G03X3728Y149445I366J161D01*
G02X7771Y150789I2571J-980D01*
G03X9025Y150376I1283J1786D01*
G01X9049D01*
X9056D01*
G03X10323Y150779I-2J2199D01*
G02X14382Y149445I1488J-2314D01*
G03X15122Y149427I374J143D01*
G02X19524I2201J-962D01*
G03X20264Y149445I366J161D01*
G02X24307Y150789I2571J-980D01*
G03X25561Y150376I1283J1786D01*
G01X25584D01*
X25591D01*
G03X26858Y150779I-2J2199D01*
G02X30917Y149445I1488J-2314D01*
G03X31657Y149427I374J143D01*
G02Y147503I2201J-962D01*
G03X30917Y147485I-366J-161D01*
G02X26874Y146141I-2571J980D01*
G03X25620Y146554I-1283J-1786D01*
G01X25597D01*
X25590D01*
G03X24323Y146151I2J-2199D01*
G02X20264Y147485I-1488J2314D01*
G03X19524Y147503I-374J-143D01*
G02X15122I-2201J962D01*
G03X14382Y147485I-366J-161D01*
G02X10339Y146141I-2571J980D01*
G03X9085Y146554I-1283J-1786D01*
G01X9061D01*
X9054D01*
G03X7787Y146151I2J-2199D01*
G02X3728Y147485I-1488J2314D01*
G03X2988Y147503I-374J-143D01*
G02X-1414I-2201J962D01*
G03X-2154Y147485I-366J-161D01*
G02X-6197Y146141I-2571J980D01*
G03X-7451Y146554I-1283J-1786D01*
G01X-7474D01*
X-7481D01*
G03X-8748Y146151I2J-2199D01*
G37*
G36*
G01X1263675Y155756D02*
G02X1263568Y153973I1025J-956D01*
G03X1262941Y153997I-323J-236D01*
G02X1263049Y155807I-1141J976D01*
G03X1263675Y155756I333J222D01*
G37*
G36*
G01X-13866Y154025D02*
G02X-13882Y158663I-1488J2314D01*
G03X-12628Y158250I1283J1786D01*
G01X-12605D01*
X-12598D01*
G03X-11331Y158653I-2J2199D01*
G02X-7272Y157319I1488J-2314D01*
G03X-6532Y157301I374J143D01*
G02X-2130I2201J-962D01*
G03X-1390Y157319I366J161D01*
G02X2653Y158663I2571J-980D01*
G03X3907Y158250I1283J1786D01*
G01X3931D01*
X3938D01*
G03X5205Y158653I-2J2199D01*
G02X9264Y157319I1488J-2314D01*
G03X10004Y157301I374J143D01*
G02X14405Y157302I2201J-962D01*
G03X15145Y157320I366J161D01*
G02X19188Y158663I2570J-981D01*
G03X20442Y158250I1283J1786D01*
G01X20466D01*
X20473D01*
G03X21740Y158653I-2J2199D01*
G02X25799Y157319I1488J-2314D01*
G03X26539Y157301I374J143D01*
G02Y155377I2201J-962D01*
G03X25799Y155359I-366J-161D01*
G02X21756Y154015I-2571J980D01*
G03X20502Y154428I-1283J-1786D01*
G01X20478D01*
X20471D01*
G03X19204Y154025I2J-2199D01*
G02X15145Y155358I-1488J2314D01*
G03X14405Y155376I-374J-143D01*
G02X10004Y155377I-2200J963D01*
G03X9264Y155359I-366J-161D01*
G02X5221Y154015I-2571J980D01*
G03X3967Y154428I-1283J-1786D01*
G01X3943D01*
X3936D01*
G03X2669Y154025I2J-2199D01*
G02X-1390Y155359I-1488J2314D01*
G03X-2130Y155377I-374J-143D01*
G02X-6532I-2201J962D01*
G03X-7272Y155359I-366J-161D01*
G02X-11315Y154015I-2571J980D01*
G03X-12569Y154428I-1283J-1786D01*
G01X-12592D01*
X-12599D01*
G03X-13866Y154025I2J-2199D01*
G37*
G36*
G01X759177Y157367D02*
G02X757623I-777J-1167D01*
G03Y158033I-222J333D01*
G02X759177I777J1167D01*
G03Y157367I222J-333D01*
G37*
G36*
G01X1403006Y163602D02*
G02X1401139Y163553I-838J-3657D01*
G03X1401237Y164279I-110J384D01*
G02X1400532Y165358I783J1282D01*
G03X1399918Y165640I-396J-54D01*
G02X1400588Y167103I-818J1260D01*
G03X1401202Y166821I396J54D01*
G02X1402869Y164322I818J-1260D01*
G03X1403006Y163602I226J-330D01*
G37*
G36*
G01X-14292Y161645D02*
G02X-14949Y163181I-1476J277D01*
G03X-14337Y163442I219J335D01*
G02X-13680Y161906I1476J-277D01*
G03X-14292Y161645I-219J-335D01*
G37*
G36*
G01X1452461Y166324D02*
G02X1450322Y166376I-1095J-1028D01*
G03X1450351Y166919I-278J287D01*
G02X1450343Y168707I1076J899D01*
G03X1450313Y169246I-310J253D01*
G02X1450550Y171579I1052J1072D01*
G03X1450554Y172248I-217J336D01*
G02X1450304Y174541I832J1251D01*
G03X1450316Y175084I-288J278D01*
G02X1450089Y176595I1049J930D01*
G03X1449904Y177118I-364J165D01*
G02X1451808Y177791I628J1254D01*
G03X1451993Y177268I364J-165D01*
G02X1452430Y175102I-628J-1254D01*
G03X1452450Y174559I303J-261D01*
G02X1452201Y172238I-1064J-1060D01*
G03X1452197Y171569I217J-336D01*
G02X1452469Y169299I-832J-1251D01*
G03X1452466Y168759I293J-272D01*
G02X1452459Y166869I-1039J-941D01*
G03X1452461Y166324I294J-271D01*
G37*
G36*
G01X1242851Y171731D02*
G02X1242553Y172980I-1470J309D01*
G03X1242909Y173110I156J125D01*
G02X1242914Y173284I1501J44D01*
G03X1242575Y173715I-398J35D01*
G02X1244296Y175066I225J1485D01*
G03X1244635Y174635I398J-35D01*
G02X1245397Y174282I-225J-1485D01*
G03X1245923I263J302D01*
G02X1246034Y174370I988J-1132D01*
G03X1245981Y175053I-233J326D01*
G02X1247531Y175175I674J1342D01*
G03X1247584Y174492I233J-326D01*
G02X1245923Y172018I-674J-1342D01*
G03X1245397I-263J-302D01*
G02X1243488Y171964I-987J1132D01*
G03X1242851Y171731I-246J-315D01*
G37*
G36*
G01X1489816Y177878D02*
G02X1488305Y177843I-728J-1198D01*
G03X1488278Y178523I-223J332D01*
G02X1489812Y178559I737J1309D01*
G03X1489816Y177878I212J-339D01*
G37*
G36*
G01X1476168Y181714D02*
G02X1476004Y183117I-1285J561D01*
G03X1476695Y183209I320J241D01*
G02X1476861Y181785I1394J-559D01*
G03X1476168Y181714I-326J-231D01*
G37*
G36*
G01X1536245Y189153D02*
G02X1534585Y189138I-820J-1137D01*
G03X1534579Y189783I-240J320D01*
G02X1536239Y189798I820J1137D01*
G03X1536245Y189153I240J-320D01*
G37*
G36*
G01X1437315Y187698D02*
X1430185D01*
X1428698Y189185D01*
Y247115D01*
X1431085Y249502D01*
X1433534D01*
G02X1433713Y249785I1266J-603D01*
G03X1433602Y250384I-310J252D01*
G02X1433148Y252400I698J1216D01*
G03X1433015Y252977I-328J228D01*
G02X1434852Y253400I686J1223D01*
G03X1434985Y252823I328J-228D01*
G02X1435387Y250715I-685J-1223D01*
G03X1435498Y250116I310J-252D01*
G02X1436066Y249502I-698J-1216D01*
G01X1437315D01*
X1439302Y247515D01*
Y241302D01*
X1443250D01*
G03X1443587Y241918I0J400D01*
G02X1446113I1263J812D01*
G03X1446450Y241302I337J-216D01*
G01X1457069D01*
G03X1457346Y241990I0J400D01*
G02X1459290I972J1010D01*
G03X1459567Y241302I277J-288D01*
G01X1467833D01*
G03X1468125Y241974I-1J400D01*
G02X1470051Y244005I1024J957D01*
G03X1470637Y244083I257J306D01*
G02X1470887Y244376I1564J-1082D01*
G03X1470820Y245006I-276J289D01*
G02X1470577Y245191I784J1281D01*
G03X1470031I-273J-292D01*
G02X1468327Y244946I-1027J1096D01*
G03X1467781Y244749I-180J-357D01*
G02X1467081Y246691I-1377J601D01*
G03X1467627Y246888I180J357D01*
G02X1470031Y247383I1377J-601D01*
G03X1470577I273J292D01*
G02X1472947Y246961I1027J-1096D01*
G03X1473661I357J179D01*
G02Y245613I1343J-674D01*
G03X1472947I-357J-179D01*
G02X1472788Y245363I-1341J677D01*
G03X1472946Y244749I315J-246D01*
G02X1474102Y243000I-745J-1749D01*
G01Y240712D01*
X1470888Y237498D01*
X1443628D01*
G03X1443233Y237036I0J-400D01*
G02X1440267I-1483J-236D01*
G03X1439872Y237498I-395J62D01*
G01X1439302D01*
Y209877D01*
X1439439Y209832D01*
G02Y207168I-439J-1332D01*
G01X1439302Y207123D01*
Y189685D01*
X1437315Y187698D01*
G37*
G36*
G01X814447Y196903D02*
G02X812953I-747J-1303D01*
G03Y197597I-199J347D01*
G02X814447I747J1303D01*
G03Y196903I199J-347D01*
G37*
G36*
G01X1403994Y206146D02*
G02X1402388Y205876I-594J-1380D01*
G03X1402276Y206538I-270J295D01*
G02X1403882Y206808I594J1380D01*
G03X1403994Y206146I270J-295D01*
G37*
G36*
G01X1479907Y208294D02*
G02X1477808Y207964I-907J-1069D01*
G03X1477709Y208494I-340J211D01*
G02X1477264Y209030I902J1201D01*
G03X1476589Y209098I-359J-177D01*
G02X1475972Y208628I-1188J919D01*
G03X1475750Y208117I152J-370D01*
G02X1473834Y208886I-1311J-496D01*
G03X1474028Y209409I-172J361D01*
G02X1476748Y210682I1373J608D01*
G03X1477423Y210614I359J177D01*
G02X1479839Y208830I1188J-919D01*
G03X1479907Y208294I327J-231D01*
G37*
G36*
G01X1461480Y222392D02*
G02X1461467Y221032I1220J-692D01*
G03X1460768Y221039I-351J-190D01*
G02X1460781Y222399I-1220J692D01*
G03X1461480Y222392I351J190D01*
G37*
G36*
G01X1499094Y222803D02*
G02X1497466Y223187I-1072J-903D01*
G03X1497613Y223812I-159J367D01*
G02X1499241Y223428I1072J903D01*
G03X1499094Y222803I159J-367D01*
G37*
G36*
G01X1481639Y223940D02*
G02X1480549Y222856I365J-1457D01*
G03X1480065Y223344I-387J100D01*
G02X1481155Y224428I-365J1457D01*
G03X1481639Y223940I387J-100D01*
G37*
G36*
G01X-2029Y230179D02*
G02X-5802Y230215I-1908J-2187D01*
G03X-5897Y230887I-257J306D01*
G02X-6286Y231133I653J1463D01*
G03X-6806I-260J-304D01*
G02Y233569I-1040J1218D01*
G03X-6286I260J304D01*
G02X-4164Y233533I1041J-1218D01*
G03X-3636Y233522I270J295D01*
G02X-1933Y230844I1036J-1221D01*
G03X-2029Y230179I167J-364D01*
G37*
G36*
G01X1398902Y232107D02*
G02X1396462Y233291I-1502J11D01*
G03X1396476Y233905I-249J313D01*
G02X1396525Y236054I924J1054D01*
G03X1396511Y236689I-250J312D01*
G02X1398902Y237905I889J1211D01*
G03X1399472Y237544I400J1D01*
G02X1401041Y235266I594J-1270D01*
G03X1401021Y234712I278J-287D01*
G02X1399452Y232475I-1043J-937D01*
G03X1398902Y232107I-150J-371D01*
G37*
G36*
G01X-16833Y246623D02*
G02Y248177I-1167J777D01*
G03X-16167I333J222D01*
G02Y246623I1167J-777D01*
G03X-16833I-333J-222D01*
G37*
G36*
G01X1479748Y252835D02*
G02X1477669Y253251I-1248J-835D01*
G03X1477792Y253788I-221J333D01*
G02X1477613Y254705I1208J712D01*
G03X1477255Y255162I-396J59D01*
G02X1476039Y256014I141J1495D01*
G03X1475327Y256035I-361J-171D01*
G02X1475346Y257341I-1231J671D01*
G03X1476059Y257340I357J181D01*
G02X1478870Y256362I1338J-682D01*
G03X1479204Y255887I392J-79D01*
G02X1479841Y253378I-204J-1387D01*
G03X1479748Y252835I239J-320D01*
G37*
G36*
G01X1440096Y254445D02*
G02X1438370Y253545I-396J-1345D01*
G03X1438104Y254055I-379J127D01*
G02X1437463Y256344I396J1345D01*
G03X1437308Y256987I-296J269D01*
G02X1438837Y257356I492J1313D01*
G03X1438992Y256713I296J-269D01*
G02X1439830Y254955I-492J-1313D01*
G03X1440096Y254445I379J-127D01*
G37*
G36*
G01X1456922Y254113D02*
G02X1456896Y255585I-1322J713D01*
G03X1457587Y255586I345J202D01*
G02X1457613Y254136I1213J-703D01*
G03X1456922Y254113I-339J-213D01*
G37*
G36*
G01X1494339Y254529D02*
G02X1494020Y256765I-1140J978D01*
G03X1494542Y256839I219J335D01*
G02X1494610Y256913I1139J-979D01*
G03X1494629Y257452I-286J280D01*
G02X1496753Y257440I1067J909D01*
G03X1496766Y256901I302J-262D01*
G02X1497005Y256572I-1085J-1039D01*
G03X1497718Y256587I353J189D01*
G02X1497747Y255223I1352J-654D01*
G03X1497034Y255208I-353J-189D01*
G02X1494861Y254603I-1353J653D01*
G03X1494339Y254529I-219J-335D01*
G37*
G36*
G01X-16833Y261923D02*
G02Y263477I-1167J777D01*
G03X-16167I333J222D01*
G02Y261923I1167J-777D01*
G03X-16833I-333J-222D01*
G37*
G36*
G01X1453595Y267493D02*
G02X1452725Y265728I461J-1324D01*
G03X1452214Y265980I-380J-126D01*
G02X1450528Y266623I-461J1324D01*
G03X1449828I-350J-194D01*
G02X1447378Y266622I-1225J681D01*
G03X1446679I-350J-194D01*
G02X1444228Y266623I-1225J682D01*
G03X1443529I-350J-194D01*
G02X1441623Y268529I-1226J680D01*
G03Y269228I-195J349D01*
G02X1441622Y271679I680J1226D01*
G03Y272378I-195J350D01*
G02X1443529Y274284I682J1225D01*
G03X1444229I350J194D01*
G02X1444773Y274828I1225J-681D01*
G03Y275528I-194J350D01*
G02X1444772Y277978I681J1225D01*
G03Y278677I-194J350D01*
G02X1444229Y279221I683J1224D01*
G03X1443529I-350J-194D01*
G02Y280583I-1225J681D01*
G03X1444229I350J194D01*
G02X1446679Y280584I1225J-681D01*
G03X1447378I349J194D01*
G02X1447923Y281128I1225J-682D01*
G03Y281827I-195J349D01*
G02X1447921Y284278I680J1226D01*
G03Y284977I-194J350D01*
G02Y287427I682J1225D01*
G03Y288126I-194J350D01*
G02X1447378Y288669I682J1225D01*
G03X1446679I-350J-194D01*
G02X1444229I-1225J682D01*
G03X1443530I-350J-194D01*
G02X1441622Y290575I-1226J681D01*
G03Y291274I-194J349D01*
G02X1443513Y293209I682J1225D01*
G03X1444206Y293215I345J203D01*
G02X1444711Y293731I1221J-689D01*
G03Y294419I-205J344D01*
G02X1444774Y296864I716J1205D01*
G03X1444780Y297569I-187J354D01*
G02X1444228Y298118I674J1229D01*
G03X1443529I-350J-194D01*
G02Y299479I-1226J681D01*
G03X1444228I349J194D01*
G02X1444773Y300023I1225J-682D01*
G03Y300723I-194J350D01*
G02Y303173I681J1225D01*
G03Y303873I-194J350D01*
G02X1444229Y304417I681J1225D01*
G03X1443529I-350J-194D01*
G02X1441622Y306323I-1225J681D01*
G03Y307022I-194J350D01*
G02X1441623Y309472I682J1225D01*
G03Y310172I-194J350D01*
G02X1443529Y312078I681J1225D01*
G03X1444229I350J194D01*
G02X1446679Y312079I1225J-681D01*
G03X1447378I349J194D01*
G02X1447921Y312622I1225J-682D01*
G03Y313321I-194J350D01*
G02X1447922Y315771I682J1225D01*
G03Y316471I-194J350D01*
G02X1447389Y316995I681J1225D01*
G03X1446706Y317012I-347J-200D01*
G02X1446742Y318473I-1178J760D01*
G03X1447425Y318456I347J200D01*
G02X1449828Y318377I1178J-760D01*
G03X1450528I350J194D01*
G02X1452982Y318370I1225J-681D01*
G03X1453687Y318376I351J192D01*
G02X1455580Y316482I1241J-653D01*
G03X1455574Y315776I185J-355D01*
G02X1456127Y315227I-672J-1230D01*
G03X1456827I350J194D01*
G02X1459277I1225J-681D01*
G03X1459977I350J194D01*
G02X1461884Y313321I1225J-681D01*
G03Y312622I194J-350D01*
G02X1462427Y312079I-682J-1225D01*
G03X1463126I349J194D01*
G02X1465032Y310171I1225J-682D01*
G03Y309472I194J-350D01*
G02Y307022I-682J-1225D01*
G03Y306323I195J-350D01*
G02Y303873I-681J-1225D01*
G03Y303173I194J-350D01*
G02Y300723I-681J-1225D01*
G03Y300023I194J-350D01*
G02X1465033Y297573I-681J-1225D01*
G03Y296874I194J-349D01*
G02X1463126Y294967I-682J-1225D01*
G03X1462427I-350J-194D01*
G02X1459977Y294968I-1225J682D01*
G03X1459277I-350J-194D01*
G02X1456827I-1225J681D01*
G03X1456127I-350J-194D01*
G02X1455618Y294444I-1225J681D01*
G03X1455585Y293778I204J-344D01*
G02X1454035Y293856I-834J-1127D01*
G03X1454068Y294522I-204J344D01*
G02X1453676Y294969I834J1127D01*
G03X1452977I-350J-195D01*
G02X1450521Y294975I-1226J680D01*
G03X1449817Y294970I-351J-192D01*
G02X1447352Y294943I-1240J654D01*
G03X1446652I-350J-194D01*
G02X1446143Y294419I-1225J681D01*
G03Y293731I205J-344D01*
G02X1446101Y291297I-716J-1205D01*
G03X1446107Y290592I192J-351D01*
G02X1446679Y290033I-653J-1241D01*
G03X1447378I349J194D01*
G02X1449828Y290032I1225J-682D01*
G03X1450528I350J194D01*
G02X1452978Y290033I1225J-681D01*
G03X1453677I349J194D01*
G02X1456127Y290032I1225J-682D01*
G03X1456827I350J194D01*
G02X1459277I1225J-681D01*
G03X1459977I350J194D01*
G02X1462427Y290033I1225J-681D01*
G03X1463126I349J194D01*
G02X1465033Y288126I1225J-682D01*
G03Y287427I194J-350D01*
G02X1465032Y284977I-682J-1225D01*
G03Y284277I194J-350D01*
G02Y281827I-681J-1225D01*
G03Y281127I194J-350D01*
G02X1465033Y278677I-681J-1225D01*
G03Y277978I194J-350D01*
G02X1465109Y275573I-682J-1225D01*
G03X1465125Y274890I216J-337D01*
G02X1463666Y274856I-702J-1214D01*
G03X1463650Y275539I-216J337D01*
G02X1463126Y276071I701J1214D01*
G03X1462427I-350J-194D01*
G02X1461883Y275528I-1224J683D01*
G03Y274828I194J-350D01*
G02X1459977Y272922I-681J-1225D01*
G03X1459277I-350J-194D01*
G02X1458715Y272368I-1225J681D01*
G03X1458726Y271657I189J-353D01*
G02X1459346Y271048I-624J-1255D01*
G03X1460056Y271047I355J184D01*
G02Y269754I1244J-646D01*
G03X1459346Y269755I-355J-184D01*
G02X1456847Y269778I-1244J647D01*
G03X1456136Y269789I-358J-178D01*
G02X1453677Y269772I-1234J665D01*
G03X1452978I-350J-194D01*
G02X1452434Y269229I-1224J683D01*
G03Y268529I194J-350D01*
G02X1453084Y267745I-681J-1226D01*
G03X1453595Y267493I380J126D01*
G37*
G36*
G01X1481323Y266622D02*
G02X1479417Y268529I-1225J682D01*
G03Y269229I-194J350D01*
G02X1478873Y269773I681J1225D01*
G03X1478173I-350J-194D01*
G02X1475723I-1225J681D01*
G03X1475023I-350J-194D01*
G02X1472573Y269772I-1225J681D01*
G03X1471874I-349J-194D01*
G02X1469967Y271679I-1225J682D01*
G03Y272378I-194J350D01*
G02X1469968Y274828I682J1225D01*
G03Y275528I-194J350D01*
G02X1469967Y277978I681J1225D01*
G03Y278677I-194J350D01*
G02X1469968Y281127I682J1225D01*
G03Y281827I-194J350D01*
G02Y284277I681J1225D01*
G03Y284977I-194J350D01*
G02X1469967Y287427I681J1225D01*
G03Y288126I-194J350D01*
G02X1471874Y290033I682J1225D01*
G03X1472573I350J194D01*
G02X1475023Y290032I1225J-682D01*
G03X1475723I350J194D01*
G02X1477630Y288126I1225J-681D01*
G03Y287427I194J-350D01*
G02X1478173Y286883I-683J-1224D01*
G03X1478873I350J194D01*
G02X1481323Y286884I1225J-681D01*
G03X1482022I350J194D01*
G02X1482565Y287427I1225J-682D01*
G03Y288126I-194J350D01*
G02X1483929I682J1225D01*
G03Y287427I194J-350D01*
G02X1484472Y286883I-683J-1224D01*
G03X1485172I350J194D01*
G02X1487622Y286884I1225J-681D01*
G03X1488321I350J194D01*
G02Y285520I1225J-682D01*
G03X1487622I-349J-194D01*
G02X1487078Y284977I-1224J683D01*
G03Y284277I194J-350D01*
G02X1485172Y282371I-681J-1225D01*
G03X1484472I-350J-194D01*
G02X1483928Y281827I-1225J681D01*
G03Y281127I194J-350D01*
G02X1483929Y278677I-681J-1225D01*
G03Y277978I194J-350D01*
G02X1483928Y275528I-682J-1225D01*
G03Y274828I194J-350D01*
G02X1484472Y274284I-681J-1225D01*
G03X1485172I350J194D01*
G02X1487079Y272378I1225J-681D01*
G03Y271679I194J-350D01*
G02X1487622Y271136I-682J-1225D01*
G03X1488321I350J194D01*
G02Y269772I1225J-682D01*
G03X1487622I-349J-194D01*
G02X1485172Y269773I-1225J682D01*
G03X1484472I-350J-194D01*
G02X1483928Y269229I-1225J681D01*
G03Y268529I194J-350D01*
G02X1482022Y266622I-681J-1225D01*
G03X1481323I-349J-194D01*
G37*
G36*
G01X1498579Y278110D02*
G02X1497638Y279382I-1497J-123D01*
G03X1498184Y279787I147J372D01*
G02X1499125Y278515I1497J123D01*
G03X1498579Y278110I-147J-372D01*
G37*
G36*
G01X1405610Y282190D02*
G02X1402927Y282075I-1324J-461D01*
G03X1402446Y282562I-387J98D01*
G02X1403439Y284686I-354J1460D01*
G03X1404152Y284676I359J176D01*
G02X1405856Y282699I1240J-654D01*
G03X1405610Y282190I132J-378D01*
G37*
G36*
G01X1471874Y294967D02*
G02X1469967Y296874I-1225J682D01*
G03Y297573I-194J350D01*
G02X1469968Y300023I682J1225D01*
G03Y300723I-194J350D01*
G02Y303173I681J1225D01*
G03Y303873I-194J350D01*
G02X1469967Y306323I681J1225D01*
G03Y307022I-194J350D01*
G02X1469968Y309472I682J1225D01*
G03Y310172I-194J350D01*
G02X1469967Y312622I681J1225D01*
G03Y313321I-194J350D01*
G02X1471874Y315228I682J1225D01*
G03X1472573I350J194D01*
G02X1474480Y313321I1225J-682D01*
G03Y312622I194J-350D01*
G02X1475023Y312078I-683J-1224D01*
G03X1475723I350J194D01*
G02X1478173I1225J-681D01*
G03X1478873I350J194D01*
G02X1479416Y312622I1226J-680D01*
G03Y313321I-194J350D01*
G02X1481323Y315228I682J1225D01*
G03X1482022I350J194D01*
G02X1484472Y315227I1225J-682D01*
G03X1485172I350J194D01*
G02X1485715Y315771I1226J-680D01*
G03Y316470I-194J349D01*
G02X1487621Y318377I681J1226D01*
G03X1488321I350J194D01*
G02X1490227Y316471I1225J-681D01*
G03Y315771I194J-350D01*
G02X1490771Y315227I-681J-1225D01*
G03X1491471I350J194D01*
G02X1493864Y315321I1225J-681D01*
G03X1494531I334J221D01*
G02X1496328Y313293I1168J-775D01*
G03X1496317Y312584I179J-357D01*
G02X1494496Y310555I-666J-1234D01*
G03X1493841Y310561I-330J-226D01*
G02X1491469Y310706I-1141J815D01*
G03X1490768Y310711I-352J-191D01*
G02X1490227Y310172I-1222J686D01*
G03Y309472I194J-350D01*
G02X1488321Y307565I-681J-1225D01*
G03X1487622I-349J-194D01*
G02X1487079Y307022I-1225J682D01*
G03Y306323I194J-350D01*
G02X1487078Y303873I-682J-1225D01*
G03Y303173I194J-350D01*
G02X1487622Y302630I-680J-1226D01*
G03X1488321I350J194D01*
G02Y301266I1225J-682D01*
G03X1487622I-349J-194D01*
G02X1487078Y300723I-1224J683D01*
G03Y300023I194J-350D01*
G02X1487079Y297573I-681J-1225D01*
G03Y296874I194J-349D01*
G02X1485715I-682J-1225D01*
G03Y297573I-194J350D01*
G02X1485172Y298117I683J1224D01*
G03X1484472I-350J-194D01*
G02X1482022Y298116I-1225J681D01*
G03X1481323I-349J-194D01*
G02X1480780Y297573I-1225J682D01*
G03Y296874I194J-349D01*
G02X1478873Y294968I-682J-1225D01*
G03X1478173I-350J-194D01*
G02X1475723I-1225J681D01*
G03X1475023I-350J-194D01*
G02X1472573Y294967I-1225J681D01*
G03X1471874I-349J-194D01*
G37*
G36*
G01X1375805Y302353D02*
G02X1374016Y302488I-985J-1134D01*
G03X1374077Y303116I-214J338D01*
G02X1374124Y305196I963J1019D01*
G03X1374068Y305842I-262J303D01*
G02X1374008Y308380I772J1288D01*
G03X1374033Y309028I-222J333D01*
G02X1375722Y308994I867J1102D01*
G03X1375721Y308346I234J-324D01*
G02X1375777Y305956I-881J-1216D01*
G03X1375807Y305308I249J-313D01*
G02X1375839Y302983I-767J-1173D01*
G03X1375805Y302353I229J-328D01*
G37*
G36*
G01X1381684Y302506D02*
G02X1379929Y302808I-1083J-1041D01*
G03X1380050Y303431I-179J358D01*
G02X1380065Y305305I1050J929D01*
G03X1379933Y305940I-296J270D01*
G02X1379852Y308641I615J1370D01*
G03X1379943Y309285I-185J355D01*
G02X1381607Y309084I967J1015D01*
G03X1381541Y308437I199J-347D01*
G02X1381617Y306255I-993J-1127D01*
G03X1381724Y305616I285J-281D01*
G02X1381779Y303133I-624J-1256D01*
G03X1381684Y302506I193J-350D01*
G37*
G36*
G01X1387101Y302586D02*
G02X1385237Y302693I-999J-1121D01*
G03X1385286Y303307I-230J327D01*
G02X1385346Y305369I979J1003D01*
G03X1385286Y306015I-263J301D01*
G02X1385191Y308543I762J1294D01*
G03X1385203Y309191I-229J328D01*
G02X1386893I845J1119D01*
G03X1386905Y308543I241J-320D01*
G02X1386988Y306138I-857J-1234D01*
G03X1387022Y305490I250J-312D01*
G02X1387122Y303201I-757J-1180D01*
G03X1387101Y302586I245J-316D01*
G37*
G36*
G01X1414835Y302989D02*
G02X1412823Y303188I-1115J-1006D01*
G03X1412895Y303761I-239J321D01*
G02X1413044Y305686I1088J884D01*
G03X1412974Y306330I-268J297D01*
G02X1412958Y308928I746J1304D01*
G03X1413019Y309574I-203J345D01*
G02X1414701Y309448I925J1054D01*
G03X1414665Y308801I216J-337D01*
G02X1414682Y306480I-945J-1167D01*
G03X1414726Y305834I256J-307D01*
G02X1414877Y303565I-743J-1189D01*
G03X1414835Y302989I255J-308D01*
G37*
G36*
G01X1420292Y303036D02*
G02X1418201Y303086I-1071J-1053D01*
G03X1418230Y303644I-271J294D01*
G02X1418473Y305714I1053J926D01*
G03X1418471Y306368I-231J326D01*
G02X1418510Y308854I862J1230D01*
G03X1418524Y309514I-219J335D01*
G02X1420154Y309508I819J1138D01*
G03X1420164Y308849I232J-326D01*
G02X1420154Y306340I-831J-1251D01*
G03X1420131Y305687I219J-335D01*
G02X1420290Y303594I-848J-1117D01*
G03X1420292Y303036I287J-278D01*
G37*
G36*
G01X1404179Y303021D02*
G02X1402114Y303231I-1142J-975D01*
G03X1402186Y303789I-246J315D01*
G02X1402361Y305681I1114J851D01*
G03X1402292Y306326I-267J298D01*
G02X1402274Y308924I745J1304D01*
G03X1402335Y309569I-203J345D01*
G02X1404018Y309444I924J1054D01*
G03X1403983Y308797I217J-336D01*
G02X1403998Y306476I-946J-1167D01*
G03X1404042Y305829I256J-308D01*
G02X1404221Y303583I-742J-1189D01*
G03X1404179Y303021I262J-302D01*
G37*
G36*
G01X1409667Y303036D02*
G02X1407593Y303214I-1130J-990D01*
G03X1407657Y303772I-251J311D01*
G02X1407835Y305691I1103J865D01*
G03X1407774Y306336I-264J300D01*
G02X1407699Y308876I763J1294D01*
G03X1407721Y309524I-223J332D01*
G02X1409407Y309500I859J1108D01*
G03X1409411Y308852I236J-323D01*
G02X1409483Y306463I-874J-1222D01*
G03X1409518Y305816I252J-311D01*
G02X1409699Y303596I-758J-1179D01*
G03X1409667Y303036I269J-296D01*
G37*
G36*
G01X1393273Y303031D02*
G02X1391201Y303227I-1138J-980D01*
G03X1391269Y303785I-249J313D01*
G02X1391447Y305686I1111J855D01*
G03X1391381Y306331I-266J299D01*
G02X1391365Y308920I754J1299D01*
G03X1391422Y309565I-205J343D01*
G02X1393105Y309450I918J1060D01*
G03X1393073Y308803I218J-335D01*
G02X1393090Y306471I-938J-1173D01*
G03X1393130Y305824I254J-309D01*
G02X1393311Y303591I-750J-1185D01*
G03X1393273Y303031I265J-299D01*
G37*
G36*
G01X1398773D02*
G02X1396701Y303227I-1138J-980D01*
G03X1396769Y303785I-249J313D01*
G02X1396947Y305686I1111J855D01*
G03X1396881Y306331I-266J299D01*
G02X1396780Y308865I754J1299D01*
G03X1396794Y309513I-227J329D01*
G02X1398482Y309510I846J1118D01*
G03X1398494Y308862I240J-320D01*
G02X1398590Y306471I-859J-1232D01*
G03X1398630Y305824I254J-309D01*
G02X1398811Y303591I-750J-1185D01*
G03X1398773Y303031I265J-299D01*
G37*
G36*
G01X1506795Y307781D02*
G02X1505065Y307774I-861J-1107D01*
G03X1505063Y308403I-248J314D01*
G02X1506793Y308410I861J1107D01*
G03X1506795Y307781I248J-314D01*
G37*
G36*
G01X1517258Y311593D02*
G02X1515138Y311731I-1119J-844D01*
G03X1515157Y312271I-286J280D01*
G02X1514885Y313745I1144J973D01*
G03X1514410Y314267I-377J134D01*
G02X1515402Y315196I-342J1360D01*
G03X1515891Y314689I381J-122D01*
G02X1517309Y312130I410J-1445D01*
G03X1517258Y311593I268J-296D01*
G37*
G36*
G01X1502911Y319322D02*
G02X1502139Y318167I627J-1254D01*
G03X1501551Y318547I-399J28D01*
G02X1502334Y319720I-711J1323D01*
G03X1502911Y319322I398J-40D01*
G37*
G36*
G01X1382298Y319187D02*
G02X1382066Y320699I-1394J560D01*
G03X1382741Y320791I309J253D01*
G02X1382970Y319301I1283J-565D01*
G03X1382298Y319187I-301J-263D01*
G37*
G36*
G01X1412451Y321208D02*
G02X1411987Y319490I936J-1175D01*
G03X1411378Y319668I-373J-145D01*
G02X1411835Y321361I-828J1132D01*
G03X1412451Y321208I367J160D01*
G37*
G36*
G01X1469827Y324466D02*
G02X1469558Y325886I-1428J465D01*
G03X1470243Y326005I309J254D01*
G02X1470508Y324606I1319J-475D01*
G03X1469827Y324466I-301J-264D01*
G37*
G36*
G01X1514759Y328814D02*
G02X1513140Y328685I-709J-1324D01*
G03X1513087Y329356I-242J318D01*
G02X1512491Y329936I709J1324D01*
G03X1511798Y329938I-347J-198D01*
G02X1511780Y331372I-1214J702D01*
G03X1512473Y331391I341J209D01*
G02X1515243Y331083I1323J-711D01*
G03X1515941Y330942I385J108D01*
G02X1515668Y329602I1174J-937D01*
G03X1514970Y329743I-385J-108D01*
G02X1514706Y329485I-1174J937D01*
G03X1514759Y328814I242J-318D01*
G37*
G36*
G01X1498346Y336280D02*
G02X1497117Y334564I254J-1480D01*
G03X1496654Y334896I-395J-62D01*
G02X1494986Y336881I-254J1480D01*
G03X1494785Y337375I-377J135D01*
G02X1494532Y339917I660J1349D01*
G03X1494626Y340449I-243J317D01*
G02X1496726Y340139I1184J751D01*
G03X1496663Y339602I262J-303D01*
G02X1496692Y339561I-1211J-888D01*
G03X1497000Y339532I166J112D01*
G02X1498123Y339942I996J-986D01*
G03X1498510Y340532I36J399D01*
G02X1501330Y341199I1319J718D01*
G03X1501697Y340786I400J-14D01*
G02X1500181Y339358I-114J-1397D01*
G03X1499791Y339748I-400J-10D01*
G02X1499651Y339759I48J1501D01*
G03X1499247Y339180I-47J-397D01*
G02X1498203Y337159I-1250J-634D01*
G03X1497870Y336682I59J-396D01*
G02X1497883Y336612I-1470J-309D01*
G03X1498346Y336280I395J62D01*
G37*
G36*
G01X1409839Y336253D02*
G02X1408638Y337910I-1491J183D01*
G03X1409108Y338233I76J392D01*
G02X1409130Y338332I1379J-254D01*
G03X1408866Y338568I-194J49D01*
G02X1409775Y339789I-490J1314D01*
G03X1410244Y339368I399J-27D01*
G02X1410292Y336600I246J-1380D01*
G03X1409839Y336253I-56J-396D01*
G37*
G36*
G01X1483756Y337225D02*
G02X1482690Y338295I-1370J-299D01*
G03X1483164Y338783I86J390D01*
G02X1483120Y339079I1456J368D01*
G03X1482690Y339458I-400J-20D01*
G02X1483980Y340998I-105J1398D01*
G03X1484429Y340642I398J41D01*
G02X1484246Y337697I191J-1490D01*
G03X1483756Y337225I-99J-387D01*
G37*
G36*
G01X1389038Y342619D02*
G02X1387422Y342650I-830J-1130D01*
G03X1387328Y343360I-224J332D01*
G02X1387470Y349085I972J2840D01*
G03X1387612Y349779I-111J384D01*
G02X1389292Y349707I888J1085D01*
G03X1389374Y349003I225J-331D01*
G02X1389890Y348746I-1074J-2803D01*
G03X1390468Y348926I211J340D01*
G02X1391726Y346828I1377J-601D01*
G03X1391295Y346402I-32J-399D01*
G02X1391302Y346214I-2995J-206D01*
G03X1391879Y345857I400J2D01*
G02X1391200Y344075I621J-1257D01*
G03X1390532Y344192I-371J-150D01*
G02X1389161Y343324I-2232J2008D01*
G03X1389038Y342619I114J-383D01*
G37*
G36*
G01X1544660Y350933D02*
G02X1542396I-1132J-987D01*
G03Y351459I-302J263D01*
G02X1542591Y353620I1132J987D01*
G03X1542465Y354312I-250J312D01*
G02X1544285Y356393I467J1428D01*
G03X1544968Y356331I360J174D01*
G02X1544829Y354793I1214J-885D01*
G03X1544146Y354855I-360J-174D01*
G02X1543869Y354566I-1213J886D01*
G03X1543995Y353874I250J-312D01*
G02X1544660Y351459I-467J-1428D01*
G03Y350933I302J-263D01*
G37*
G36*
G01X1497437Y350438D02*
G02X1496400Y351448I-1437J-438D01*
G03X1496893Y351938I107J385D01*
G02X1497221Y353261I1353J367D01*
G03X1497205Y353822I-293J272D01*
G02X1497150Y355932I1041J1083D01*
G03Y356478I-292J273D01*
G02X1497139Y358521I1096J1027D01*
G03X1497153Y359046I-294J271D01*
G02X1497227Y361046I1156J959D01*
G03X1497213Y361614I-289J277D01*
G02X1497220Y363802I1033J1091D01*
G03X1497221Y364385I-273J292D01*
G02X1499191Y364431I962J1020D01*
G03X1499220Y363849I288J-277D01*
G02X1499328Y361664I-974J-1143D01*
G03X1499342Y361096I289J-277D01*
G02X1499416Y358989I-1033J-1091D01*
G03X1499402Y358464I294J-271D01*
G02X1499342Y356478I-1156J-959D01*
G03Y355932I292J-273D01*
G02X1499287Y353822I-1096J-1027D01*
G03X1499271Y353261I277J-289D01*
G02X1497914Y350943I-1025J-956D01*
G03X1497437Y350438I-94J-389D01*
G37*
G36*
G01X1588960Y351816D02*
G02Y350175I1258J-820D01*
G03X1588290I-335J-219D01*
G02Y351816I-1258J821D01*
G03X1588960I335J219D01*
G37*
G36*
G01X-8748Y355048D02*
G02X-12807Y356382I-1488J2314D01*
G03X-13547Y356400I-374J-143D01*
G02Y358324I-2201J962D01*
G03X-12807Y358342I366J161D01*
G02X-8764Y359686I2571J-980D01*
G03X-7510Y359273I1283J1786D01*
G01X-7487D01*
X-7480D01*
G03X-6213Y359676I-2J2199D01*
G02X-2154Y358342I1488J-2314D01*
G03X-1414Y358324I374J143D01*
G02X2988I2201J-962D01*
G03X3728Y358342I366J161D01*
G02X7771Y359686I2571J-980D01*
G03X9025Y359273I1283J1786D01*
G01X9049D01*
X9056D01*
G03X10323Y359676I-2J2199D01*
G02X14382Y358342I1488J-2314D01*
G03X15122Y358324I374J143D01*
G02X19524I2201J-962D01*
G03X20264Y358342I366J161D01*
G02X24307Y359686I2571J-980D01*
G03X25561Y359273I1283J1786D01*
G01X25584D01*
X25591D01*
G03X26858Y359676I-2J2199D01*
G02X30917Y358342I1488J-2314D01*
G03X31657Y358324I374J143D01*
G02Y356400I2201J-962D01*
G03X30917Y356382I-366J-161D01*
G02X26874Y355038I-2571J980D01*
G03X25620Y355451I-1283J-1786D01*
G01X25597D01*
X25590D01*
G03X24323Y355048I2J-2199D01*
G02X20264Y356382I-1488J2314D01*
G03X19524Y356400I-374J-143D01*
G02X15122I-2201J962D01*
G03X14382Y356382I-366J-161D01*
G02X10339Y355038I-2571J980D01*
G03X9085Y355451I-1283J-1786D01*
G01X9061D01*
X9054D01*
G03X7787Y355048I2J-2199D01*
G02X3728Y356382I-1488J2314D01*
G03X2988Y356400I-374J-143D01*
G02X-1414I-2201J962D01*
G03X-2154Y356382I-366J-161D01*
G02X-6197Y355038I-2571J980D01*
G03X-7451Y355451I-1283J-1786D01*
G01X-7474D01*
X-7481D01*
G03X-8748Y355048I2J-2199D01*
G37*
G36*
G01X1609421Y356560D02*
G02X1608269Y357880I-1401J-60D01*
G03X1608739Y358290I71J394D01*
G02X1609891Y356970I1401J60D01*
G03X1609421Y356560I-71J-394D01*
G37*
G36*
G01X1484833Y357904D02*
G02X1482801Y357811I-965J-1151D01*
G03X1482774Y358399I-284J282D01*
G02X1483010Y360862I966J1150D01*
G03X1482994Y361570I-195J350D01*
G02X1482553Y363925I670J1344D01*
G03X1482534Y364484I-295J270D01*
G02X1484587Y364615I966J1016D01*
G03X1484638Y364058I310J-252D01*
G02X1484394Y361602I-974J-1143D01*
G03X1484410Y360894I195J-350D01*
G02X1484806Y358492I-670J-1344D01*
G03X1484833Y357904I284J-282D01*
G37*
G36*
G01X1576954Y360938D02*
G02X1575455Y361078I-881J-1338D01*
G03X1575541Y361767I-154J369D01*
G02X1576998Y361632I839J1123D01*
G03X1576954Y360938I176J-360D01*
G37*
G36*
G01X1608786Y360618D02*
G02X1608339Y361947I-1374J277D01*
G03X1608996Y362167I265J300D01*
G02X1609443Y360838I1374J-277D01*
G03X1608786Y360618I-265J-300D01*
G37*
G36*
G01X-13866Y362922D02*
G02X-13882Y367560I-1488J2314D01*
G03X-12628Y367147I1283J1786D01*
G01X-12605D01*
X-12598D01*
G03X-11331Y367550I-2J2199D01*
G02X-7272Y366216I1488J-2314D01*
G03X-6532Y366198I374J143D01*
G02X-2130I2201J-962D01*
G03X-1390Y366216I366J161D01*
G02X2653Y367560I2571J-980D01*
G03X3907Y367147I1283J1786D01*
G01X3931D01*
X3938D01*
G03X5205Y367550I-2J2199D01*
G02X9264Y366216I1488J-2314D01*
G03X10004Y366198I374J143D01*
G02X14405Y366199I2201J-962D01*
G03X15145Y366217I366J161D01*
G02X19188Y367560I2570J-981D01*
G03X20442Y367147I1283J1786D01*
G01X20466D01*
X20473D01*
G03X21740Y367550I-2J2199D01*
G02X25799Y366216I1488J-2314D01*
G03X26539Y366198I374J143D01*
G02Y364274I2201J-962D01*
G03X25799Y364256I-366J-161D01*
G02X21756Y362912I-2571J980D01*
G03X20502Y363325I-1283J-1786D01*
G01X20478D01*
X20471D01*
G03X19204Y362922I2J-2199D01*
G02X15145Y364255I-1488J2314D01*
G03X14405Y364273I-374J-143D01*
G02X10004Y364274I-2200J963D01*
G03X9264Y364256I-366J-161D01*
G02X5221Y362912I-2571J980D01*
G03X3967Y363325I-1283J-1786D01*
G01X3943D01*
X3936D01*
G03X2669Y362922I2J-2199D01*
G02X-1390Y364256I-1488J2314D01*
G03X-2130Y364274I-374J-143D01*
G02X-6532I-2201J962D01*
G03X-7272Y364256I-366J-161D01*
G02X-11315Y362912I-2571J980D01*
G03X-12569Y363325I-1283J-1786D01*
G01X-12592D01*
X-12599D01*
G03X-13866Y362922I2J-2199D01*
G37*
G36*
G01X1419025Y367244D02*
G02X1418512Y368658I-1369J303D01*
G03X1419146Y368888I244J317D01*
G02X1419659Y367474I1369J-303D01*
G03X1419025Y367244I-244J-317D01*
G37*
G36*
G01X1444328Y369627D02*
G02X1442884Y370335I-1228J-677D01*
G03X1443172Y370923I-62J395D01*
G02X1444616Y370215I1228J677D01*
G03X1444328Y369627I62J-395D01*
G37*
G36*
G01X7787Y370796D02*
G02X3728Y372130I-1488J2314D01*
G03X2988Y372148I-374J-143D01*
G02Y374072I-2201J962D01*
G03X3728Y374090I366J161D01*
G02X7771Y375434I2571J-980D01*
G03X9025Y375021I1283J1786D01*
G01X9049D01*
X9056D01*
G03X10323Y375424I-2J2199D01*
G02X14382Y374090I1488J-2314D01*
G03X15122Y374072I374J143D01*
G02X19524I2201J-962D01*
G03X20264Y374090I366J161D01*
G02X24307Y375434I2571J-980D01*
G03X25561Y375021I1283J1786D01*
G01X25584D01*
X25591D01*
G03X26858Y375424I-2J2199D01*
G02X30917Y374090I1488J-2314D01*
G03X31657Y374072I374J143D01*
G02Y372148I2201J-962D01*
G03X30917Y372130I-366J-161D01*
G02X26874Y370786I-2571J980D01*
G03X25620Y371199I-1283J-1786D01*
G01X25597D01*
X25590D01*
G03X24323Y370796I2J-2199D01*
G02X20264Y372130I-1488J2314D01*
G03X19524Y372148I-374J-143D01*
G02X15122I-2201J962D01*
G03X14382Y372130I-366J-161D01*
G02X10339Y370786I-2571J980D01*
G03X9085Y371199I-1283J-1786D01*
G01X9061D01*
X9054D01*
G03X7787Y370796I2J-2199D01*
G37*
G36*
G01X1446821Y375813D02*
G02X1446851Y374046I1229J-863D01*
G03X1446214Y374048I-319J-241D01*
G02X1446184Y375789I-1114J852D01*
G03X1446821Y375813I309J254D01*
G37*
G36*
G01X1419168Y379444D02*
G02X1418759Y377893I907J-1069D01*
G03X1418124Y378060I-376J-138D01*
G02X1416499Y380333I-907J1069D01*
G03X1416528Y381001I-205J344D01*
G02X1418087Y383329I821J1136D01*
G03X1418692Y383604I210J340D01*
G02X1419337Y382183I1383J-229D01*
G03X1418732Y381908I-210J-340D01*
G02X1418067Y380933I-1383J229D01*
G03X1418038Y380265I205J-344D01*
G02X1418533Y379611I-821J-1136D01*
G03X1419168Y379444I376J138D01*
G37*
G36*
G01X-13866Y378670D02*
G02X-13882Y383308I-1488J2314D01*
G03X-12628Y382895I1283J1786D01*
G01X-12605D01*
X-12598D01*
G03X-11331Y383298I-2J2199D01*
G02X-7272Y381964I1488J-2314D01*
G03X-6532Y381946I374J143D01*
G02X-2130I2201J-962D01*
G03X-1390Y381964I366J161D01*
G02X2653Y383308I2571J-980D01*
G03X3907Y382895I1283J1786D01*
G01X3931D01*
X3938D01*
G03X5205Y383298I-2J2199D01*
G02X9264Y381964I1488J-2314D01*
G03X10004Y381946I374J143D01*
G02Y380022I2201J-962D01*
G03X9264Y380004I-366J-161D01*
G02X5221Y378660I-2571J980D01*
G03X3967Y379073I-1283J-1786D01*
G01X3943D01*
X3936D01*
G03X2669Y378670I2J-2199D01*
G02X-1390Y380004I-1488J2314D01*
G03X-2130Y380022I-374J-143D01*
G02X-6532I-2201J962D01*
G03X-7272Y380004I-366J-161D01*
G02X-11315Y378660I-2571J980D01*
G03X-12569Y379073I-1283J-1786D01*
G01X-12592D01*
X-12599D01*
G03X-13866Y378670I2J-2199D01*
G37*
G36*
G01X1457806Y382773D02*
G02X1455865Y382938I-1056J-923D01*
G03X1455901Y383526I-252J311D01*
G02X1456042Y385742I1080J1044D01*
G03X1456025Y386379I-250J312D01*
G02X1457839Y386427I875J1221D01*
G03X1457856Y385790I250J-312D01*
G02X1457870Y383358I-875J-1221D01*
G03X1457806Y382773I237J-322D01*
G37*
G36*
G01X1419527Y386552D02*
G02X1418256Y387758I-1389J-191D01*
G03X1418686Y388211I34J399D01*
G02X1419957Y387005I1389J191D01*
G03X1419527Y386552I-34J-399D01*
G37*
G36*
G01X24323Y386544D02*
G02X20264Y387878I-1488J2314D01*
G03X19524Y387896I-374J-143D01*
G02Y389820I-2201J962D01*
G03X20264Y389838I366J161D01*
G02X24307Y391182I2571J-980D01*
G03X25561Y390769I1283J1786D01*
G01X25584D01*
X25591D01*
G03X26858Y391172I-2J2199D01*
G02X30917Y389838I1488J-2314D01*
G03X31657Y389820I374J143D01*
G02Y387896I2201J-962D01*
G03X30917Y387878I-366J-161D01*
G02X26874Y386534I-2571J980D01*
G03X25620Y386947I-1283J-1786D01*
G01X25597D01*
X25590D01*
G03X24323Y386544I2J-2199D01*
G37*
G36*
G01X1470953Y393463D02*
G02X1469582Y393653I-853J-1113D01*
G03X1469737Y394285I-148J371D01*
G02X1469538Y395811I1063J915D01*
G03X1469332Y396354I-360J174D01*
G02X1468754Y396803I541J1294D01*
G03X1468106Y396791I-320J-241D01*
G02X1467179Y396177I-1234J856D01*
G03X1466869Y395700I81J-392D01*
G02X1464137Y395727I-1369J-301D01*
G03X1463858Y396204I-389J93D01*
G02X1465300Y398744I415J1444D01*
G03X1465846I273J292D01*
G02X1468106Y398505I1027J-1096D01*
G03X1468754Y398493I328J229D01*
G02X1470966Y398526I1119J-845D01*
G03X1471560Y398493I312J250D01*
G02X1472536Y396098I990J-993D01*
G03X1472147Y395588I-4J-400D01*
G02X1472183Y395433I-1346J-394D01*
G03X1472689Y395116I394J67D01*
G02X1471700Y393537I394J-1346D01*
G03X1471194Y393854I-394J-67D01*
G02X1471040Y393819I-387J1348D01*
G03X1470953Y393463I34J-197D01*
G37*
G36*
G01X1420951Y394497D02*
G02X1419219Y394512I-876J-1095D01*
G03X1419225Y395141I-244J317D01*
G02X1420957Y395126I876J1095D01*
G03X1420951Y394497I244J-317D01*
G37*
G36*
G01X-13866Y394418D02*
G02X-13882Y399056I-1488J2314D01*
G03X-12628Y398643I1283J1786D01*
G01X-12605D01*
X-12598D01*
G03X-11331Y399046I-2J2199D01*
G02X-7272Y397712I1488J-2314D01*
G03X-6532Y397694I374J143D01*
G02X-2130I2201J-962D01*
G03X-1390Y397712I366J161D01*
G02X2653Y399056I2571J-980D01*
G03X3907Y398643I1283J1786D01*
G01X3931D01*
X3938D01*
G03X5205Y399046I-2J2199D01*
G02X9264Y397712I1488J-2314D01*
G03X10004Y397694I374J143D01*
G02Y395770I2201J-962D01*
G03X9264Y395752I-366J-161D01*
G02X5221Y394408I-2571J980D01*
G03X3967Y394821I-1283J-1786D01*
G01X3943D01*
X3936D01*
G03X2669Y394418I2J-2199D01*
G02X-1390Y395752I-1488J2314D01*
G03X-2130Y395770I-374J-143D01*
G02X-6532I-2201J962D01*
G03X-7272Y395752I-366J-161D01*
G02X-11315Y394408I-2571J980D01*
G03X-12569Y394821I-1283J-1786D01*
G01X-12592D01*
X-12599D01*
G03X-13866Y394418I2J-2199D01*
G37*
G36*
G01X1414941Y397017D02*
G02X1413513Y397686I-1206J-715D01*
G03X1413794Y398285I-63J395D01*
G02X1415222Y397616I1206J715D01*
G03X1414941Y397017I63J-395D01*
G37*
G36*
G01X1469824Y403256D02*
G02X1469740Y401333I976J-1006D01*
G03X1469145Y401344I-302J-262D01*
G02X1466863Y401447I-1097J1026D01*
G03X1466233I-315J-246D01*
G02X1463753Y403131I-1185J923D01*
G03X1463606Y403682I-345J203D01*
G02X1464441Y406295I694J1218D01*
G03X1464881Y406710I41J398D01*
G02X1467615Y407630I1501J63D01*
G03X1468263Y407618I328J229D01*
G02X1470311Y407823I1119J-845D01*
G03X1470870Y407851I265J299D01*
G02X1470971Y405850I1030J-951D01*
G03X1470412Y405822I-265J-299D01*
G02X1468263Y405928I-1030J951D01*
G03X1467615Y405916I-320J-241D01*
G02X1466161Y405287I-1234J857D01*
G03X1465702Y404894I-59J-395D01*
G02X1465545Y404255I-1402J6D01*
G03X1465721Y403713I355J-184D01*
G02X1466233Y403293I-673J-1343D01*
G03X1466863I315J246D01*
G02X1469230Y403296I1185J-923D01*
G03X1469824Y403256I315J247D01*
G37*
G36*
G01X-8748Y402292D02*
G02X-12807Y403626I-1488J2314D01*
G03X-13547Y403644I-374J-143D01*
G02Y405568I-2201J962D01*
G03X-12807Y405586I366J161D01*
G02X-8764Y406930I2571J-980D01*
G03X-7510Y406517I1283J1786D01*
G01X-7487D01*
X-7480D01*
G03X-6213Y406920I-2J2199D01*
G02X-2154Y405586I1488J-2314D01*
G03X-1414Y405568I374J143D01*
G02X2988I2201J-962D01*
G03X3728Y405586I366J161D01*
G02X7771Y406930I2571J-980D01*
G03X9025Y406517I1283J1786D01*
G01X9049D01*
X9056D01*
G03X10323Y406920I-2J2199D01*
G02X14382Y405586I1488J-2314D01*
G03X15122Y405568I374J143D01*
G02X19524I2201J-962D01*
G03X20264Y405586I366J161D01*
G02X24307Y406930I2571J-980D01*
G03X25561Y406517I1283J1786D01*
G01X25584D01*
X25591D01*
G03X26858Y406920I-2J2199D01*
G02X30917Y405586I1488J-2314D01*
G03X31657Y405568I374J143D01*
G02Y403644I2201J-962D01*
G03X30917Y403626I-366J-161D01*
G02X26874Y402282I-2571J980D01*
G03X25620Y402695I-1283J-1786D01*
G01X25597D01*
X25590D01*
G03X24323Y402292I2J-2199D01*
G02X20264Y403626I-1488J2314D01*
G03X19524Y403644I-374J-143D01*
G02X15122I-2201J962D01*
G03X14382Y403626I-366J-161D01*
G02X10339Y402282I-2571J980D01*
G03X9085Y402695I-1283J-1786D01*
G01X9061D01*
X9054D01*
G03X7787Y402292I2J-2199D01*
G02X3728Y403626I-1488J2314D01*
G03X2988Y403644I-374J-143D01*
G02X-1414I-2201J962D01*
G03X-2154Y403626I-366J-161D01*
G02X-6197Y402282I-2571J980D01*
G03X-7451Y402695I-1283J-1786D01*
G01X-7474D01*
X-7481D01*
G03X-8748Y402292I2J-2199D01*
G37*
G36*
G01X1440542Y407638D02*
G02X1438498Y408013I-1192J-738D01*
G03X1438583Y408561I-243J318D01*
G02X1438852Y410576I1230J861D01*
G03X1438818Y411216I-256J307D01*
G02X1440612Y411312I833J1250D01*
G03X1440646Y410672I256J-307D01*
G02X1440657Y408180I-833J-1250D01*
G03X1440542Y407638I225J-331D01*
G37*
G36*
G01X-13866Y410166D02*
G02X-13882Y414804I-1488J2314D01*
G03X-12628Y414391I1283J1786D01*
G01X-12605D01*
X-12598D01*
G03X-11331Y414794I-2J2199D01*
G02X-7272Y413460I1488J-2314D01*
G03X-6532Y413442I374J143D01*
G02X-2130I2201J-962D01*
G03X-1390Y413460I366J161D01*
G02X2653Y414804I2571J-980D01*
G03X3907Y414391I1283J1786D01*
G01X3931D01*
X3938D01*
G03X5205Y414794I-2J2199D01*
G02X9264Y413460I1488J-2314D01*
G03X10004Y413442I374J143D01*
G02X14405Y413443I2201J-962D01*
G03X15145Y413461I366J161D01*
G02X19188Y414804I2570J-981D01*
G03X20442Y414391I1283J1786D01*
G01X20466D01*
X20473D01*
G03X21740Y414794I-2J2199D01*
G02X25799Y413460I1488J-2314D01*
G03X26539Y413442I374J143D01*
G02Y411518I2201J-962D01*
G03X25799Y411500I-366J-161D01*
G02X21756Y410156I-2571J980D01*
G03X20502Y410569I-1283J-1786D01*
G01X20478D01*
X20471D01*
G03X19204Y410166I2J-2199D01*
G02X15145Y411499I-1488J2314D01*
G03X14405Y411517I-374J-143D01*
G02X10004Y411518I-2200J963D01*
G03X9264Y411500I-366J-161D01*
G02X5221Y410156I-2571J980D01*
G03X3967Y410569I-1283J-1786D01*
G01X3943D01*
X3936D01*
G03X2669Y410166I2J-2199D01*
G02X-1390Y411500I-1488J2314D01*
G03X-2130Y411518I-374J-143D01*
G02X-6532I-2201J962D01*
G03X-7272Y411500I-366J-161D01*
G02X-11315Y410156I-2571J980D01*
G03X-12569Y410569I-1283J-1786D01*
G01X-12592D01*
X-12599D01*
G03X-13866Y410166I2J-2199D01*
G37*
G36*
G01X1370783Y458965D02*
G02X1370811Y457244I1245J-840D01*
G03X1370165Y457246I-324J-234D01*
G02X1370136Y458941I-1131J828D01*
G03X1370783Y458965I315J247D01*
G37*
G36*
G01X-5037Y465901D02*
G02X-6839Y466148I-1063J-1061D01*
G03X-6753Y466779I-197J348D01*
G02X-4951Y466532I1063J1061D01*
G03X-5037Y465901I197J-348D01*
G37*
G36*
G01X1826107Y474786D02*
G02X1824222Y475172I-1147J-806D01*
G03X1824281Y475808I-210J340D01*
G02X1825297Y478438I1016J1119D01*
G01X1828802D01*
G03X1829117Y479085I0J400D01*
G02X1830956Y478757I1103J865D01*
G03X1830915Y478104I209J-341D01*
G02X1831478Y476937I-948J-1177D01*
G01Y476842D01*
X1831469Y476758D01*
G02X1829967Y475416I-1502J169D01*
G01X1826435D01*
G03X1826107Y474786I0J-400D01*
G37*
G36*
G01X1817375Y476808D02*
X1812375D01*
G02X1811490Y479545I0J1512D01*
G03X1811493Y480191I-234J324D01*
G02X1813442Y480473I832J1129D01*
G03X1813761Y479832I319J-241D01*
G01X1815889D01*
G03X1816208Y480473I0J400D01*
G02X1818194Y480220I1117J847D01*
G03X1818219Y479574I248J-314D01*
G02X1818886Y478330I-844J-1254D01*
G01Y478235D01*
X1818877Y478151D01*
G02X1817375Y476808I-1502J169D01*
G37*
G36*
G01X1362050Y480753D02*
G02X1362095Y482533I-1187J921D01*
G03X1362728Y482504I328J229D01*
G02X1364641Y482722I1072J-904D01*
G03X1365188Y482786I240J320D01*
G02X1365373Y480674I1153J-963D01*
G03X1364823Y480642I-258J-306D01*
G02X1362685Y480750I-1023J958D01*
G03X1362050Y480753I-319J-242D01*
G37*
G36*
G01X1653019Y483227D02*
G02X1650787Y483176I-1093J-1030D01*
G03X1650774Y483711I-304J260D01*
G02X1651066Y486012I1093J1030D01*
G03X1651042Y486702I-213J338D01*
G02X1652555Y486754I712J1323D01*
G03X1652579Y486064I213J-338D01*
G02X1653006Y483762I-712J-1323D01*
G03X1653019Y483227I304J-260D01*
G37*
G36*
G01X1417874Y483914D02*
G02X1417053Y481948I567J-1391D01*
G03X1416554Y482174I-370J-153D01*
G02X1415269Y482371I-454J1326D01*
G03X1414646Y482150I-236J-323D01*
G02X1414127Y483709I-1453J382D01*
G03X1414758Y483906I248J313D01*
G02X1417362Y484110I1342J-406D01*
G03X1417874Y483914I360J174D01*
G37*
G36*
G01X1361979Y485673D02*
G02X1361910Y487467I-1238J851D01*
G03X1362541Y487478I311J251D01*
G02X1364644Y487636I1121J-842D01*
G03X1365216Y487648I280J286D01*
G02X1365202Y485603I1093J-1030D01*
G03X1364630Y485622I-295J-270D01*
G02X1362609Y485710I-968J1014D01*
G03X1361979Y485673I-301J-264D01*
G37*
G36*
G01X1642145Y488084D02*
G02X1640987Y489147I-1364J-324D01*
G03X1641432Y489648I59J395D01*
G02X1642607Y488570I1448J399D01*
G03X1642145Y488084I-73J-393D01*
G37*
G36*
G01X729810Y487918D02*
G02X729279Y489554I-1437J438D01*
G03X729902Y489757I240J319D01*
G02X730433Y488121I1437J-438D01*
G03X729810Y487918I-240J-319D01*
G37*
G36*
G01X1851740Y493715D02*
G02X1851295Y492096I979J-1140D01*
G03X1850667Y492282I-379J-127D01*
G02X1851106Y493876I-872J1098D01*
G03X1851740Y493715I374J142D01*
G37*
G36*
G01X704195Y491823D02*
G02X702251Y493767I-1167J777D01*
G03Y494433I-222J333D01*
G02X704195Y496377I777J1167D01*
G03X704861I333J222D01*
G02X707195I1167J-777D01*
G03X707861I333J222D01*
G02Y494823I1167J-777D01*
G03X707195I-333J-222D01*
G02X706805Y494433I-1167J777D01*
G03Y493767I222J-333D01*
G02X704861Y491823I-777J-1167D01*
G03X704195I-333J-222D01*
G37*
G36*
G01X1672992Y495292D02*
G02X1671448Y495365I-833J-1250D01*
G03X1671480Y496050I-190J352D01*
G02X1671378Y498475I833J1250D01*
G03X1671457Y499017I-249J313D01*
G02X1673541Y498775I1149J803D01*
G03X1673493Y498229I266J-299D01*
G02X1673024Y495977I-1180J-929D01*
G03X1672992Y495292I190J-352D01*
G37*
G36*
G01X1414214Y493929D02*
G02X1413771Y495317I-1473J295D01*
G03X1414434Y495517I274J291D01*
G02X1417030Y495873I1366J-317D01*
G03X1417583Y495720I351J192D01*
G02X1416987Y493772I758J-1297D01*
G03X1416443Y493954I-360J-173D01*
G02X1414871Y494150I-643J1246D01*
G03X1414214Y493929I-265J-300D01*
G37*
G36*
G01X1641020Y497133D02*
G02X1640560Y495429I943J-1169D01*
G03X1639948Y495608I-374J-143D01*
G02X1640401Y497287I-835J1126D01*
G03X1641020Y497133I368J157D01*
G37*
G36*
G01X1270425Y496507D02*
G02X1267750Y495193I-1420J-490D01*
G03X1267152Y495274I-334J-220D01*
G02X1267418Y497227I-990J1129D01*
G03X1268016Y497146I334J220D01*
G02X1269244Y497499I990J-1130D01*
G03X1269686Y498025I64J395D01*
G02X1270867Y497033I1419J491D01*
G03X1270425Y496507I-64J-395D01*
G37*
G36*
G01X1320594Y499773D02*
G02X1318998Y499049I-294J-1473D01*
G03X1318745Y499637I-347J199D01*
G02X1318149Y499948I332J1362D01*
G03X1317616Y499944I-264J-301D01*
G02X1315733Y499945I-941J1039D01*
G03X1315199Y499949I-269J-296D01*
G02X1313299Y499990I-928J1051D01*
G03X1312745I-277J-288D01*
G02X1311771Y499598I-972J1010D01*
G03X1311371Y499210I0J-400D01*
G02X1309954Y500754I-1501J44D01*
G03X1310375Y501119I23J399D01*
G02X1312745Y502010I1397J-119D01*
G03X1313299I277J288D01*
G02X1315214Y502038I972J-1010D01*
G03X1315748Y502034I269J296D01*
G02X1317601Y502035I927J-1051D01*
G03X1318134Y502039I264J301D01*
G02X1320317Y500351I940J-1040D01*
G03X1320594Y499773I355J-185D01*
G37*
G36*
G01X723743Y500493D02*
G02X722373Y499367I5J-1402D01*
G03X721963Y499846I-392J79D01*
G02X723353Y500988I-69J1500D01*
G03X723743Y500493I388J-95D01*
G37*
G36*
G01X1694025Y501178D02*
G02X1693013Y499711I385J-1348D01*
G03X1692505Y500062I-399J-34D01*
G02X1690835Y501971I-385J1348D01*
G03X1690389Y502523I-367J160D01*
G02X1688650Y503572I-298J1472D01*
G03X1688105Y503825I-384J-113D01*
G02X1686375Y504205I-605J1375D01*
G03X1685775I-300J-265D01*
G02Y506195I-1125J995D01*
G03X1686375I300J265D01*
G02X1688941Y505623I1125J-995D01*
G03X1689486Y505370I384J113D01*
G02X1691450Y503356I605J-1375D01*
G03X1691880Y502791I362J-171D01*
G02X1693517Y501529I240J-1381D01*
G03X1694025Y501178I399J34D01*
G37*
G36*
G01X680346Y502988D02*
G02X680219Y504688I-1297J758D01*
G03X680868Y504724I312J251D01*
G02X683217Y504747I1182J-754D01*
G03X683883I333J222D01*
G02Y503193I1167J-777D01*
G03X683217I-333J-222D01*
G02X680993Y503049I-1167J777D01*
G03X680346Y502988I-302J-263D01*
G37*
G36*
G01X-16228Y504962D02*
G02X-17656Y504700I-498J-1311D01*
G03X-17791Y505378I-265J300D01*
G02X-16342Y505643I489J1420D01*
G03X-16228Y504962I256J-307D01*
G37*
G36*
G01X1643598Y506571D02*
G02X1643192Y505142I1053J-1071D01*
G03X1642523Y505332I-388J-95D01*
G02X1640001Y506092I-1053J1071D01*
G03X1639562Y506406I-391J-83D01*
G02X1640746Y508169I-168J1392D01*
G03X1641203Y507881I386J106D01*
G02X1642929Y506761I267J-1478D01*
G03X1643598Y506571I388J95D01*
G37*
G36*
G01X1958589Y507241D02*
G02X1957865Y505872I671J-1231D01*
G03X1957264Y506177I-398J-40D01*
G02X1957999Y507567I-764J1293D01*
G03X1958589Y507241I399J25D01*
G37*
G36*
G01X1345941Y508897D02*
G02X1345750Y507224I1140J-978D01*
G03X1345102Y507310I-354J-186D01*
G02X1345290Y508959I-1029J953D01*
G03X1345941Y508897I347J198D01*
G37*
G36*
G01X713248Y511896D02*
G02X713116Y513666I-1148J804D01*
G03X713743Y513726I290J275D01*
G02X713877Y511929I1266J-809D01*
G03X713248Y511896I-302J-263D01*
G37*
G36*
G01X653167Y513123D02*
G02Y514677I-1167J777D01*
G03X653833I333J222D01*
G02Y513123I1167J-777D01*
G03X653167I-333J-222D01*
G37*
G36*
G01X659667D02*
G02Y514677I-1167J777D01*
G03X660333I333J222D01*
G02Y513123I1167J-777D01*
G03X659667I-333J-222D01*
G37*
G36*
G01X1797553Y514117D02*
G02X1796878Y515400I-1400J83D01*
G03X1797483Y515719I206J343D01*
G02X1799900Y516601I1400J-83D01*
G03X1800487Y516608I290J275D01*
G02X1800460Y514622I1113J-1008D01*
G03X1799874Y514644I-303J-261D01*
G02X1798158Y514436I-991J992D01*
G03X1797553Y514117I-206J-343D01*
G37*
G36*
G01X1644636Y515562D02*
G02X1644608Y514234I1333J-692D01*
G03X1643896Y514259I-362J-169D01*
G02X1643923Y515567I-1226J680D01*
G03X1644636Y515562I358J179D01*
G37*
G36*
G01X58748Y517276D02*
G02X57124I-812J-1264D01*
G03Y517948I-216J336D01*
G02X56933Y518094I814J1263D01*
G03X56420Y518113I-268J-297D01*
G02X54397Y518281I-920J1187D01*
G03X54103I-147J-136D01*
G02X54037Y518214I-1102J1020D01*
G03X54036Y517925I138J-145D01*
G02X51848Y517819I-1044J-1079D01*
G03X51849Y518335I-305J259D01*
G02X51868Y520287I1151J965D01*
G03Y520813I-302J263D01*
G02Y522787I1132J987D01*
G03Y523313I-302J263D01*
G02X51736Y523488I1130J990D01*
G03X51064I-336J-216D01*
G02X48577Y523428I-1264J812D01*
G03X47885Y523355I-325J-233D01*
G02X46049Y525384I-1378J598D01*
G03X46230Y526025I-122J381D01*
G02X47827Y525574I1139J980D01*
G03X47646Y524933I122J-381D01*
G02X47730Y524825I-1143J-975D01*
G03X48422Y524898I325J233D01*
G02X51064Y525112I1378J-598D01*
G03X51736I336J216D01*
G02X53987Y525432I1264J-812D01*
G03X54513I263J302D01*
G02X56487I987J-1132D01*
G03X57013I263J302D01*
G02X58096Y525799I987J-1132D01*
G03X58517Y526262I26J399D01*
G02X59904Y525001I1483J238D01*
G03X59483Y524538I-26J-399D01*
G02X59132Y523313I-1483J-238D01*
G03Y522787I302J-263D01*
G02X59158Y522757I-1122J-999D01*
G03X59475Y522769I154J128D01*
G02X59673Y520804I1225J-869D01*
G03X59105Y520783I-274J-292D01*
G02X59075Y520751I-1111J1011D01*
G03X59061Y520207I286J-280D01*
G02X58748Y517948I-1125J-995D01*
G03Y517276I216J-336D01*
G37*
G36*
G01X1389321Y517663D02*
G02X1389190Y515874I1009J-973D01*
G03X1388577Y515919I-325J-233D01*
G02X1386599Y515879I-1009J973D01*
G03X1386036Y515869I-276J-289D01*
G02X1384096Y515805I-1003J979D01*
G03X1383551Y515796I-268J-297D01*
G02X1383515Y517848I-973J1009D01*
G03X1384060Y517857I268J297D01*
G02X1386002Y517861I973J-1009D01*
G03X1386565Y517871I276J289D01*
G02X1387959Y518239I1004J-979D01*
G03X1388120Y518600I54J192D01*
G02X1387833Y518839I746J1187D01*
G03X1387277Y518871I-294J-271D01*
G02X1385386Y518921I-918J1060D01*
G03X1384832I-277J-288D01*
G02X1382781Y519035I-973J1010D01*
G03X1382167Y519037I-308J-256D01*
G02X1380132Y518921I-1072J903D01*
G03X1379580Y518919I-275J-290D01*
G02X1377636Y518921I-971J1012D01*
G03X1377082I-277J-288D01*
G02X1375031Y519035I-973J1010D01*
G03X1374417Y519037I-308J-256D01*
G02X1374423Y520836I-1072J903D01*
G03X1375037Y520834I308J256D01*
G02X1377082Y520941I1073J-903D01*
G03X1377636I277J288D01*
G02X1379572Y520950I973J-1010D01*
G03X1380124Y520952I275J290D01*
G02X1382173Y520836I970J-1012D01*
G03X1382787Y520834I308J256D01*
G02X1384832Y520941I1073J-903D01*
G03X1385386I277J288D01*
G02X1387391Y520880I973J-1010D01*
G03X1387947Y520848I294J271D01*
G02X1387970Y520867I904J-1071D01*
G03X1387968Y521176I-128J154D01*
G02X1388072Y523433I882J1090D01*
G03X1388083Y524090I-222J332D01*
G02X1389678Y524063I817J1140D01*
G03X1389667Y523406I222J-332D01*
G02X1389874Y521308I-817J-1140D01*
G03X1389877Y520758I292J-273D01*
G02X1388967Y518390I-1012J-970D01*
G03X1388679Y517747I29J-399D01*
G02X1388708Y517708I-1110J-856D01*
G03X1389321Y517663I325J233D01*
G37*
G36*
G01X1867986Y516372D02*
G02X1867938Y517961I-1298J756D01*
G03X1868616Y517981I333J222D01*
G02X1868664Y516392I1298J-756D01*
G03X1867986Y516372I-333J-222D01*
G37*
G36*
G01X1835939Y519690D02*
G02X1834672Y520996I-1399J-90D01*
G03X1835107Y521437I37J398D01*
G02X1835155Y522011I1493J164D01*
G03X1834630Y522494I-385J109D01*
G02X1835545Y523489I-530J1406D01*
G03X1836070Y523006I385J-109D01*
G02X1836393Y520112I529J-1406D01*
G03X1835939Y519690I-55J-396D01*
G37*
G36*
G01X1861153Y521422D02*
G02X1859208Y521252I-873J-1222D01*
G03X1859024Y521919I-286J280D01*
G02X1861218Y522111I830J3144D01*
G03X1861153Y521422I167J-363D01*
G37*
G36*
G01X41429Y521343D02*
G02X40279Y522116I-1318J-720D01*
G03X40675Y522705I45J397D01*
G02X41825Y521932I1318J720D01*
G03X41429Y521343I-45J-397D01*
G37*
G36*
G01X1429921Y520514D02*
G02X1429687Y521920I-1421J486D01*
G03X1430378Y522024I316J245D01*
G02X1430608Y520638I1312J-494D01*
G03X1429921Y520514I-309J-254D01*
G37*
G36*
G01X1764059Y520415D02*
G02X1764044Y521785I-1344J670D01*
G03X1764756Y521794I354J187D01*
G02X1767258Y522081I1344J-670D01*
G03X1767862Y522067I308J255D01*
G02Y520181I1038J-943D01*
G03X1767258Y520167I-296J-269D01*
G02X1764771Y520424I-1158J957D01*
G03X1764059Y520415I-354J-187D01*
G37*
G36*
G01X1804213Y522569D02*
G02X1802541Y526180I-3227J698D01*
G03X1803122Y526459I188J353D01*
G02X1803575Y527253I1378J-260D01*
G03X1803409Y527942I-264J301D01*
G02X1802573Y528542I342J1359D01*
G03X1802006Y528653I-337J-216D01*
G02X1800267Y528754I-806J1147D01*
G03X1799632Y528612I-267J-298D01*
G02X1799293Y530281I-1382J588D01*
G03X1799932Y530398I277J288D01*
G02X1802379Y530559I1268J-598D01*
G03X1802946Y530448I337J216D01*
G02X1804677Y528248I806J-1147D01*
G03X1804843Y527559I264J-301D01*
G02X1805726Y525521I-343J-1359D01*
G03X1806076Y524927I350J-194D01*
G02X1804931Y522716I0J-1402D01*
G03X1804213Y522569I-327J-231D01*
G37*
G36*
G01X716858Y523292D02*
G02X715546Y523223I-591J-1272D01*
G03X715509Y523928I-206J343D01*
G02X715090Y526173I591J1272D01*
G03Y526727I-288J277D01*
G02X715006Y526823I1012J970D01*
G03X714694I-156J-125D01*
G02X713488Y526302I-1094J877D01*
G03X713067Y525810I-32J-399D01*
G02X711816Y526881I-1363J-327D01*
G03X712237Y527373I32J399D01*
G02X712590Y528673I1363J328D01*
G03Y529227I-288J277D01*
G02Y531173I1010J973D01*
G03Y531727I-288J277D01*
G02X714573Y533710I1010J973D01*
G03X715127I277J288D01*
G02X717110Y531727I973J-1010D01*
G03Y531173I288J-277D01*
G02Y529227I-1010J-973D01*
G03Y528673I288J-277D01*
G02Y526727I-1010J-973D01*
G03Y526173I288J-277D01*
G02X716821Y523997I-1010J-973D01*
G03X716858Y523292I206J-343D01*
G37*
G36*
G01X-1302Y523348D02*
G02X-3807Y523740I-1128J992D01*
G03X-4508Y523800I-367J-159D01*
G02X-4411Y525167I-1172J770D01*
G03X-3709Y525128I362J171D01*
G02X-1310Y525340I1279J-788D01*
G03X-725Y525328I298J267D01*
G02X-717Y523365I1005J-977D01*
G03X-1302Y523348I-285J-281D01*
G37*
G36*
G01X1410106Y527885D02*
G02X1408748Y528920I-1353J-367D01*
G03X1409133Y529425I-1J400D01*
G02X1410491Y528390I1353J367D01*
G03X1410106Y527885I1J-400D01*
G37*
G36*
G01X652335Y529277D02*
G02X649999Y531165I-1185J923D01*
G03X649988Y531690I-307J256D01*
G02X652296Y533609I1112J1010D01*
G03X652948Y533630I319J242D01*
G02X655107Y533997I1252J-830D01*
G03X655748Y534313I241J319D01*
G02X658237Y535432I1502J-13D01*
G03X658763I263J302D01*
G02X660673Y533115I987J-1132D01*
G03Y532485I246J-315D01*
G02X658763Y530168I-923J-1185D01*
G03X658237I-263J-302D01*
G02X656278Y530155I-987J1132D01*
G03X655626Y529923I-259J-305D01*
G02X652965Y529277I-1476J277D01*
G03X652335I-315J-246D01*
G37*
G36*
G01X20111Y531329D02*
G02X17752Y532685I-1011J971D01*
G03X17319Y533192I-385J110D01*
G02X16007Y535670I-180J1491D01*
G03Y536196I-302J263D01*
G02X15650Y537378I1132J987D01*
G03X15469Y537604I-198J27D01*
G02X15357Y537618I130J1496D01*
G03X15126Y537393I-33J-197D01*
G02X14771Y536196I-1487J-210D01*
G03Y535670I302J-263D01*
G02X12507I-1132J-987D01*
G03Y536196I-302J263D01*
G02X13686Y538684I1132J987D01*
G03X14098Y539087I12J400D01*
G02X15294Y540571I1502J13D01*
G03X15610Y541012I-81J392D01*
G02X15615Y541428I1490J190D01*
G03X15342Y541870I-395J61D01*
G02Y544730I458J1430D01*
G03X15615Y545172I-122J381D01*
G02Y545628I1485J228D01*
G03X15342Y546070I-395J61D01*
G02X15432Y548956I458J1430D01*
G03X15577Y549198I-49J194D01*
G02X15558Y549830I1458J360D01*
G03X15295Y550281I-393J73D01*
G02X15504Y553175I492J1419D01*
G03X15662Y553408I-38J196D01*
G02X17422Y552208I1477J275D01*
G03X17264Y551975I38J-196D01*
G02Y551428I-1477J-273D01*
G03X17527Y550977I393J-73D01*
G02X17403Y548102I-492J-1419D01*
G03X17258Y547860I49J-194D01*
G02X17285Y547272I-1458J-362D01*
G03X17558Y546830I395J-61D01*
G02Y543970I-458J-1430D01*
G03X17285Y543528I122J-381D01*
G02Y543072I-1485J-228D01*
G03X17558Y542630I395J-61D01*
G02X17406Y539729I-458J-1430D01*
G03X17090Y539288I81J-392D01*
G02X17101Y539061I-1490J-186D01*
G03X17425Y538657I400J-11D01*
G02X18271Y536196I-286J-1474D01*
G03Y535670I302J-263D01*
G02X18568Y534219I-1132J-988D01*
G03X18982Y533697I380J-124D01*
G02X20111Y533271I118J-1397D01*
G03X20689I289J277D01*
G02Y531329I1011J-971D01*
G03X20111I-289J-277D01*
G37*
G36*
G01X1844524Y534393D02*
G02X1843911Y533045I883J-1215D01*
G03X1843288Y533340I-398J-36D01*
G02X1843892Y534669I-788J1160D01*
G03X1844524Y534393I397J48D01*
G37*
G36*
G01X42873Y534083D02*
G02X41481Y535202I-1373J-283D01*
G03X41868Y535682I-5J400D01*
G02X42447Y537121I1373J283D01*
G03X42506Y537731I-226J330D01*
G02X44379Y539810I999J983D01*
G03X45022Y540049I250J312D01*
G02X45526Y538694I1378J-259D01*
G03X44883Y538455I-250J-312D01*
G02X44299Y537558I-1378J259D01*
G03X44240Y536948I226J-330D01*
G02X44402Y536751I-997J-985D01*
G03X45103Y536823I331J224D01*
G02X45239Y535504I1297J-533D01*
G03X44538Y535432I-331J-224D01*
G02X43260Y534563I-1297J533D01*
G03X42873Y534083I5J-400D01*
G37*
G36*
G01X1835767Y535757D02*
G02Y534043I1233J-857D01*
G03X1835119Y534055I-328J-229D01*
G02Y535745I-1119J845D01*
G03X1835767Y535757I320J241D01*
G37*
G36*
G01X1385303Y534550D02*
G02X1383533Y536707I-993J990D01*
G03Y537373I-222J333D01*
G02Y539707I777J1167D01*
G03Y540373I-222J333D01*
G02X1382961Y541923I777J1167D01*
G03X1382522Y542429I-384J110D01*
G02X1383233Y544892I-191J1389D01*
G03X1383833Y544991I258J306D01*
G02X1386145Y545120I1200J-724D01*
G03X1386783Y545124I317J244D01*
G02X1388200Y542915I1124J-838D01*
G03X1387954Y542296I83J-391D01*
G02X1387577Y540333I-1154J-796D01*
G03Y539667I222J-333D01*
G02X1387632Y537372I-777J-1167D01*
G03Y536728I238J-322D01*
G02X1385856Y534564I-832J-1128D01*
G03X1385303Y534550I-269J-296D01*
G37*
G36*
G01X1942833Y537022D02*
G02X1941904Y535571I467J-1322D01*
G03X1941357Y535905I-398J-37D01*
G02X1942300Y537378I-557J1395D01*
G03X1942833Y537022I399J21D01*
G37*
G36*
G01X1440629Y538649D02*
G02X1439047Y538669I-807J-1267D01*
G03X1439067Y539341I-206J342D01*
G02X1438516Y540891I794J1155D01*
G03X1438272Y541378I-384J112D01*
G02X1437814Y543919I527J1407D01*
G03X1437883Y544447I-262J303D01*
G02X1440108Y544160I1240J847D01*
G03X1440039Y543632I262J-303D01*
G02X1440213Y542280I-1240J-847D01*
G03X1440428Y541779I377J-135D01*
G02X1440625Y539322I-567J-1282D01*
G03X1440629Y538649I218J-335D01*
G37*
G36*
G01X1872229Y542494D02*
G02X1872128Y541122I1281J-784D01*
G03X1871425Y541184I-368J-156D01*
G02X1871524Y542535I-1175J765D01*
G03X1872229Y542494I363J167D01*
G37*
G36*
G01X1915761Y545974D02*
G02X1913976Y546150I-1011J-1111D01*
G03X1914039Y546789I-206J343D01*
G02X1915824Y546613I1011J1111D01*
G03X1915761Y545974I206J-343D01*
G37*
G36*
G01X1811291Y544448D02*
G02X1811069Y546068I-1239J655D01*
G03X1811713Y546156I290J275D01*
G02X1811935Y544536I1239J-655D01*
G03X1811291Y544448I-290J-275D01*
G37*
G36*
G01X1900099Y546084D02*
G02X1898351Y546667I-1249J-834D01*
G03X1898551Y547266I-133J377D01*
G02X1898517Y547319I1247J837D01*
G03X1897991Y547466I-342J-208D01*
G02X1898583Y549581I-691J1334D01*
G03X1899109Y549434I342J208D01*
G02X1900299Y546683I691J-1334D01*
G03X1900099Y546084I133J-377D01*
G37*
G36*
G01X1849886Y546497D02*
G02X1847914I-986J-997D01*
G03X1847900Y547080I-281J285D01*
G02X1848050Y549438I1000J1120D01*
G03X1848029Y550111I-227J330D01*
G02X1849650Y550162I771J1289D01*
G03X1849671Y549489I227J-330D01*
G02X1850285Y548780I-772J-1289D01*
G03X1850990Y548717I369J155D01*
G02X1850865Y547320I1260J-817D01*
G03X1850160Y547383I-369J-155D01*
G02X1849900Y547080I-1260J818D01*
G03X1849886Y546497I267J-298D01*
G37*
G36*
G01X1699091Y545127D02*
G02X1698427Y547032I-1252J632D01*
G03X1698962Y547235I168J363D01*
G02X1700348Y548144I1386J-602D01*
G01X1705348D01*
G02X1706227Y547863I1J-1511D01*
G03X1706832Y548044I232J325D01*
G02X1707378Y546361I1308J-506D01*
G03X1706781Y546153I-218J-335D01*
G02X1705348Y545122I-1433J480D01*
G01X1700348D01*
G02X1699636Y545300I0J1511D01*
G03X1699091Y545127I-188J-353D01*
G37*
G36*
G01X1830196Y546366D02*
G02X1829424Y547756I-1396J134D01*
G03X1830001Y548090I178J358D01*
G02X1830784Y546679I1499J-91D01*
G03X1830196Y546366I-190J-351D01*
G37*
G36*
G01X1958308Y548314D02*
G02X1957619Y547089I812J-1263D01*
G03X1957003Y547436I-400J10D01*
G02X1957692Y548661I-812J1263D01*
G03X1958308Y548314I400J-10D01*
G37*
G36*
G01X1363515Y546822D02*
G02X1362082Y549388I-987J1132D01*
G03X1362319Y549952I-119J382D01*
G02X1364693Y551426I1249J637D01*
G03X1365334I320J239D01*
G02X1366668Y549203I1125J-837D01*
G03X1366370Y548628I60J-396D01*
G02X1364041Y546822I-1342J-674D01*
G03X1363515I-263J-302D01*
G37*
G36*
G01X1857222Y548299D02*
G02X1855414Y549464I-1472J-299D01*
G03X1855720Y549910I-90J390D01*
G02X1856137Y551119I1388J198D01*
G03Y551697I-277J289D01*
G02X1856026Y551817I972J1010D01*
G03X1855711Y551809I-154J-127D01*
G02X1853025Y552948I-1203J899D01*
G03X1852582Y553409I-395J64D01*
G02X1853883Y554660I-182J1491D01*
G03X1854326Y554199I395J-64D01*
G02X1855591Y553749I182J-1491D01*
G03X1856152Y553733I289J277D01*
G02X1858064I956J-1025D01*
G03X1858625Y553749I272J293D01*
G02Y551667I1083J-1041D01*
G03X1858064Y551683I-289J-277D01*
G02X1857927Y551570I-959J1023D01*
G03Y551246I117J-162D01*
G02X1857502Y548762I-819J-1138D01*
G03X1857222Y548299I112J-384D01*
G37*
G36*
G01X1739196Y549377D02*
G02X1737135Y549281I-980J-1138D01*
G03X1737108Y549862I-288J278D01*
G02X1737496Y552380I980J1138D01*
G03X1737582Y553065I-158J368D01*
G02X1739090Y552875I916J1190D01*
G03X1739004Y552190I158J-368D01*
G02X1739169Y549958I-916J-1190D01*
G03X1739196Y549377I288J-278D01*
G37*
G36*
G01X1807341Y550014D02*
G02X1806148Y550601I-1141J-814D01*
G03X1806459Y551233I-15J400D01*
G02X1807652Y550646I1141J814D01*
G03X1807341Y550014I15J-400D01*
G37*
G36*
G01X1836990Y550812D02*
G02X1836640Y549062I1010J-1112D01*
G03X1836010Y549188I-362J-170D01*
G02X1836360Y550938I-1010J1112D01*
G03X1836990Y550812I362J170D01*
G37*
G36*
G01X1816995Y551606D02*
G02X1815565I-715J-1206D01*
G03Y552294I-204J344D01*
G02X1816995I715J1206D01*
G03Y551606I204J-344D01*
G37*
G36*
G01X46588Y555920D02*
G02X45172I-708J-1210D01*
G03Y556610I-203J345D01*
G02X46588I708J1210D01*
G03Y555920I203J-345D01*
G37*
G36*
G01X1913049Y556801D02*
G02X1912340Y555147I751J-1301D01*
G03X1911751Y555399I-389J-94D01*
G02X1909877Y555702I-751J1301D01*
G03X1909317Y555739I-299J-266D01*
G02X1909395Y557787I-917J1060D01*
G03X1909957Y557781I284J282D01*
G02X1912460Y557053I1043J-1081D01*
G03X1913049Y556801I389J94D01*
G37*
G36*
G01X1733857Y558233D02*
G02X1732143I-857J-1233D01*
G03X1732155Y558881I-229J328D01*
G02X1733845I845J1119D01*
G03X1733857Y558233I241J-320D01*
G37*
G36*
G01X1405492Y556370D02*
G02X1403370Y556577I-973J1010D01*
G03X1402761Y556633I-328J-229D01*
G02X1400455Y558098I-984J999D01*
G03X1400107Y558630I-377J133D01*
G02X1401611Y559571I109J1498D01*
G03X1401937Y559025I371J-149D01*
G02X1402926Y558435I-160J-1393D01*
G03X1403535Y558379I328J229D01*
G02X1403687Y558508I981J-1002D01*
G03Y559152I-238J322D01*
G02X1405455Y561323I832J1128D01*
G03X1406005Y561337I268J298D01*
G02X1408043Y561272I988J-994D01*
G03X1408643I300J265D01*
G02X1410627Y561389I1050J-929D01*
G03X1411159I266J298D01*
G02X1412862Y559170I934J-1046D01*
G03X1412845Y558513I219J-334D01*
G02X1411046Y556370I-827J-1132D01*
G03X1410492I-277J-288D01*
G02X1408546I-973J1010D01*
G03X1407992I-277J-288D01*
G02X1406046I-973J1010D01*
G03X1405492I-277J-288D01*
G37*
G36*
G01X1361720Y560797D02*
G02X1360474Y560236I-120J-1397D01*
G03X1360176Y560873I-321J238D01*
G02X1359896Y560916I87J1500D01*
G03X1359672Y560627I-48J-194D01*
G02X1357314Y559122I-1232J-669D01*
G03X1356673I-321J-239D01*
G02Y560796I-1125J837D01*
G03X1357314I320J239D01*
G02X1358456Y561361I1125J-837D01*
G03X1358839Y561890I4J400D01*
G02X1361440Y561443I1422J483D01*
G03X1361720Y560797I314J-247D01*
G37*
G36*
G01X1377086Y560726D02*
G02X1374974Y560635I-1016J-966D01*
G03X1374935Y561176I-313J249D01*
G02X1377398Y562710I1026J1097D01*
G03X1378051Y562532I383J117D01*
G02X1377603Y561386I949J-1032D01*
G03X1377234Y561476I-199J-16D01*
G02X1377078Y561269I-1273J797D01*
G03X1377086Y560726I298J-267D01*
G37*
G36*
G01X1419845Y562207D02*
G02X1417190Y561738I-1443J417D01*
G03X1416596Y561796I-323J-236D01*
G02X1416794Y563790I-1014J1108D01*
G03X1417388Y563732I323J236D01*
G02X1419453Y563697I1014J-1108D01*
G03X1420117Y563872I280J286D01*
G02X1420509Y562382I1443J-417D01*
G03X1419845Y562207I-280J-286D01*
G37*
G36*
G01X1781692Y566333D02*
G02X1779913Y566036I-692J-1333D01*
G03X1779808Y566667I-290J276D01*
G02X1779449Y569073I692J1333D01*
G03Y569645I-280J286D01*
G02X1781551I1051J1073D01*
G03Y569073I280J-286D01*
G02X1781587Y566964I-1051J-1073D01*
G03X1781692Y566333I290J-276D01*
G37*
G36*
G01X1361953Y567101D02*
G02X1360500Y565516I47J-1501D01*
G03X1360132Y565892I-399J-23D01*
G02X1360380Y568886I115J1498D01*
G03X1360598Y569087I18J199D01*
G02X1360601Y569189I1502J7D01*
G03X1360413Y569401I-200J12D01*
G02X1360333Y572393I87J1499D01*
G03X1360509Y572616I-22J199D01*
G02Y572984I1491J184D01*
G03X1360333Y573207I-198J24D01*
G02X1360187Y576169I167J1493D01*
G03X1360502Y576590I-84J391D01*
G02X1360514Y576918I1498J109D01*
G03X1360148Y577375I-396J58D01*
G02X1359129Y579860I113J1498D01*
G03Y580386I-302J263D01*
G02X1360286Y582875I1132J987D01*
G03X1360656Y583444I7J400D01*
G02X1360916Y585010I1270J594D01*
G03Y585564I-288J277D01*
G02X1360766Y585750I1012J970D01*
G03X1360413Y585708I-166J-112D01*
G02X1357733Y586510I-1313J492D01*
G03X1357355Y586999I-390J89D01*
G02X1356587Y589542I45J1401D01*
G03X1356659Y590127I-232J326D01*
G02X1358699Y592047I1067J910D01*
G03X1359253I277J288D01*
G02X1359315Y592102I961J-1021D01*
G03X1359311Y592409I-130J152D01*
G02X1359761Y594989I950J1164D01*
G03X1360021Y595437I-134J377D01*
G02X1360015Y595928I1479J264D01*
G03X1359742Y596370I-395J61D01*
G02X1359818Y599253I458J1430D01*
G03X1360112Y599694I-102J387D01*
G02Y600106I1488J206D01*
G03X1359818Y600547I-396J54D01*
G02X1359755Y603435I382J1453D01*
G03X1360029Y603897I-118J382D01*
G02X1360015Y604428I1471J304D01*
G03X1359742Y604870I-395J61D01*
G02X1360041Y607794I458J1430D01*
G03X1360398Y608193I-43J398D01*
G02Y608201I1502J4D01*
G03X1360019Y608600I-400J0D01*
G02X1359026Y611151I81J1500D01*
G03X1359060Y611671I-286J280D01*
G02X1361335Y611522I1201J902D01*
G03X1361301Y611002I286J-280D01*
G02X1361602Y610099I-1201J-902D01*
G03X1361981Y609700I400J0D01*
G02X1362049Y609695I-76J-1500D01*
G03X1362267Y609915I19J199D01*
G02X1362629Y611060I1494J157D01*
G03Y611586I-302J263D01*
G02X1364893I1132J987D01*
G03Y611060I302J-263D01*
G02X1363793Y608571I-1132J-987D01*
G03X1363402Y608177I9J-400D01*
G02X1362059Y606706I-1502J23D01*
G03X1361702Y606307I43J-398D01*
G02X1361685Y606072I-1502J-9D01*
G03X1361958Y605630I395J-61D01*
G02X1361945Y602765I-458J-1430D01*
G03X1361671Y602303I118J-382D01*
G02X1361688Y601794I-1471J-304D01*
G03X1361982Y601353I396J-54D01*
G02Y598447I-382J-1453D01*
G03X1361688Y598006I102J-387D01*
G02X1361685Y597572I-1488J-207D01*
G03X1361958Y597130I395J-61D01*
G02X1362000Y594284I-458J-1430D01*
G03X1361740Y593836I134J-377D01*
G02X1361311Y592499I-1479J-263D01*
G03X1361288Y591952I280J-286D01*
G02X1361130Y589966I-1062J-915D01*
G03X1361102Y589380I258J-306D01*
G02X1361501Y588352I-1002J-980D01*
G03X1361906Y587939I400J-13D01*
G02X1362858Y587584I19J-1402D01*
G03X1363413Y587606I266J299D01*
G02X1365436Y585664I1013J-969D01*
G03Y585110I288J-277D01*
G02X1365077Y582895I-1010J-973D01*
G03X1364947Y582295I185J-354D01*
G02X1362424Y582058I-1186J-922D01*
G03X1362037Y582639I-356J182D01*
G02X1361950Y582635I-108J1398D01*
G03X1361600Y582054I6J-400D01*
G02X1361393Y580386I-1339J-681D01*
G03Y579860I302J-263D01*
G02X1361747Y578655I-1132J-987D01*
G03X1362113Y578198I396J-58D01*
G02X1362313Y575231I-113J-1498D01*
G03X1361998Y574810I84J-391D01*
G02X1361991Y574516I-1498J-111D01*
G03X1362167Y574293I198J-24D01*
G02Y571307I-167J-1493D01*
G03X1361991Y571084I22J-199D01*
G02X1361999Y570811I-1491J-180D01*
G03X1362187Y570599I200J-12D01*
G02X1361967Y567604I-87J-1499D01*
G03X1361749Y567403I-18J-199D01*
G02X1361747Y567312I-1502J-13D01*
G03X1361953Y567101I200J-11D01*
G37*
G36*
G01X1451897Y571203D02*
G02X1450403I-747J-1303D01*
G03Y571897I-199J347D01*
G02X1451897I747J1303D01*
G03Y571203I199J-347D01*
G37*
G36*
G01X1467688Y571033D02*
G02X1467410Y569355I961J-1021D01*
G03X1466772Y569448I-353J-188D01*
G02X1467054Y571151I-1072J1052D01*
G03X1467688Y571033I360J173D01*
G37*
G36*
G01X1418208Y569756D02*
G02X1416196Y569715I-1026J955D01*
G03X1415654Y569735I-282J-284D01*
G02X1413758Y571797I-910J1066D01*
G03X1413757Y572366I-282J284D01*
G02X1415676Y574409I986J996D01*
G03X1416233Y574433I266J299D01*
G02X1416588Y574705I1019J-963D01*
G03X1416596Y575405I-190J352D01*
G02X1416340Y575591I691J1220D01*
G03X1415799I-270J-295D01*
G02X1414169Y577849I-948J1033D01*
G03X1414158Y578554I-195J350D01*
G02X1415482Y578575I642J1246D01*
G03X1415493Y577870I195J-350D01*
G02X1415799Y577657I-641J-1247D01*
G03X1416340I271J295D01*
G02X1418229Y577663I948J-1033D01*
G03X1418789Y577685I269J296D01*
G02X1420825Y577689I1020J-962D01*
G03X1421424Y577711I290J276D01*
G02X1421715Y577979I1086J-887D01*
G03X1421713Y578640I-226J330D01*
G02X1423294Y578644I788J1160D01*
G03X1423296Y577983I226J-330D01*
G02X1423286Y575656I-787J-1160D01*
G03Y574990I222J-333D01*
G02Y572656I-777J-1167D01*
G03Y571990I222J-333D01*
G02X1421493Y569857I-777J-1167D01*
G03X1420894Y569835I-290J-276D01*
G02X1418791Y569759I-1085J888D01*
G03X1418208Y569756I-290J-276D01*
G37*
G36*
G01X1924325Y573500D02*
G02X1922875I-725J-1200D01*
G03X1922864Y574191I-207J342D01*
G02X1924336I736J1309D01*
G03X1924325Y573500I196J-349D01*
G37*
G36*
G01X1475833Y571394D02*
G02Y573236I-1057J921D01*
G03X1476436I301J263D01*
G02X1478427Y573361I1057J-921D01*
G03X1478959I266J298D01*
G02X1480827I934J-1046D01*
G03X1481359I266J298D01*
G02X1483227I934J-1046D01*
G03X1483759I266J298D01*
G02X1485627I934J-1046D01*
G03X1486159I266J298D01*
G02X1488027I934J-1046D01*
G03X1488559I266J298D01*
G02X1489914Y573652I933J-1046D01*
G03X1490421Y573931I120J382D01*
G02X1492655Y574663I1355J-360D01*
G03X1493243Y574758I251J311D01*
G02X1495386Y575018I1179J-758D01*
G03X1495936I275J290D01*
G02X1498067Y574777I964J-1018D01*
G03X1498733I333J222D01*
G02Y573223I1167J-777D01*
G03X1498067I-333J-222D01*
G02X1495936Y572982I-1167J777D01*
G03X1495386I-275J-290D01*
G02X1493543Y572908I-964J1018D01*
G03X1492955Y572813I-251J-311D01*
G02X1491355Y572234I-1179J758D01*
G03X1490848Y571955I-120J-382D01*
G02X1488559Y571269I-1355J360D01*
G03X1488027I-266J-298D01*
G02X1486159I-934J1046D01*
G03X1485627I-266J-298D01*
G02X1483759I-934J1046D01*
G03X1483227I-266J-298D01*
G02X1481359I-934J1046D01*
G03X1480827I-266J-298D01*
G02X1478959I-934J1046D01*
G03X1478427I-266J-298D01*
G02X1476436Y571394I-934J1046D01*
G03X1475833I-302J-263D01*
G37*
G36*
G01X1772218Y574065D02*
G02X1769297Y574449I-1499J-100D01*
G03X1768937Y574977I-378J129D01*
G02X1770244Y575732I62J1401D01*
G03X1770457Y575443I178J-92D01*
G02X1770688Y575466I264J-1479D01*
G03X1771079Y575892I-8J400D01*
G02X1772609Y574491I1499J101D01*
G03X1772218Y574065I8J-400D01*
G37*
G36*
G01X1745015Y574997D02*
G02X1744745Y573376I985J-997D01*
G03X1744095Y573472I-358J-178D01*
G02X1744369Y575118I-1095J1028D01*
G03X1745015Y574997I365J164D01*
G37*
G36*
G01X1858246Y575380D02*
G02X1856692Y574505I-246J-1380D01*
G03X1856372Y575045I-373J144D01*
G02X1857950Y575934I201J1489D01*
G03X1858246Y575380I367J-160D01*
G37*
G36*
G01X1764655Y576057D02*
G02X1763809Y574521I645J-1356D01*
G03X1763240Y574834I-397J-48D01*
G02X1764086Y576370I-645J1356D01*
G03X1764655Y576057I397J48D01*
G37*
G36*
G01X1653528Y576553D02*
G02X1651596Y576672I-1028J-953D01*
G03X1651617Y577265I-258J306D01*
G02X1651158Y578350I1053J1085D01*
G01Y581915D01*
G03X1650567Y582267I-400J0D01*
G02X1651255Y583859I-667J1233D01*
G03X1651857Y583625I387J103D01*
G02X1654180Y582360I812J-1275D01*
G01Y578265D01*
X1654171Y578181D01*
G02X1653580Y577144I-1502J169D01*
G03X1653528Y576553I241J-319D01*
G37*
G36*
G01X1935546Y577033D02*
G02X1935263Y578761I-1346J667D01*
G03X1935904Y578867I282J283D01*
G02X1936187Y577139I1346J-667D01*
G03X1935546Y577033I-282J-283D01*
G37*
G36*
G01X1604332Y577315D02*
G02X1603869Y579205I-1212J705D01*
G03X1604482Y579543I213J338D01*
G01Y581436D01*
G03X1603856Y581766I-400J0D01*
G02X1604272Y583625I-796J1154D01*
G03X1604906Y583549I346J201D01*
G02X1607506Y582510I1088J-1049D01*
G01Y578415D01*
X1607496Y578331D01*
G02X1604953Y577404I-1502J169D01*
G03X1604332Y577315I-275J-290D01*
G37*
G36*
G01X1631370Y580391D02*
G02X1626947Y579005I-2331J-311D01*
G01X1626946Y579006D01*
X1625498Y581710D01*
G03X1624810Y581740I-353J-188D01*
G02X1623322Y584828I-1676J1095D01*
G03X1623756Y585279I37J398D01*
G02X1628179Y586665I2331J311D01*
G01X1628180Y586664D01*
X1629628Y583960D01*
G03X1630316Y583930I353J188D01*
G02X1632180Y584828I1676J-1095D01*
G03X1632614Y585279I37J398D01*
G02X1637045Y586650I2331J312D01*
G01X1637046Y586648D01*
X1638486Y583960D01*
G03X1639174Y583930I353J188D01*
G02X1641341Y584776I1676J-1095D01*
G03X1641833Y585235I98J388D01*
G02X1643312Y583650I1970J356D01*
G03X1642820Y583191I-98J-388D01*
G02X1640663Y580842I-1970J-356D01*
G03X1640229Y580391I-37J-398D01*
G02X1635798Y579020I-2331J-312D01*
G01X1635797Y579022D01*
X1634356Y581711D01*
G03X1633669Y581741I-352J-189D01*
G02X1631804Y580842I-1677J1094D01*
G03X1631370Y580391I-37J-398D01*
G37*
G36*
G01X1678614D02*
G02X1674191Y579005I-2331J-311D01*
G01X1674190Y579006D01*
X1672742Y581710D01*
G03X1672054Y581740I-353J-188D01*
G02X1670566Y584828I-1676J1095D01*
G03X1671000Y585279I37J398D01*
G02X1675423Y586665I2331J311D01*
G01X1675424Y586664D01*
X1676872Y583960D01*
G03X1677560Y583930I353J188D01*
G02X1679424Y584828I1676J-1095D01*
G03X1679858Y585279I37J398D01*
G02X1684289Y586650I2331J312D01*
G01X1684290Y586648D01*
X1685730Y583960D01*
G03X1686418Y583930I353J188D01*
G02X1688585Y584776I1676J-1095D01*
G03X1689077Y585235I98J388D01*
G02X1690556Y583650I1970J356D01*
G03X1690064Y583191I-98J-388D01*
G02X1687907Y580842I-1970J-356D01*
G03X1687473Y580391I-37J-398D01*
G02X1683042Y579020I-2331J-312D01*
G01X1683041Y579022D01*
X1681600Y581711D01*
G03X1680913Y581741I-352J-189D01*
G02X1679048Y580842I-1677J1094D01*
G03X1678614Y580391I-37J-398D01*
G37*
G36*
G01X1780383Y580715D02*
G02X1778538Y580654I-883J-1215D01*
G03X1778517Y581285I-256J307D01*
G02X1778400Y583621I883J1215D01*
G03X1778326Y584270I-266J298D01*
G02X1778155Y586619I674J1230D01*
G03X1778143Y587267I-241J320D01*
G02X1779857I857J1233D01*
G03X1779845Y586619I229J-328D01*
G02X1779972Y584490I-845J-1119D01*
G03X1780071Y583844I278J-288D01*
G02X1780362Y581346I-671J-1344D01*
G03X1780383Y580715I256J-307D01*
G37*
G36*
G01X1662170Y585272D02*
G02X1660696Y584651I-290J-1372D01*
G03X1660426Y585260I-337J215D01*
G02X1659168Y586750I253J1490D01*
G01Y590751D01*
G02X1660825Y592255I1512J-1D01*
G03X1661244Y592774I38J398D01*
G02X1662500Y591800I1336J426D01*
G03X1662101Y591265I-23J-399D01*
G02X1662192Y590760I-1421J-517D01*
G01Y586665D01*
X1662182Y586581D01*
G02X1661923Y585891I-1502J170D01*
G03X1662170Y585272I329J-227D01*
G37*
G36*
G01X1793376Y584614D02*
G02X1791922Y585280I-1207J-714D01*
G03X1792188Y585890I-70J394D01*
G02X1792039Y587212I1264J812D01*
G03X1791594Y587741I-376J135D01*
G02X1792682Y588687I-245J1381D01*
G03X1793144Y588171I380J-125D01*
G02X1793664Y585214I308J-1470D01*
G03X1793376Y584614I56J-396D01*
G37*
G36*
G01X1375668Y585155D02*
G02X1375520Y583756I1132J-827D01*
G03X1374832Y583829I-365J-163D01*
G02X1374980Y585228I-1132J827D01*
G03X1375668Y585155I365J163D01*
G37*
G36*
G01X1786488Y584117D02*
G02X1786266Y585432I-1438J433D01*
G03X1786969Y585541I324J235D01*
G02X1787188Y584246I1331J-441D01*
G03X1786488Y584117I-317J-244D01*
G37*
G36*
G01X1743226Y586649D02*
G02X1741043Y585112I-845J-1119D01*
G03X1740417Y585310I-382J-119D01*
G02X1738108Y587065I-917J1190D01*
G03X1737884Y587588I-370J151D01*
G02X1737800Y587624I549J1398D01*
G03X1737289Y587468I-169J-363D01*
G02X1736637Y589606I-1286J776D01*
G03X1737148Y589762I169J363D01*
G02X1737923Y590398I1286J-776D01*
G03X1738079Y591047I-136J376D01*
G02X1738612Y593461I1100J1023D01*
G03X1738842Y593955I-151J371D01*
G02X1738832Y594853I1428J465D01*
G03X1738609Y595335I-383J115D01*
G02X1740593Y596122I602J1376D01*
G03X1740717Y595853I184J-78D01*
G02X1740837Y595810I-446J-1434D01*
G03X1741111Y595979I75J185D01*
G02X1742226Y594496I1398J-110D01*
G03X1741751Y594170I-80J-392D01*
G02X1740837Y593028I-1481J249D01*
G03X1740607Y592534I151J-371D01*
G02X1740681Y592089I-1428J-466D01*
G03X1741068Y592022I200J3D01*
G02X1743226Y590411I1313J-492D01*
G03X1743238Y589763I241J-320D01*
G02Y587297I-857J-1233D01*
G03X1743226Y586649I229J-328D01*
G37*
G36*
G01X1920820Y587102D02*
G02X1920606Y585366I980J-1002D01*
G03X1919974Y585430I-340J-210D01*
G02X1920191Y587193I-1094J1030D01*
G03X1920820Y587102I349J195D01*
G37*
G36*
G01X1857888Y587748D02*
G02X1856564Y586690I112J-1498D01*
G03X1856152Y587206I-382J117D01*
G02X1857476Y588264I-112J1498D01*
G03X1857888Y587748I382J-117D01*
G37*
G36*
G01X1838036Y588140D02*
G02X1836821Y587185I188J-1490D01*
G03X1836410Y587726I-374J143D01*
G02X1837607Y588667I-129J1396D01*
G03X1838036Y588140I378J-130D01*
G37*
G36*
G01X1399147Y586309D02*
G02X1396604Y587353I-1167J777D01*
G03X1396076Y587805I-393J75D01*
G02X1392058Y590669I-1016J2825D01*
G02X1393362Y593106I443J1331D01*
G02X1397950Y591441I1698J-2476D01*
G02X1399282Y590629I60J-1401D01*
G03X1399942Y590528I363J168D01*
G02X1401990Y588613I1038J-942D01*
G03Y588059I288J-277D01*
G02X1399813Y586309I-1010J-972D01*
G03X1399147I-333J-222D01*
G37*
G36*
G01X1445522Y597099D02*
G02X1440657Y594929I-1868J-2350D01*
G02X1440504Y599499I1868J2350D01*
G02X1442867Y602884I2969J445D01*
G03X1443063Y603564I-81J392D01*
G02X1446382Y608462I2082J2163D01*
G02X1449308Y608716I1689J-2481D01*
G02X1452039Y608763I1411J-2649D01*
G02X1454688Y608849I1412J-2649D01*
G02X1458150Y608393I1412J-2649D01*
G02X1462577Y608033I2050J-2193D01*
G02X1463129Y605540I842J-1121D01*
G02X1459692Y603241I-2929J660D01*
G03X1459231Y602918I-68J-394D01*
G02X1455040Y600719I-2954J536D01*
G02X1450641Y603066I-1412J2649D01*
G02X1449483Y603332I80J3001D01*
G02X1446834Y603246I-1412J2649D01*
G02X1445751Y602787I-1690J2481D01*
G03X1445555Y602107I81J-392D01*
G02X1445494Y597724I-2082J-2163D01*
G02X1445522Y597099I-2969J-446D01*
G37*
G36*
G01X1824276Y594887D02*
G02X1823619Y593554I738J-1192D01*
G03X1823011Y593854I-398J-40D01*
G02X1821611Y593810I-738J1192D01*
G03X1821030Y593534I-189J-353D01*
G02X1820316Y595039I-1376J269D01*
G03X1820897Y595315I189J353D01*
G02X1823668Y595187I1376J-269D01*
G03X1824276Y594887I398J40D01*
G37*
G36*
G01X1764670Y598328D02*
G02X1764488Y600095I-1170J772D01*
G03X1765112Y600173I281J284D01*
G02X1765298Y598380I1288J-773D01*
G03X1764670Y598328I-294J-272D01*
G37*
G36*
G01X1539519Y600344D02*
G02X1539431Y601974I-1182J754D01*
G03X1540088Y602022I312J250D01*
G02X1540300Y602302I1295J-761D01*
G03X1538917Y603050I-1300J-752D01*
G02X1538496Y603424I-22J399D01*
G03X1537852Y605357I-3994J-257D01*
G03X1537920Y605944I-3931J753D01*
G03X1538053Y606144I-1180J929D01*
G02X1538744Y606157I349J-195D01*
G03X1540834Y605667I1285J778D01*
G02X1541444Y605273I214J-338D01*
G03X1541776Y603029I3963J-560D01*
G03X1541399Y602764I723J-1430D01*
G02X1540178Y600367I-15J-1502D01*
G03X1539519Y600344I-322J-238D01*
G37*
G36*
G01X1660485Y602506D02*
G02X1659876Y600839I715J-1206D01*
G03X1659262Y601030I-378J-131D01*
G02X1656858Y602250I-892J1220D01*
G01Y606251D01*
G02X1659241Y607484I1511J-1D01*
G03X1659856Y607698I231J327D01*
G02X1660485Y606094I1344J-398D01*
G03X1659880Y605750I-205J-344D01*
G01Y602850D01*
G03X1660485Y602506I400J0D01*
G37*
G36*
G01X1383077Y607519D02*
G02X1381627Y607689I-878J-1219D01*
G03X1381709Y608383I-152J370D01*
G02X1381461Y610598I877J1220D01*
G03X1381465Y611123I-299J265D01*
G02X1383730Y611106I1140J979D01*
G03X1383726Y610581I299J-265D01*
G02X1383159Y608213I-1140J-979D01*
G03X1383077Y607519I152J-370D01*
G37*
G36*
G01X1936346Y608546D02*
G02X1935381Y607402I424J-1336D01*
G03X1934852Y607834I-396J55D01*
G02X1935830Y608995I-502J1416D01*
G03X1936346Y608546I394J-68D01*
G37*
G36*
G01X1498208Y611341D02*
G02X1496845Y611026I-408J-1341D01*
G03X1496689Y611702I-272J293D01*
G02X1495870Y612364I407J1342D01*
G03X1495205Y612417I-350J-193D01*
G02X1493563Y611985I-1105J863D01*
G03X1493011Y611640I-153J-370D01*
G02X1490718Y613007I-1499J92D01*
G03X1490770Y613647I-212J339D01*
G02X1495193Y614158I1980J2256D01*
G02X1495327Y613959I-1092J-880D01*
G03X1495992Y613906I350J193D01*
G02X1498052Y612017I1105J-862D01*
G03X1498208Y611341I272J-293D01*
G37*
G36*
G01X1701203Y618481D02*
G02X1700252Y616202I4569J-3244D01*
G03X1699700Y616638I-394J69D01*
G02X1700504Y618566I-594J1379D01*
G03X1701203Y618481I372J146D01*
G37*
G36*
G01X1727086Y615676D02*
G02X1727063Y614062I1255J-825D01*
G03X1726388Y614071I-340J-210D01*
G02X1726411Y615685I-1255J825D01*
G03X1727086Y615676I340J210D01*
G37*
G36*
G01X1545453Y616069D02*
G02X1544319Y616875I-1403J-773D01*
G03X1544742Y617454I68J394D01*
G02X1545860Y616658I1334J690D01*
G03X1545453Y616069I-57J-396D01*
G37*
G36*
G01X1619461Y618783D02*
G02X1618281Y617791I239J-1483D01*
G03X1617839Y618317I-378J131D01*
G02X1619019Y619309I-239J1483D01*
G03X1619461Y618783I378J-131D01*
G37*
G36*
G01X1509670Y618966D02*
G02X1507346Y619092I-1120J844D01*
G03X1506708Y619159I-344J-204D01*
G02X1504673Y619135I-1029J952D01*
G03X1504080Y619114I-287J-279D01*
G02X1502035Y619009I-1072J904D01*
G03X1501466Y618995I-278J-288D01*
G02X1501418Y620965I-1021J961D01*
G03X1501987Y620979I278J288D01*
G02X1504014Y620994I1021J-961D01*
G03X1504607Y621015I287J279D01*
G02X1506883Y620829I1072J-904D01*
G03X1507521Y620762I344J204D01*
G02X1509495Y620845I1029J-952D01*
G03X1510084Y620900I269J296D01*
G02X1512238Y621003I1120J-844D01*
G03X1512792Y620968I295J270D01*
G02X1512666Y618953I908J-1068D01*
G03X1512112Y618988I-295J-270D01*
G02X1510259Y619021I-908J1068D01*
G03X1509670Y618966I-269J-296D01*
G37*
G36*
G01X1614293Y585452D02*
G02X1613628Y584236I737J-1193D01*
G03X1613080Y584600I-400J-7D01*
G02X1611008Y586004I-561J1404D01*
G01Y590005D01*
G02X1612097Y591455I1511J-1D01*
G03X1612371Y591947I-111J384D01*
G02X1614192Y591004I1350J378D01*
G03X1613948Y590497I134J-377D01*
G02X1614030Y590014I-1429J-491D01*
G01Y586004D01*
Y585919D01*
X1614021Y585835D01*
G02X1613992Y585667I-1501J173D01*
G03X1614293Y585452I195J-45D01*
G37*
G36*
G01X1464895Y358225D02*
G02X1462630Y358521I-1278J-966D01*
G03X1462730Y359037I-246J315D01*
G02X1462660Y359174I1212J705D01*
G03X1462306Y359195I-182J-81D01*
G02X1461266Y361446I-1290J770D01*
G03X1461725Y361916I66J394D01*
G02X1464518Y361479I1475J284D01*
G03X1464663Y360944I351J-192D01*
G02X1464932Y358749I-721J-1202D01*
G03X1464895Y358225I282J-283D01*
G37*
G36*
G01X1589306Y402686D02*
G02X1586471Y403249I-1338J682D01*
G01X1586456Y403434D01*
X1570268D01*
G02X1568582I-843J1120D01*
G01X1566547D01*
X1563444Y406537D01*
X1563378Y406546D01*
G02X1562187Y407737I197J1388D01*
G01X1562178Y407803D01*
X1561760Y408221D01*
G03X1561077Y407937I-283J-283D01*
G02X1559678Y409336I-1402J-3D01*
G03X1559962Y410019I1J400D01*
G01X1558211Y411770D01*
X1555626D01*
G03X1555226Y411357I0J-400D01*
G02X1552424I-1401J-43D01*
G03X1552024Y411770I-400J13D01*
G01X1551727D01*
G03X1551327Y411357I0J-400D01*
G02X1548525I-1401J-45D01*
G03X1548125Y411770I-400J13D01*
G01X1542250D01*
G03X1541906Y411165I0J-400D01*
G02X1541458Y409270I-1206J-715D01*
G03X1541341Y408712I216J-337D01*
G02X1539417Y409114I-1167J-778D01*
G03X1539534Y409672I-216J337D01*
G02X1539494Y411165I1166J778D01*
G03X1539150Y411770I-344J205D01*
G01X1537476D01*
X1533773Y408067D01*
X1533776Y407980D01*
G02X1532329Y406533I-1401J-46D01*
G01X1532242Y406536D01*
X1531431Y405724D01*
X1528154D01*
G03X1527792Y405154I0J-400D01*
G02X1525258I-1267J-600D01*
G03X1524896Y405724I-362J170D01*
G01X1524254D01*
G03X1523892Y405154I0J-400D01*
G02X1521358I-1267J-600D01*
G03X1520996Y405724I-362J170D01*
G01X1519868D01*
G02X1517532I-1168J776D01*
G01X1517027D01*
X1515026Y407725D01*
G03X1514346Y407489I-283J-283D01*
G02X1511886Y408561I-1392J164D01*
G03X1511752Y409182I-305J259D01*
G02X1511125Y409769I599J1268D01*
G03X1510425I-350J-194D01*
G02X1508024Y411213I-1225J681D01*
G03X1507688Y411830I-336J217D01*
G01X1501023D01*
G03X1500624Y411405I0J-400D01*
G02X1497826I-1399J-91D01*
G03X1497427Y411830I-399J25D01*
G01X1497123D01*
G03X1496724Y411405I0J-400D01*
G02X1493926I-1399J-91D01*
G03X1493527Y411830I-399J25D01*
G01X1493223D01*
G03X1492824Y411405I0J-400D01*
G02X1490026I-1399J-91D01*
G03X1489627Y411830I-399J25D01*
G01X1489323D01*
G03X1488924Y411405I0J-400D01*
G02X1486126I-1399J-91D01*
G03X1485727Y411830I-399J25D01*
G01X1483705D01*
G03X1483326Y411301I-1J-400D01*
G02X1480674I-1326J-455D01*
G03X1480295Y411830I-378J129D01*
G01X1476476D01*
X1472108Y416198D01*
X1454585D01*
X1443212Y427571D01*
Y427624D01*
X1442804Y428033D01*
Y475739D01*
G03X1442348Y476135I-400J0D01*
G02X1440940Y476721I-207J1488D01*
G03X1440330Y476757I-320J-240D01*
G02X1438238Y476824I-1016J966D01*
G03X1437608Y476804I-307J-256D01*
G02X1437588Y478604I-1212J887D01*
G03X1438218Y478598I317J243D01*
G02X1440396Y478615I1096J-875D01*
G03X1441006Y478607I308J254D01*
G02X1442348Y479111I1135J-984D01*
G03X1442804Y479507I56J396D01*
G01Y481107D01*
G03X1442285Y481489I-400J0D01*
G02X1440538Y482179I-443J1435D01*
G03X1440015Y482340I-347J-198D01*
G02X1438578Y482464I-615J1260D01*
G03X1437977Y482300I-234J-324D01*
G02X1437533Y484077I-1377J600D01*
G03X1438140Y484215I248J314D01*
G02X1440575Y484364I1260J-615D01*
G03X1441107Y484234I335J218D01*
G02X1442285Y484359I735J-1310D01*
G03X1442804Y484741I119J382D01*
G01Y487356D01*
G03X1442327Y487749I-400J0D01*
G02X1440884Y488265I-287J1474D01*
G03X1440302Y488302I-308J-255D01*
G02X1438263Y488427I-961J1021D01*
G03X1437637Y488414I-308J-255D01*
G02Y490232I-1196J909D01*
G03X1438263Y490219I318J242D01*
G02X1440375Y490270I1078J-896D01*
G03X1440958Y490264I294J271D01*
G02X1442327Y490697I1082J-1041D01*
G03X1442804Y491090I77J393D01*
G01Y492556D01*
G03X1442327Y492949I-400J0D01*
G02X1440837Y493525I-286J1474D01*
G03X1440269Y493600I-321J-239D01*
G02X1438425Y493692I-869J1100D01*
G03X1437810Y493619I-278J-288D01*
G02X1437632Y495456I-1269J804D01*
G03X1438250Y495502I290J275D01*
G02X1440478Y495596I1150J-802D01*
G03X1441050Y495551I308J256D01*
G02X1442327Y495897I991J-1128D01*
G03X1442804Y496290I77J393D01*
G01Y547117D01*
G03X1442161Y547436I-400J1D01*
G02Y549826I-909J1195D01*
G03X1442804Y550145I243J318D01*
G01Y559496D01*
G03X1442194Y559837I-400J0D01*
G02Y562397I-785J1280D01*
G03X1442804Y562738I210J341D01*
G01Y565274D01*
X1445420Y567890D01*
X1515438D01*
X1519782Y572234D01*
X1522183D01*
G03X1522457Y572926I0J400D01*
G02X1524063Y575193I959J1023D01*
G03X1524600Y575360I184J355D01*
G02X1524936Y575774I1237J-660D01*
G03X1524861Y576436I-257J306D01*
G02X1524490Y578657I639J1248D01*
G03Y579211I-288J277D01*
G02X1524486Y581153I1010J973D01*
G03Y581705I-289J276D01*
G02X1526514I1014J969D01*
G03Y581153I289J-276D01*
G02X1526861Y580520I-1015J-968D01*
G03X1527349Y580228I388J95D01*
G02X1528158Y580194I348J-1358D01*
G03X1528656Y580412I131J378D01*
G02X1528798Y580664I1286J-559D01*
G03X1528722Y581207I-326J231D01*
G02X1530689Y583183I878J1093D01*
G03X1531311I311J252D01*
G02X1533514Y581449I1089J-883D01*
G03X1533568Y580906I318J-243D01*
G02X1533500Y578744I-926J-1053D01*
G03X1533436Y578174I245J-316D01*
G02X1531372Y576282I-1082J-891D01*
G03X1530826Y576295I-280J-286D01*
G02X1530724Y576212I-935J1045D01*
G03X1530731Y575886I119J-161D01*
G02X1528570Y574444I-787J-1161D01*
G03X1528099Y574756I-392J-80D01*
G02X1527652Y574738I-279J1374D01*
G03X1527211Y574421I-49J-397D01*
G02X1525190Y573456I-1374J279D01*
G03X1524653Y573289I-184J-355D01*
G02X1524375Y572926I-1237J660D01*
G03X1524649Y572234I274J-292D01*
G01X1531783D01*
X1531816Y572202D01*
X1564214D01*
G03X1564597Y572717I0J400D01*
G02X1565035Y574191I1343J403D01*
G03X1565049Y574790I-258J306D01*
G02X1566905Y574749I951J1030D01*
G03X1566891Y574150I258J-306D01*
G02X1567283Y572717I-951J-1030D01*
G03X1567666Y572202I383J-115D01*
G01X1568631D01*
X1578218Y562614D01*
G03X1578900Y562920I283J283D01*
G02X1579323Y564006I1400J80D01*
G03X1579336Y564566I-279J287D01*
G02X1579357Y566504I1024J958D01*
G03X1579366Y567053I-286J279D01*
G02X1581403Y567020I1034J947D01*
G03X1581394Y566471I286J-279D01*
G02X1581337Y564518I-1034J-947D01*
G03X1581324Y563958I279J-287D01*
G02X1581310Y562027I-1024J-958D01*
G03Y561473I288J-277D01*
G02X1581420Y559656I-1010J-973D01*
G01X1581315Y559517D01*
X1591547Y549286D01*
G03X1592230Y549568I283J283D01*
G01Y568076D01*
X1593954Y569800D01*
X1600314D01*
Y571139D01*
G03X1599748Y571503I-400J0D01*
G02X1600313Y573592I-578J1277D01*
G03X1600887Y573510I326J232D01*
G02X1603336Y572335I938J-1185D01*
G01Y569800D01*
X1606022D01*
G02X1613571Y562759I5262J-1926D01*
G03X1613452Y562111I164J-365D01*
G01X1620169Y555395D01*
G03X1620804Y555489I283J283D01*
G02X1622929Y555911I1236J-662D01*
G03X1623582Y556220I253J309D01*
G01Y559200D01*
G02X1623787Y559959I1512J-1D01*
G03X1623630Y560512I-346J200D01*
G02X1625544Y561114I663J1235D01*
G03X1625732Y560570I357J-181D01*
G02X1626606Y559210I-638J-1371D01*
G01Y555115D01*
X1626596Y555031D01*
G02X1623934Y554231I-1502J169D01*
G03X1623275Y554163I-307J-257D01*
G02X1622094Y553426I-1235J664D01*
G03X1621902Y553226I8J-200D01*
G01Y526449D01*
G03X1622564Y526147I400J0D01*
G02Y523883I987J-1132D01*
G03X1621902Y523581I-262J-302D01*
G01Y513277D01*
X1624967Y510211D01*
G03X1625646Y510434I283J283D01*
G02X1626000Y511175I1386J-207D01*
G03X1626008Y511708I-294J271D01*
G02X1628100Y511677I1060J918D01*
G03X1628092Y511144I294J-271D01*
G02X1627240Y508840I-1060J-918D01*
G03X1627017Y508161I60J-396D01*
G01X1627662Y507517D01*
G03X1628330Y507693I283J283D01*
G02X1630177Y505846I1448J-399D01*
G03X1630001Y505178I107J-385D01*
G01X1633113Y502065D01*
Y474855D01*
G03X1633483Y474456I400J0D01*
G02X1634422Y471660I-124J-1597D01*
G03X1634365Y471124I265J-299D01*
G02X1633287Y468586I-1290J-950D01*
G01X1633114Y468563D01*
Y457110D01*
X1631479Y455476D01*
X1631543Y455347D01*
G02X1631343Y453701I-1343J-672D01*
G03X1631365Y453160I305J-259D01*
G02X1631393Y451070I-1065J-1059D01*
G03X1631388Y450527I291J-274D01*
G02X1629183Y450547I-1112J-1010D01*
G03X1629188Y451090I-291J274D01*
G02X1628811Y451899I1112J1010D01*
G03X1628132Y452129I-396J-53D01*
G01X1622260Y446256D01*
G03X1622254Y445979I141J-142D01*
G02X1620273Y443998I-1028J-953D01*
G01X1620132Y444129D01*
X1613147Y437145D01*
G03X1613168Y436560I283J-283D01*
G02X1613095Y434381I-918J-1060D01*
G03X1613107Y433733I241J-320D01*
G02X1613043Y431225I-857J-1233D01*
G03X1612977Y430597I211J-340D01*
G02X1611142Y430790I-1041J-1082D01*
G03X1611208Y431418I-211J340D01*
G02X1611393Y433733I1042J1082D01*
G03X1611405Y434381I-229J328D01*
G02X1611176Y434598I844J1120D01*
G03X1610587Y434624I-306J-257D01*
G01X1610230Y434267D01*
X1610239Y434237D01*
X1595116Y419113D01*
Y414398D01*
G03X1595302Y414199I200J0D01*
G02Y411201I-102J-1499D01*
G03X1595116Y411002I14J-199D01*
G01Y409800D01*
X1591352Y406036D01*
G03X1591413Y405421I283J-282D01*
G02X1589856Y402855I-832J-1251D01*
G03X1589306Y402686I-193J-350D01*
G37*
G36*
G01X34016Y453011D02*
G03X33427Y453045I-310J-253D01*
G02X33534Y454939I-977J1005D01*
G03X34123Y454905I310J253D01*
G02X34016Y453011I977J-1005D01*
G37*
G36*
G01X37670Y423903D02*
G03X37302Y423503I32J-399D01*
G02X35707Y424889I-1402J-3D01*
G03X36051Y425309I-55J396D01*
G02X37670Y423903I1499J91D01*
G37*
G36*
G01X47064Y415253D02*
G03X47079Y414659I275J-290D01*
G02X45121I-979J-1139D01*
G03X45136Y415253I-260J304D01*
G02X47064I964J1018D01*
G37*
G36*
G01X49372Y358259D02*
G03X48838Y358324I-303J-261D01*
G02X49108Y360531I-868J1226D01*
G03X49642Y360466I303J261D01*
G02X49372Y358259I868J-1226D01*
G37*
G36*
G01X57545Y298269D02*
G03X57566Y298815I-281J284D01*
G02X57690Y300912I1134J985D01*
G03X57669Y301521I-269J296D01*
G02X59610Y301588I931J1179D01*
G03X59631Y300979I269J-296D01*
G02X59755Y298731I-931J-1179D01*
G03X59734Y298185I281J-284D01*
G02X57545Y298269I-1134J-985D01*
G37*
G36*
G01X49683Y291311D02*
G03Y290689I252J-311D01*
G02X47917I-883J-1089D01*
G03Y291311I-252J311D01*
G02X49683I883J1089D01*
G37*
G36*
G01X49810Y284127D02*
G03Y283573I288J-277D01*
G02X47790I-1010J-973D01*
G03Y284127I-288J277D01*
G02X49810I1010J973D01*
G37*
G36*
G01X61013Y276868D02*
G03X60487I-263J-302D01*
G02Y279132I-987J1132D01*
G03X61013I263J302D01*
G02Y276868I987J-1132D01*
G37*
G36*
G01X51939Y237500D02*
G03Y238100I-265J300D01*
G02X53993Y240557I1061J1200D01*
G03X54513Y240577I248J314D01*
G02X56640Y240618I1087J-1177D01*
G03X57160I260J304D01*
G02X59261Y238200I1040J-1218D01*
G03Y237600I265J-300D01*
G02Y235200I-1061J-1200D01*
G03Y234600I265J-300D01*
G02Y232200I-1061J-1200D01*
G03Y231600I265J-300D01*
G02Y229200I-1061J-1200D01*
G03Y228600I265J-300D01*
G02X57160Y226182I-1061J-1200D01*
G03X56640I-260J-304D01*
G02X54607Y226143I-1040J1218D01*
G03X54087Y226123I-248J-314D01*
G02X51939Y228500I-1088J1176D01*
G03Y229100I-265J300D01*
G02Y231500I1061J1200D01*
G03Y232100I-265J300D01*
G02Y234500I1061J1200D01*
G03Y235100I-265J300D01*
G02Y237500I1061J1200D01*
G37*
G36*
G01X37173Y207328D02*
G03X37176Y206690I243J-318D01*
G02X33299Y206337I-1743J-2320D01*
G03X33044Y207006I-294J271D01*
G02X32000Y207539I156J1594D01*
G03X31400I-300J-265D01*
G02X29139Y209800I-1200J1061D01*
G03Y210400I-265J300D01*
G02X31400Y212661I1061J1200D01*
G03X32000I300J265D01*
G02X34400I1200J-1061D01*
G03X35000I300J265D01*
G02X37261Y210400I1200J-1061D01*
G03Y209800I265J-300D01*
G02X37173Y207328I-1061J-1200D01*
G37*
G36*
G01X52728Y153836D02*
G03X52970Y153321I375J-138D01*
G02X51141Y152346I-470J-1321D01*
G03X50754Y152844I-387J98D01*
G01X47309D01*
G02X46273Y153255I0J1511D01*
G03X45688Y153216I-274J-291D01*
G02X45504Y155172I-1088J884D01*
G03X46085Y155243I257J306D01*
G02X47309Y155868I1224J-886D01*
G01X51310D01*
G02X52820Y154366I-1J-1512D01*
G01Y154271D01*
X52811Y154187D01*
G02X52728Y153836I-1502J170D01*
G37*
G36*
G01X69199Y150437D02*
G02X68098Y149962I-1100J1036D01*
G01X63098D01*
G02X61925Y150520I0J1511D01*
G03X61323Y150541I-310J-252D01*
G02X61341Y152439I-1023J959D01*
G03X61944Y152449I297J268D01*
G02X63098Y152984I1154J-976D01*
G01X68099D01*
G02X69253Y152448I0J-1511D01*
G03X69834Y152416I306J258D01*
G02X69781Y150437I966J-1016D01*
G03X69199I-291J-274D01*
G37*
G36*
G01X77054Y151821D02*
G02X76864Y153278I-1394J559D01*
G03X77556Y153369I321J239D01*
G02X77746Y151912I1394J-559D01*
G03X77054Y151821I-321J-239D01*
G37*
G36*
G01X63478Y177656D02*
G02X62697Y176146I709J-1324D01*
G03X62111Y176449I-397J-50D01*
G02X60518Y178987I-708J1324D01*
G03X60497Y179648I-236J323D01*
G02X62253Y179673I859J1352D01*
G03X62251Y179012I224J-331D01*
G02X62892Y177959I-849J-1239D01*
G03X63478Y177656I397J50D01*
G37*
G36*
G01X31500Y219939D02*
G02X29239Y222200I-1200J1061D01*
G03Y222800I-265J300D01*
G02X28838Y224655I1061J1200D01*
G03X28363Y225203I-365J164D01*
G02X29873Y226240I-804J2789D01*
G03X30213Y225600I319J-241D01*
G02X31500Y225061I86J-1600D01*
G03X32100I300J265D01*
G02X32932Y225559I1200J-1061D01*
G03X33154Y226196I-92J389D01*
G02X37349Y225812I2279J1796D01*
G03X37350Y225210I264J-301D01*
G02X37361Y222800I-1050J-1210D01*
G03Y222200I265J-300D01*
G02X35100Y219939I-1061J-1200D01*
G03X34500I-300J-265D01*
G02X32100I-1200J1061D01*
G03X31500I-300J-265D01*
G37*
G36*
G01X54127Y275699D02*
G02X52673I-727J-1199D01*
G03Y276383I-207J342D01*
G02X54127I727J1199D01*
G03Y275699I207J-342D01*
G37*
G36*
G01X59921Y282125D02*
G02X59789Y284034I-1221J875D01*
G03X60404Y284076I290J275D01*
G02X60820Y284469I1221J-875D01*
G03X60878Y285100I-214J338D01*
G02X62705Y284932I1022J1100D01*
G03X62647Y284301I214J-338D01*
G02X60536Y282167I-1022J-1100D01*
G03X59921Y282125I-290J-275D01*
G37*
G36*
G01X49828Y342014D02*
G02X48428Y341938I-628J-1364D01*
G03X48389Y342645I-206J343D01*
G02X47885Y344996I628J1364D01*
G03Y345522I-302J263D01*
G02X47926Y347541I1132J987D01*
G03X47947Y348067I-290J275D01*
G02X47975Y349984I1170J942D01*
G03X47969Y350510I-304J260D01*
G02X48167Y352693I1122J999D01*
G03X48168Y353322I-247J315D01*
G02X50296Y355409I932J1178D01*
G03X50922Y355396I318J242D01*
G02Y353604I1078J-896D01*
G03X50296Y353591I-308J-255D01*
G02X50024Y353316I-1195J910D01*
G03X50023Y352687I247J-315D01*
G02X50377Y352285I-932J-1178D01*
G03X50968Y352178I343J206D01*
G02X50515Y350420I932J-1178D01*
G03X50185Y350479I-184J-78D01*
G02X50122Y350416I-1093J1030D01*
G03X50125Y350123I137J-145D01*
G02X50208Y347977I-1008J-1114D01*
G03X50187Y347451I290J-275D01*
G02X50320Y347257I-1169J-944D01*
G03X50945Y347169I347J199D01*
G02X50621Y345643I978J-1005D01*
G03X50269Y345679I-185J-74D01*
G02X50149Y345522I-1251J832D01*
G03Y344996I302J-263D01*
G02X49789Y342721I-1132J-987D01*
G03X49828Y342014I206J-343D01*
G37*
G36*
G01X52896Y415449D02*
G02X50750Y417487I-1251J832D01*
G03X50818Y418067I-238J322D01*
G02X50793Y418096I1049J930D01*
G03X50477Y418091I-156J-124D01*
G02X47754Y418995I-1211J904D01*
G01Y423996D01*
G02X50180Y425198I1511J-1D01*
G03X50748Y425284I242J318D01*
G02X51335Y423183I1142J-813D01*
G03X50776Y422815I-159J-367D01*
G01Y420625D01*
G03X51335Y420257I400J-1D01*
G02X52781Y417888I554J-1288D01*
G03X52743Y417306I254J-309D01*
G02X52777Y417268I-1102J-1020D01*
G03X53411Y417310I301J263D01*
G02X53530Y415491I1251J-832D01*
G03X52896Y415449I-301J-263D01*
G37*
G36*
G01X42458Y429594D02*
G02X41587Y430801I-1493J-160D01*
G03X42152Y431195I166J364D01*
G02X43010Y430006I1398J105D01*
G03X42458Y429594I-154J-369D01*
G37*
G36*
G01X25949Y439185D02*
G02X23188Y438517I-1502J169D01*
G03X22532Y438530I-333J-222D01*
G02X22283Y440441I-1135J824D01*
G03X22936Y440751I253J310D01*
G01Y442957D01*
G03X22283Y443267I-400J0D01*
G02X22532Y445178I-886J1087D01*
G03X23188Y445191I323J235D01*
G02X25958Y444364I1259J-837D01*
G01X25959Y439354D01*
X25958D01*
Y439269D01*
X25949Y439185D01*
G37*
G36*
G01X108274Y129541D02*
G02X110848Y129747I1348J-662D01*
G03X111488Y129729I327J231D01*
G02X111438Y127927I1176J-934D01*
G03X110798Y127945I-327J-231D01*
G02X108990Y127516I-1176J934D01*
G03X108474Y127350I-168J-363D01*
G02X107768Y129345I-1220J691D01*
G03X108274Y129541I147J372D01*
G37*
G36*
G01X119178Y129253D02*
G03X118662Y129248I-255J-308D01*
G02X116606Y131435I-980J1139D01*
G03X116602Y131718I-143J140D01*
G02X118591Y133964I1051J1073D01*
G03X119110Y133979I251J312D01*
G02X121272Y131905I1006J-1115D01*
G03X121276Y131388I307J-256D01*
G02X119178Y129253I-1138J-980D01*
G37*
G36*
G01X364495Y91490D02*
G03X363904I-295J-269D01*
G02Y93510I-1112J1010D01*
G03X364495I296J269D01*
G02Y91490I1112J-1010D01*
G37*
G36*
G01X596456Y89417D02*
G03X596470Y88834I281J-285D01*
G02X594470I-1000J-1120D01*
G03X594484Y89417I-267J298D01*
G02X596456I986J997D01*
G37*
G36*
G01X589763D02*
G03X589777Y88834I281J-285D01*
G02X587777I-1000J-1120D01*
G03X587791Y89417I-267J298D01*
G02X589763I986J997D01*
G37*
G36*
G01X572331D02*
G03X572345Y88834I281J-285D01*
G02X570345I-1000J-1120D01*
G03X570359Y89417I-267J298D01*
G02X572331I986J997D01*
G37*
G36*
G01X559645D02*
G03X559659Y88834I281J-285D01*
G02X557659I-1000J-1120D01*
G03X557673Y89417I-267J298D01*
G02X559645I986J997D01*
G37*
G36*
G01X552952D02*
G03X552966Y88834I281J-285D01*
G02X550966I-1000J-1120D01*
G03X550980Y89417I-267J298D01*
G02X552952I986J997D01*
G37*
G36*
G01X535520D02*
G03X535534Y88834I281J-285D01*
G02X533534I-1000J-1120D01*
G03X533548Y89417I-267J298D01*
G02X535520I986J997D01*
G37*
G36*
G01X529234Y89378D02*
G03X529261Y88817I298J-267D01*
G02X527180Y88777I-1020J-1103D01*
G03X527184Y89338I-283J283D01*
G02X529234Y89378I1006J976D01*
G37*
G36*
G01X522834Y89417D02*
G03X522848Y88834I281J-285D01*
G02X520848I-1000J-1120D01*
G03X520862Y89417I-267J298D01*
G02X522834I986J997D01*
G37*
G36*
G01X516141D02*
G03X516155Y88834I281J-285D01*
G02X514155I-1000J-1120D01*
G03X514169Y89417I-267J298D01*
G02X516141I986J997D01*
G37*
G36*
G01X498709D02*
G03X498723Y88834I281J-285D01*
G02X496723I-1000J-1120D01*
G03X496737Y89417I-267J298D01*
G02X498709I986J997D01*
G37*
G36*
G01X492423Y89378D02*
G03X492450Y88817I298J-267D01*
G02X490369Y88777I-1020J-1103D01*
G03X490373Y89338I-283J283D01*
G02X492423Y89378I1006J976D01*
G37*
G36*
G01X486023Y89417D02*
G03X486037Y88834I281J-285D01*
G02X484037I-1000J-1120D01*
G03X484051Y89417I-267J298D01*
G02X486023I986J997D01*
G37*
G36*
G01X479330D02*
G03X479344Y88834I281J-285D01*
G02X477344I-1000J-1120D01*
G03X477358Y89417I-267J298D01*
G02X479330I986J997D01*
G37*
G36*
G01X461937Y89358D02*
G03X461953Y88797I293J-272D01*
G02X459871I-1041J-1083D01*
G03X459887Y89358I-277J289D01*
G02X461937I1025J956D01*
G37*
G36*
G01X455612Y89378D02*
G03X455639Y88817I298J-267D01*
G02X453558Y88777I-1020J-1103D01*
G03X453562Y89338I-283J283D01*
G02X455612Y89378I1006J976D01*
G37*
G36*
G01X305282Y89435D02*
G03X305307Y88853I286J-279D01*
G02X303307Y88816I-979J-1139D01*
G03X303311Y89399I-272J293D01*
G02X305282Y89435I967J1015D01*
G37*
G36*
G01X298621Y89417D02*
G03X298635Y88834I281J-285D01*
G02X296635I-1000J-1120D01*
G03X296649Y89417I-267J298D01*
G02X298621I986J997D01*
G37*
G36*
G01X281189D02*
G03X281203Y88834I281J-285D01*
G02X279203I-1000J-1120D01*
G03X279217Y89417I-267J298D01*
G02X281189I986J997D01*
G37*
G36*
G01X274903Y89378D02*
G03X274930Y88817I298J-267D01*
G02X272849Y88777I-1020J-1103D01*
G03X272853Y89338I-283J283D01*
G02X274903Y89378I1006J976D01*
G37*
G36*
G01X268503Y89417D02*
G03X268517Y88834I281J-285D01*
G02X266517I-1000J-1120D01*
G03X266531Y89417I-267J298D01*
G02X268503I986J997D01*
G37*
G36*
G01X261810D02*
G03X261824Y88834I281J-285D01*
G02X259824I-1000J-1120D01*
G03X259838Y89417I-267J298D01*
G02X261810I986J997D01*
G37*
G36*
G01X244378D02*
G03X244392Y88834I281J-285D01*
G02X242392I-1000J-1120D01*
G03X242406Y89417I-267J298D01*
G02X244378I986J997D01*
G37*
G36*
G01X238092Y89378D02*
G03X238119Y88817I298J-267D01*
G02X236038Y88777I-1020J-1103D01*
G03X236042Y89338I-283J283D01*
G02X238092Y89378I1006J976D01*
G37*
G36*
G01X231692Y89417D02*
G03X231706Y88834I281J-285D01*
G02X229706I-1000J-1120D01*
G03X229720Y89417I-267J298D01*
G02X231692I986J997D01*
G37*
G36*
G01X224999D02*
G03X225013Y88834I281J-285D01*
G02X223013I-1000J-1120D01*
G03X223027Y89417I-267J298D01*
G02X224999I986J997D01*
G37*
G36*
G01X207567D02*
G03X207581Y88834I281J-285D01*
G02X205581I-1000J-1120D01*
G03X205595Y89417I-267J298D01*
G02X207567I986J997D01*
G37*
G36*
G01X201281Y89378D02*
G03X201308Y88817I298J-267D01*
G02X199227Y88777I-1020J-1103D01*
G03X199231Y89338I-283J283D01*
G02X201281Y89378I1006J976D01*
G37*
G36*
G01X194881Y89417D02*
G03X194895Y88834I281J-285D01*
G02X192895I-1000J-1120D01*
G03X192909Y89417I-267J298D01*
G02X194881I986J997D01*
G37*
G36*
G01X188188D02*
G03X188202Y88834I281J-285D01*
G02X186202I-1000J-1120D01*
G03X186216Y89417I-267J298D01*
G02X188188I986J997D01*
G37*
G36*
G01X170776Y89387D02*
G03X170791Y88816I287J-278D01*
G02X168749I-1021J-1102D01*
G03X168764Y89387I-272J293D01*
G02X170776I1006J977D01*
G37*
G36*
G01X164470Y89378D02*
G03X164497Y88817I298J-267D01*
G02X162416Y88777I-1020J-1103D01*
G03X162420Y89338I-283J283D01*
G02X164470Y89378I1006J976D01*
G37*
G36*
G01X158070Y89417D02*
G03X158084Y88834I281J-285D01*
G02X156084I-1000J-1120D01*
G03X156098Y89417I-267J298D01*
G02X158070I986J997D01*
G37*
G36*
G01X151377D02*
G03X151391Y88834I281J-285D01*
G02X149391I-1000J-1120D01*
G03X149405Y89417I-267J298D01*
G02X151377I986J997D01*
G37*
G36*
G01X133945D02*
G03X133959Y88834I281J-285D01*
G02X131959I-1000J-1120D01*
G03X131973Y89417I-267J298D01*
G02X133945I986J997D01*
G37*
G36*
G01X127659Y89378D02*
G03X127686Y88817I298J-267D01*
G02X125605Y88777I-1020J-1103D01*
G03X125609Y89338I-283J283D01*
G02X127659Y89378I1006J976D01*
G37*
G36*
G01X364129Y86483D02*
G03X363540I-295J-271D01*
G02Y88517I-1105J1017D01*
G03X364129I294J271D01*
G02Y86483I1105J-1017D01*
G37*
G36*
G01X581206Y86343D02*
G03X581187Y85736I251J-312D01*
G02X579315Y85751I-944J-1036D01*
G03X579306Y86359I-265J300D01*
G02X579170Y88541I960J1155D01*
G03Y89087I-292J273D01*
G02X579225Y91197I1096J1027D01*
G03X579241Y91758I-277J289D01*
G02X581291I1025J956D01*
G03X581307Y91197I293J-272D01*
G02X581362Y89087I-1041J-1083D01*
G03Y88541I292J-273D01*
G02X581206Y86343I-1096J-1027D01*
G37*
G36*
G01X544395D02*
G03X544376Y85736I251J-312D01*
G02X542504Y85751I-944J-1036D01*
G03X542495Y86359I-265J300D01*
G02X542359Y88541I960J1155D01*
G03Y89087I-292J273D01*
G02X542414Y91197I1096J1027D01*
G03X542430Y91758I-277J289D01*
G02X544480I1025J956D01*
G03X544496Y91197I293J-272D01*
G02X544551Y89087I-1041J-1083D01*
G03Y88541I292J-273D01*
G02X544395Y86343I-1096J-1027D01*
G37*
G36*
G01X507584D02*
G03X507565Y85736I251J-312D01*
G02X505693Y85751I-944J-1036D01*
G03X505684Y86359I-265J300D01*
G02X505548Y88541I960J1155D01*
G03Y89087I-292J273D01*
G02X505603Y91197I1096J1027D01*
G03X505619Y91758I-277J289D01*
G02X507669I1025J956D01*
G03X507685Y91197I293J-272D01*
G02X507740Y89087I-1041J-1083D01*
G03Y88541I292J-273D01*
G02X507584Y86343I-1096J-1027D01*
G37*
G36*
G01X470772D02*
G03X470753Y85736I251J-312D01*
G02X468881Y85751I-944J-1036D01*
G03X468872Y86359I-265J300D01*
G02X468736Y88541I960J1155D01*
G03Y89087I-292J273D01*
G02X468791Y91197I1096J1027D01*
G03X468807Y91758I-277J289D01*
G02X470857I1025J956D01*
G03X470873Y91197I293J-272D01*
G02X470928Y89087I-1041J-1083D01*
G03Y88541I292J-273D01*
G02X470772Y86343I-1096J-1027D01*
G37*
G36*
G01X290064D02*
G03X290045Y85736I251J-312D01*
G02X288173Y85751I-944J-1036D01*
G03X288164Y86359I-265J300D01*
G02X288028Y88541I960J1155D01*
G03Y89087I-292J273D01*
G02X288083Y91197I1096J1027D01*
G03X288099Y91758I-277J289D01*
G02X290149I1025J956D01*
G03X290165Y91197I293J-272D01*
G02X290220Y89087I-1041J-1083D01*
G03Y88541I292J-273D01*
G02X290064Y86343I-1096J-1027D01*
G37*
G36*
G01X253253D02*
G03X253234Y85736I251J-312D01*
G02X251362Y85751I-944J-1036D01*
G03X251353Y86359I-265J300D01*
G02X251217Y88541I960J1155D01*
G03Y89087I-292J273D01*
G02X251272Y91197I1096J1027D01*
G03X251288Y91758I-277J289D01*
G02X253338I1025J956D01*
G03X253354Y91197I293J-272D01*
G02X253409Y89087I-1041J-1083D01*
G03Y88541I292J-273D01*
G02X253253Y86343I-1096J-1027D01*
G37*
G36*
G01X216442D02*
G03X216423Y85736I251J-312D01*
G02X214551Y85751I-944J-1036D01*
G03X214542Y86359I-265J300D01*
G02X214406Y88541I960J1155D01*
G03Y89087I-292J273D01*
G02X214461Y91197I1096J1027D01*
G03X214477Y91758I-277J289D01*
G02X216527I1025J956D01*
G03X216543Y91197I293J-272D01*
G02X216598Y89087I-1041J-1083D01*
G03Y88541I292J-273D01*
G02X216442Y86343I-1096J-1027D01*
G37*
G36*
G01X179631D02*
G03X179612Y85736I251J-312D01*
G02X177740Y85751I-944J-1036D01*
G03X177731Y86359I-265J300D01*
G02X177595Y88541I960J1155D01*
G03Y89087I-292J273D01*
G02X177650Y91197I1096J1027D01*
G03X177666Y91758I-277J289D01*
G02X179716I1025J956D01*
G03X179732Y91197I293J-272D01*
G02X179787Y89087I-1041J-1083D01*
G03Y88541I292J-273D01*
G02X179631Y86343I-1096J-1027D01*
G37*
G36*
G01X142820D02*
G03X142801Y85736I251J-312D01*
G02X140929Y85751I-944J-1036D01*
G03X140920Y86359I-265J300D01*
G02X140784Y88541I960J1155D01*
G03Y89087I-292J273D01*
G02X140839Y91197I1096J1027D01*
G03X140855Y91758I-277J289D01*
G02X142905I1025J956D01*
G03X142921Y91197I293J-272D01*
G02X142976Y89087I-1041J-1083D01*
G03Y88541I292J-273D01*
G02X142820Y86343I-1096J-1027D01*
G37*
G36*
G01X576206Y86216D02*
G03X576191Y85655I277J-288D01*
G02X574141I-1025J-957D01*
G03X574126Y86216I-292J273D01*
G02X574070Y88327I1040J1084D01*
G03Y88873I-292J273D01*
G02X574115Y90973I1096J1027D01*
G03X574125Y91535I-280J286D01*
G02X576176Y91553I1017J965D01*
G03X576197Y90992I295J-270D01*
G02X576262Y88873I-1031J-1092D01*
G03Y88327I292J-273D01*
G02X576206Y86216I-1096J-1027D01*
G37*
G36*
G01X539395D02*
G03X539380Y85655I277J-288D01*
G02X537330I-1025J-957D01*
G03X537315Y86216I-292J273D01*
G02X537259Y88327I1040J1084D01*
G03Y88873I-292J273D01*
G02X537304Y90973I1096J1027D01*
G03X537314Y91535I-280J286D01*
G02X539365Y91553I1017J965D01*
G03X539386Y90992I295J-270D01*
G02X539451Y88873I-1031J-1092D01*
G03Y88327I292J-273D01*
G02X539395Y86216I-1096J-1027D01*
G37*
G36*
G01X502584D02*
G03X502569Y85655I277J-288D01*
G02X500519I-1025J-957D01*
G03X500504Y86216I-292J273D01*
G02X500448Y88327I1040J1084D01*
G03Y88873I-292J273D01*
G02X500493Y90973I1096J1027D01*
G03X500503Y91535I-280J286D01*
G02X502554Y91553I1017J965D01*
G03X502575Y90992I295J-270D01*
G02X502640Y88873I-1031J-1092D01*
G03Y88327I292J-273D01*
G02X502584Y86216I-1096J-1027D01*
G37*
G36*
G01X465772D02*
G03X465757Y85655I277J-288D01*
G02X463707I-1025J-957D01*
G03X463692Y86216I-292J273D01*
G02X463636Y88327I1040J1084D01*
G03Y88873I-292J273D01*
G02X463681Y90973I1096J1027D01*
G03X463691Y91535I-280J286D01*
G02X465742Y91553I1017J965D01*
G03X465763Y90992I295J-270D01*
G02X465828Y88873I-1031J-1092D01*
G03Y88327I292J-273D01*
G02X465772Y86216I-1096J-1027D01*
G37*
G36*
G01X285064D02*
G03X285049Y85655I277J-288D01*
G02X282999I-1025J-957D01*
G03X282984Y86216I-292J273D01*
G02X282928Y88327I1040J1084D01*
G03Y88873I-292J273D01*
G02X282973Y90973I1096J1027D01*
G03X282983Y91535I-280J286D01*
G02X285034Y91553I1017J965D01*
G03X285055Y90992I295J-270D01*
G02X285120Y88873I-1031J-1092D01*
G03Y88327I292J-273D01*
G02X285064Y86216I-1096J-1027D01*
G37*
G36*
G01X248253D02*
G03X248238Y85655I277J-288D01*
G02X246188I-1025J-957D01*
G03X246173Y86216I-292J273D01*
G02X246117Y88327I1040J1084D01*
G03Y88873I-292J273D01*
G02X246162Y90973I1096J1027D01*
G03X246172Y91535I-280J286D01*
G02X248223Y91553I1017J965D01*
G03X248244Y90992I295J-270D01*
G02X248309Y88873I-1031J-1092D01*
G03Y88327I292J-273D01*
G02X248253Y86216I-1096J-1027D01*
G37*
G36*
G01X211442D02*
G03X211427Y85655I277J-288D01*
G02X209377I-1025J-957D01*
G03X209362Y86216I-292J273D01*
G02X209306Y88327I1040J1084D01*
G03Y88873I-292J273D01*
G02X209351Y90973I1096J1027D01*
G03X209361Y91535I-280J286D01*
G02X211412Y91553I1017J965D01*
G03X211433Y90992I295J-270D01*
G02X211498Y88873I-1031J-1092D01*
G03Y88327I292J-273D01*
G02X211442Y86216I-1096J-1027D01*
G37*
G36*
G01X174631D02*
G03X174616Y85655I277J-288D01*
G02X172566I-1025J-957D01*
G03X172551Y86216I-292J273D01*
G02X172495Y88327I1040J1084D01*
G03Y88873I-292J273D01*
G02X172540Y90973I1096J1027D01*
G03X172550Y91535I-280J286D01*
G02X174601Y91553I1017J965D01*
G03X174622Y90992I295J-270D01*
G02X174687Y88873I-1031J-1092D01*
G03Y88327I292J-273D01*
G02X174631Y86216I-1096J-1027D01*
G37*
G36*
G01X137820D02*
G03X137805Y85655I277J-288D01*
G02X135755I-1025J-957D01*
G03X135740Y86216I-292J273D01*
G02X135684Y88327I1040J1084D01*
G03Y88873I-292J273D01*
G02X135729Y90973I1096J1027D01*
G03X135739Y91535I-280J286D01*
G02X137790Y91553I1017J965D01*
G03X137811Y90992I295J-270D01*
G02X137876Y88873I-1031J-1092D01*
G03Y88327I292J-273D01*
G02X137820Y86216I-1096J-1027D01*
G37*
G36*
G01X376469Y85390D02*
G03Y84864I302J-263D01*
G02X374205I-1132J-987D01*
G03Y85390I-302J263D01*
G02X376469I1132J987D01*
G37*
G36*
G01X358743Y69924D02*
G03Y69346I277J-289D01*
G02X356801I-971J-1011D01*
G03Y69924I-277J289D01*
G02X358743I971J1011D01*
G37*
G36*
G01X308938Y69365D02*
G03X308924Y68789I270J-295D01*
G02X306982Y68837I-996J-987D01*
G03X306996Y69413I-270J295D01*
G02X308938Y69365I996J987D01*
G37*
G36*
G01X576233Y67467D02*
G03X576217Y66906I277J-289D01*
G02X574167I-1025J-956D01*
G03X574151Y67467I-293J272D01*
G02X574104Y69585I1041J1083D01*
G03X574098Y70142I-290J275D01*
G02X574125Y72282I1068J1057D01*
G03X574141Y72843I-277J289D01*
G02X576191I1025J956D01*
G03X576207Y72282I293J-272D01*
G02X576254Y70164I-1041J-1083D01*
G03X576260Y69607I290J-275D01*
G02X576233Y67467I-1068J-1057D01*
G37*
G36*
G01X539422D02*
G03X539406Y66906I277J-289D01*
G02X537356I-1025J-956D01*
G03X537340Y67467I-293J272D01*
G02X537293Y69585I1041J1083D01*
G03X537287Y70142I-290J275D01*
G02X537314Y72282I1068J1057D01*
G03X537330Y72843I-277J289D01*
G02X539380I1025J956D01*
G03X539396Y72282I293J-272D01*
G02X539443Y70164I-1041J-1083D01*
G03X539449Y69607I290J-275D01*
G02X539422Y67467I-1068J-1057D01*
G37*
G36*
G01X502611D02*
G03X502595Y66906I277J-289D01*
G02X500545I-1025J-956D01*
G03X500529Y67467I-293J272D01*
G02X500482Y69585I1041J1083D01*
G03X500476Y70142I-290J275D01*
G02X500503Y72282I1068J1057D01*
G03X500519Y72843I-277J289D01*
G02X502569I1025J956D01*
G03X502585Y72282I293J-272D01*
G02X502632Y70164I-1041J-1083D01*
G03X502638Y69607I290J-275D01*
G02X502611Y67467I-1068J-1057D01*
G37*
G36*
G01X465799D02*
G03X465783Y66906I277J-289D01*
G02X463733I-1025J-956D01*
G03X463717Y67467I-293J272D01*
G02X463670Y69585I1041J1083D01*
G03X463664Y70142I-290J275D01*
G02X463691Y72282I1068J1057D01*
G03X463707Y72843I-277J289D01*
G02X465757I1025J956D01*
G03X465773Y72282I293J-272D01*
G02X465820Y70164I-1041J-1083D01*
G03X465826Y69607I290J-275D01*
G02X465799Y67467I-1068J-1057D01*
G37*
G36*
G01X285091D02*
G03X285075Y66906I277J-289D01*
G02X283025I-1025J-956D01*
G03X283009Y67467I-293J272D01*
G02X282962Y69585I1041J1083D01*
G03X282956Y70142I-290J275D01*
G02X282983Y72282I1068J1057D01*
G03X282999Y72843I-277J289D01*
G02X285049I1025J956D01*
G03X285065Y72282I293J-272D01*
G02X285112Y70164I-1041J-1083D01*
G03X285118Y69607I290J-275D01*
G02X285091Y67467I-1068J-1057D01*
G37*
G36*
G01X248280D02*
G03X248264Y66906I277J-289D01*
G02X246214I-1025J-956D01*
G03X246198Y67467I-293J272D01*
G02X246151Y69585I1041J1083D01*
G03X246145Y70142I-290J275D01*
G02X246172Y72282I1068J1057D01*
G03X246188Y72843I-277J289D01*
G02X248238I1025J956D01*
G03X248254Y72282I293J-272D01*
G02X248301Y70164I-1041J-1083D01*
G03X248307Y69607I290J-275D01*
G02X248280Y67467I-1068J-1057D01*
G37*
G36*
G01X211469D02*
G03X211453Y66906I277J-289D01*
G02X209403I-1025J-956D01*
G03X209387Y67467I-293J272D01*
G02X209340Y69585I1041J1083D01*
G03X209334Y70142I-290J275D01*
G02X209361Y72282I1068J1057D01*
G03X209377Y72843I-277J289D01*
G02X211427I1025J956D01*
G03X211443Y72282I293J-272D01*
G02X211490Y70164I-1041J-1083D01*
G03X211496Y69607I290J-275D01*
G02X211469Y67467I-1068J-1057D01*
G37*
G36*
G01X174658D02*
G03X174642Y66906I277J-289D01*
G02X172592I-1025J-956D01*
G03X172576Y67467I-293J272D01*
G02X172529Y69585I1041J1083D01*
G03X172523Y70142I-290J275D01*
G02X172550Y72282I1068J1057D01*
G03X172566Y72843I-277J289D01*
G02X174616I1025J956D01*
G03X174632Y72282I293J-272D01*
G02X174679Y70164I-1041J-1083D01*
G03X174685Y69607I290J-275D01*
G02X174658Y67467I-1068J-1057D01*
G37*
G36*
G01X137847D02*
G03X137831Y66906I277J-289D01*
G02X135781I-1025J-956D01*
G03X135765Y67467I-293J272D01*
G02X135718Y69585I1041J1083D01*
G03X135712Y70142I-290J275D01*
G02X135739Y72282I1068J1057D01*
G03X135755Y72843I-277J289D01*
G02X137805I1025J956D01*
G03X137821Y72282I293J-272D01*
G02X137868Y70164I-1041J-1083D01*
G03X137874Y69607I290J-275D01*
G02X137847Y67467I-1068J-1057D01*
G37*
G36*
G01X581311Y67261D02*
G03X581298Y66699I278J-288D01*
G02X579250Y66689I-1019J-963D01*
G03X579232Y67250I-293J271D01*
G02X579173Y69370I1034J1090D01*
G03Y69919I-291J274D01*
G02X579236Y72043I1093J1031D01*
G03X579257Y72604I-274J291D01*
G02X581307Y72583I1035J946D01*
G03X581317Y72022I290J-275D01*
G02X581359Y69919I-1051J-1073D01*
G03Y69370I291J-274D01*
G02X581311Y67261I-1093J-1030D01*
G37*
G36*
G01X544500D02*
G03X544487Y66699I278J-288D01*
G02X542439Y66689I-1019J-963D01*
G03X542421Y67250I-293J271D01*
G02X542362Y69370I1034J1090D01*
G03Y69919I-291J274D01*
G02X542425Y72043I1093J1031D01*
G03X542446Y72604I-274J291D01*
G02X544496Y72583I1035J946D01*
G03X544506Y72022I290J-275D01*
G02X544548Y69919I-1051J-1073D01*
G03Y69370I291J-274D01*
G02X544500Y67261I-1093J-1030D01*
G37*
G36*
G01X507689D02*
G03X507676Y66699I278J-288D01*
G02X505628Y66689I-1019J-963D01*
G03X505610Y67250I-293J271D01*
G02X505551Y69370I1034J1090D01*
G03Y69919I-291J274D01*
G02X505614Y72043I1093J1031D01*
G03X505635Y72604I-274J291D01*
G02X507685Y72583I1035J946D01*
G03X507695Y72022I290J-275D01*
G02X507737Y69919I-1051J-1073D01*
G03Y69370I291J-274D01*
G02X507689Y67261I-1093J-1030D01*
G37*
G36*
G01X470877D02*
G03X470864Y66699I278J-288D01*
G02X468816Y66689I-1019J-963D01*
G03X468798Y67250I-293J271D01*
G02X468739Y69370I1034J1090D01*
G03Y69919I-291J274D01*
G02X468802Y72043I1093J1031D01*
G03X468823Y72604I-274J291D01*
G02X470873Y72583I1035J946D01*
G03X470883Y72022I290J-275D01*
G02X470925Y69919I-1051J-1073D01*
G03Y69370I291J-274D01*
G02X470877Y67261I-1093J-1030D01*
G37*
G36*
G01X290169D02*
G03X290156Y66699I278J-288D01*
G02X288108Y66689I-1019J-963D01*
G03X288090Y67250I-293J271D01*
G02X288031Y69370I1034J1090D01*
G03Y69919I-291J274D01*
G02X288094Y72043I1093J1031D01*
G03X288115Y72604I-274J291D01*
G02X290165Y72583I1035J946D01*
G03X290175Y72022I290J-275D01*
G02X290217Y69919I-1051J-1073D01*
G03Y69370I291J-274D01*
G02X290169Y67261I-1093J-1030D01*
G37*
G36*
G01X253358D02*
G03X253345Y66699I278J-288D01*
G02X251297Y66689I-1019J-963D01*
G03X251279Y67250I-293J271D01*
G02X251220Y69370I1034J1090D01*
G03Y69919I-291J274D01*
G02X251283Y72043I1093J1031D01*
G03X251304Y72604I-274J291D01*
G02X253354Y72583I1035J946D01*
G03X253364Y72022I290J-275D01*
G02X253406Y69919I-1051J-1073D01*
G03Y69370I291J-274D01*
G02X253358Y67261I-1093J-1030D01*
G37*
G36*
G01X216547D02*
G03X216534Y66699I278J-288D01*
G02X214486Y66689I-1019J-963D01*
G03X214468Y67250I-293J271D01*
G02X214409Y69370I1034J1090D01*
G03Y69919I-291J274D01*
G02X214472Y72043I1093J1031D01*
G03X214493Y72604I-274J291D01*
G02X216543Y72583I1035J946D01*
G03X216553Y72022I290J-275D01*
G02X216595Y69919I-1051J-1073D01*
G03Y69370I291J-274D01*
G02X216547Y67261I-1093J-1030D01*
G37*
G36*
G01X179736D02*
G03X179723Y66699I278J-288D01*
G02X177675Y66689I-1019J-963D01*
G03X177657Y67250I-293J271D01*
G02X177598Y69370I1034J1090D01*
G03Y69919I-291J274D01*
G02X177661Y72043I1093J1031D01*
G03X177682Y72604I-274J291D01*
G02X179732Y72583I1035J946D01*
G03X179742Y72022I290J-275D01*
G02X179784Y69919I-1051J-1073D01*
G03Y69370I291J-274D01*
G02X179736Y67261I-1093J-1030D01*
G37*
G36*
G01X142925D02*
G03X142912Y66699I278J-288D01*
G02X140864Y66689I-1019J-963D01*
G03X140846Y67250I-293J271D01*
G02X140787Y69370I1034J1090D01*
G03Y69919I-291J274D01*
G02X140850Y72043I1093J1031D01*
G03X140871Y72604I-274J291D01*
G02X142921Y72583I1035J946D01*
G03X142931Y72022I290J-275D01*
G02X142973Y69919I-1051J-1073D01*
G03Y69370I291J-274D01*
G02X142925Y67261I-1093J-1030D01*
G37*
G36*
G01X381854Y62047D02*
G03X381873Y61418I256J-307D01*
G02X380018Y61363I-892J-1208D01*
G03X379999Y61992I-256J307D01*
G02X381854Y62047I892J1208D01*
G37*
G36*
G01X449900Y55935D02*
G03X450461Y55966I265J300D01*
G02X450520Y53886I1112J-1009D01*
G03X449958I-281J-285D01*
G02X449900Y55935I-985J997D01*
G37*
G36*
G01X596456Y51617D02*
G03X596470Y51034I281J-285D01*
G02X594470I-1000J-1120D01*
G03X594484Y51617I-267J298D01*
G02X596456I986J997D01*
G37*
G36*
G01X589763D02*
G03X589777Y51034I281J-285D01*
G02X587777I-1000J-1120D01*
G03X587791Y51617I-267J298D01*
G02X589763I986J997D01*
G37*
G36*
G01X572331D02*
G03X572345Y51034I281J-285D01*
G02X570345I-1000J-1120D01*
G03X570359Y51617I-267J298D01*
G02X572331I986J997D01*
G37*
G36*
G01X559645D02*
G03X559659Y51034I281J-285D01*
G02X557659I-1000J-1120D01*
G03X557673Y51617I-267J298D01*
G02X559645I986J997D01*
G37*
G36*
G01X552952D02*
G03X552966Y51034I281J-285D01*
G02X550966I-1000J-1120D01*
G03X550980Y51617I-267J298D01*
G02X552952I986J997D01*
G37*
G36*
G01X535520D02*
G03X535534Y51034I281J-285D01*
G02X533534I-1000J-1120D01*
G03X533548Y51617I-267J298D01*
G02X535520I986J997D01*
G37*
G36*
G01X522834D02*
G03X522848Y51034I281J-285D01*
G02X520848I-1000J-1120D01*
G03X520862Y51617I-267J298D01*
G02X522834I986J997D01*
G37*
G36*
G01X516141D02*
G03X516155Y51034I281J-285D01*
G02X514155I-1000J-1120D01*
G03X514169Y51617I-267J298D01*
G02X516141I986J997D01*
G37*
G36*
G01X498709D02*
G03X498723Y51034I281J-285D01*
G02X496723I-1000J-1120D01*
G03X496737Y51617I-267J298D01*
G02X498709I986J997D01*
G37*
G36*
G01X486023D02*
G03X486037Y51034I281J-285D01*
G02X484037I-1000J-1120D01*
G03X484051Y51617I-267J298D01*
G02X486023I986J997D01*
G37*
G36*
G01X479330D02*
G03X479344Y51034I281J-285D01*
G02X477344I-1000J-1120D01*
G03X477358Y51617I-267J298D01*
G02X479330I986J997D01*
G37*
G36*
G01X461898D02*
G03X461912Y51034I281J-285D01*
G02X459912I-1000J-1120D01*
G03X459926Y51617I-267J298D01*
G02X461898I986J997D01*
G37*
G36*
G01X305314D02*
G03X305328Y51034I281J-285D01*
G02X303328I-1000J-1120D01*
G03X303342Y51617I-267J298D01*
G02X305314I986J997D01*
G37*
G36*
G01X298621D02*
G03X298635Y51034I281J-285D01*
G02X296635I-1000J-1120D01*
G03X296649Y51617I-267J298D01*
G02X298621I986J997D01*
G37*
G36*
G01X281189D02*
G03X281203Y51034I281J-285D01*
G02X279203I-1000J-1120D01*
G03X279217Y51617I-267J298D01*
G02X281189I986J997D01*
G37*
G36*
G01X268503D02*
G03X268517Y51034I281J-285D01*
G02X266517I-1000J-1120D01*
G03X266531Y51617I-267J298D01*
G02X268503I986J997D01*
G37*
G36*
G01X261810D02*
G03X261824Y51034I281J-285D01*
G02X259824I-1000J-1120D01*
G03X259838Y51617I-267J298D01*
G02X261810I986J997D01*
G37*
G36*
G01X244378D02*
G03X244392Y51034I281J-285D01*
G02X242392I-1000J-1120D01*
G03X242406Y51617I-267J298D01*
G02X244378I986J997D01*
G37*
G36*
G01X238092Y51578D02*
G03X238119Y51017I298J-267D01*
G02X236038Y50977I-1020J-1103D01*
G03X236042Y51538I-283J283D01*
G02X238092Y51578I1006J976D01*
G37*
G36*
G01X231692Y51617D02*
G03X231706Y51034I281J-285D01*
G02X229706I-1000J-1120D01*
G03X229720Y51617I-267J298D01*
G02X231692I986J997D01*
G37*
G36*
G01X224999D02*
G03X225013Y51034I281J-285D01*
G02X223013I-1000J-1120D01*
G03X223027Y51617I-267J298D01*
G02X224999I986J997D01*
G37*
G36*
G01X207567D02*
G03X207581Y51034I281J-285D01*
G02X205581I-1000J-1120D01*
G03X205595Y51617I-267J298D01*
G02X207567I986J997D01*
G37*
G36*
G01X201281Y51578D02*
G03X201308Y51017I298J-267D01*
G02X199227Y50977I-1020J-1103D01*
G03X199231Y51538I-283J283D01*
G02X201281Y51578I1006J976D01*
G37*
G36*
G01X194881Y51617D02*
G03X194895Y51034I281J-285D01*
G02X192895I-1000J-1120D01*
G03X192909Y51617I-267J298D01*
G02X194881I986J997D01*
G37*
G36*
G01X188188D02*
G03X188202Y51034I281J-285D01*
G02X186202I-1000J-1120D01*
G03X186216Y51617I-267J298D01*
G02X188188I986J997D01*
G37*
G36*
G01X170756D02*
G03X170770Y51034I281J-285D01*
G02X168770I-1000J-1120D01*
G03X168784Y51617I-267J298D01*
G02X170756I986J997D01*
G37*
G36*
G01X164470Y51578D02*
G03X164497Y51017I298J-267D01*
G02X162416Y50977I-1020J-1103D01*
G03X162420Y51538I-283J283D01*
G02X164470Y51578I1006J976D01*
G37*
G36*
G01X158070Y51617D02*
G03X158084Y51034I281J-285D01*
G02X156084I-1000J-1120D01*
G03X156098Y51617I-267J298D01*
G02X158070I986J997D01*
G37*
G36*
G01X151377D02*
G03X151391Y51034I281J-285D01*
G02X149391I-1000J-1120D01*
G03X149405Y51617I-267J298D01*
G02X151377I986J997D01*
G37*
G36*
G01X133945D02*
G03X133959Y51034I281J-285D01*
G02X131959I-1000J-1120D01*
G03X131973Y51617I-267J298D01*
G02X133945I986J997D01*
G37*
G36*
G01X127659Y51578D02*
G03X127686Y51017I298J-267D01*
G02X125605Y50977I-1020J-1103D01*
G03X125609Y51538I-283J283D01*
G02X127659Y51578I1006J976D01*
G37*
G36*
G01X358702Y51293D02*
G03Y50699I268J-297D01*
G02X356822I-940J-1040D01*
G03Y51293I-268J297D01*
G02X358702I940J1040D01*
G37*
G36*
G01X581362Y51287D02*
G03Y50741I292J-273D01*
G02X579170I-1096J-1027D01*
G03Y51287I-292J273D01*
G02X579225Y53397I1096J1027D01*
G03X579241Y53958I-277J289D01*
G02X581291I1025J956D01*
G03X581307Y53397I293J-272D01*
G02X581362Y51287I-1041J-1083D01*
G37*
G36*
G01X470851Y48610D02*
G03X470827Y48046I271J-294D01*
G02X468787Y48077I-1035J-946D01*
G03X468780Y48642I-287J279D01*
G02X468736Y50741I1052J1072D01*
G03Y51287I-292J273D01*
G02X468791Y53397I1096J1027D01*
G03X468807Y53958I-277J289D01*
G02X470857I1025J956D01*
G03X470873Y53397I293J-272D01*
G02X470928Y51287I-1041J-1083D01*
G03Y50741I292J-273D01*
G02X470851Y48610I-1096J-1027D01*
G37*
G36*
G01X544428Y48570D02*
G03X544402Y47984I259J-305D01*
G02X542443Y48021I-998J-984D01*
G03X542440Y48607I-274J292D01*
G02X542359Y50741I1015J1107D01*
G03Y51287I-292J273D01*
G02X542414Y53397I1096J1027D01*
G03X542430Y53958I-277J289D01*
G02X544480I1025J956D01*
G03X544496Y53397I293J-272D01*
G02X544551Y51287I-1041J-1083D01*
G03Y50741I292J-273D01*
G02X544428Y48570I-1096J-1027D01*
G37*
G36*
G01X507616D02*
G03X507590Y47984I259J-305D01*
G02X505631Y48021I-998J-984D01*
G03X505628Y48607I-274J292D01*
G02X505547Y50741I1015J1107D01*
G03Y51287I-292J273D01*
G02X505603Y53397I1096J1027D01*
G03X505618Y53958I-277J288D01*
G02X507669I1025J956D01*
G03X507684Y53396I292J-273D01*
G02X507739Y51287I-1041J-1082D01*
G03Y50741I292J-273D01*
G02X507616Y48570I-1096J-1027D01*
G37*
G36*
G01X363196Y46006D02*
G03X362587I-305J-258D01*
G02Y47822I-1069J908D01*
G03X363196I305J258D01*
G02Y46006I1069J-908D01*
G37*
G36*
G01X290064Y48543D02*
G03X290045Y47936I251J-312D01*
G02X288173Y47951I-944J-1036D01*
G03X288164Y48559I-265J300D01*
G02X288028Y50741I960J1155D01*
G03Y51287I-292J273D01*
G02X288083Y53397I1096J1027D01*
G03X288099Y53958I-277J289D01*
G02X290149I1025J956D01*
G03X290165Y53397I293J-272D01*
G02X290220Y51287I-1041J-1083D01*
G03Y50741I292J-273D01*
G02X290064Y48543I-1096J-1027D01*
G37*
G36*
G01X253253D02*
G03X253234Y47936I251J-312D01*
G02X251362Y47951I-944J-1036D01*
G03X251353Y48559I-265J300D01*
G02X251217Y50741I960J1155D01*
G03Y51287I-292J273D01*
G02X251272Y53397I1096J1027D01*
G03X251288Y53958I-277J289D01*
G02X253338I1025J956D01*
G03X253354Y53397I293J-272D01*
G02X253409Y51287I-1041J-1083D01*
G03Y50741I292J-273D01*
G02X253253Y48543I-1096J-1027D01*
G37*
G36*
G01X216442D02*
G03X216423Y47936I251J-312D01*
G02X214551Y47951I-944J-1036D01*
G03X214542Y48559I-265J300D01*
G02X214406Y50741I960J1155D01*
G03Y51287I-292J273D01*
G02X214461Y53397I1096J1027D01*
G03X214477Y53958I-277J289D01*
G02X216527I1025J956D01*
G03X216543Y53397I293J-272D01*
G02X216598Y51287I-1041J-1083D01*
G03Y50741I292J-273D01*
G02X216442Y48543I-1096J-1027D01*
G37*
G36*
G01X179631D02*
G03X179612Y47936I251J-312D01*
G02X177740Y47951I-944J-1036D01*
G03X177731Y48559I-265J300D01*
G02X177595Y50741I960J1155D01*
G03Y51287I-292J273D01*
G02X177650Y53397I1096J1027D01*
G03X177666Y53958I-277J289D01*
G02X179716I1025J956D01*
G03X179732Y53397I293J-272D01*
G02X179787Y51287I-1041J-1083D01*
G03Y50741I292J-273D01*
G02X179631Y48543I-1096J-1027D01*
G37*
G36*
G01X142820D02*
G03X142801Y47936I251J-312D01*
G02X140929Y47951I-944J-1036D01*
G03X140920Y48559I-265J300D01*
G02X140784Y50741I960J1155D01*
G03Y51287I-292J273D01*
G02X140839Y53397I1096J1027D01*
G03X140855Y53958I-277J289D01*
G02X142905I1025J956D01*
G03X142921Y53397I293J-272D01*
G02X142976Y51287I-1041J-1083D01*
G03Y50741I292J-273D01*
G02X142820Y48543I-1096J-1027D01*
G37*
G36*
G01X576206Y48416D02*
G03X576191Y47855I277J-288D01*
G02X574141I-1025J-957D01*
G03X574126Y48416I-292J273D01*
G02X574070Y50527I1040J1084D01*
G03Y51073I-292J273D01*
G02X576262I1096J1027D01*
G03Y50527I292J-273D01*
G02X576206Y48416I-1096J-1027D01*
G37*
G36*
G01X539395D02*
G03X539380Y47855I277J-288D01*
G02X537330I-1025J-957D01*
G03X537315Y48416I-292J273D01*
G02X537259Y50527I1040J1084D01*
G03Y51073I-292J273D01*
G02X537293Y53162I1096J1027D01*
G03X537298Y53724I-282J284D01*
G02X539348Y53764I1006J976D01*
G03X539374Y53203I298J-267D01*
G02X539451Y51073I-1019J-1103D01*
G03Y50527I292J-273D01*
G02X539395Y48416I-1096J-1027D01*
G37*
G36*
G01X502584Y48417D02*
G03X502568Y47855I277J-289D01*
G02X500519Y47854I-1024J-957D01*
G03X500503Y48416I-292J273D01*
G02X500447Y50527I1040J1084D01*
G03Y51073I-292J273D01*
G02X500481Y53162I1096J1027D01*
G03X500486Y53724I-282J284D01*
G02X502536Y53764I1006J976D01*
G03X502562Y53203I298J-267D01*
G02X502639Y51073I-1019J-1103D01*
G03Y50527I292J-273D01*
G02X502584Y48417I-1096J-1027D01*
G37*
G36*
G01X465772Y48416D02*
G03X465757Y47855I277J-288D01*
G02X463707I-1025J-957D01*
G03X463692Y48416I-292J273D01*
G02X463636Y50527I1040J1084D01*
G03Y51073I-292J273D01*
G02X463675Y53167I1096J1027D01*
G03X463681Y53728I-282J284D01*
G02X465732Y53760I1011J972D01*
G03X465756Y53199I297J-268D01*
G02X465828Y51073I-1024J-1099D01*
G03Y50527I292J-273D01*
G02X465772Y48416I-1096J-1027D01*
G37*
G36*
G01X285064D02*
G03X285049Y47855I277J-288D01*
G02X282999I-1025J-957D01*
G03X282984Y48416I-292J273D01*
G02X282928Y50527I1040J1084D01*
G03Y51073I-292J273D01*
G02X282973Y53173I1096J1027D01*
G03X282983Y53735I-280J286D01*
G02X285034Y53753I1017J965D01*
G03X285055Y53192I295J-270D01*
G02X285120Y51073I-1031J-1092D01*
G03Y50527I292J-273D01*
G02X285064Y48416I-1096J-1027D01*
G37*
G36*
G01X248253D02*
G03X248238Y47855I277J-288D01*
G02X246188I-1025J-957D01*
G03X246173Y48416I-292J273D01*
G02X246117Y50527I1040J1084D01*
G03Y51073I-292J273D01*
G02X246162Y53173I1096J1027D01*
G03X246172Y53735I-280J286D01*
G02X248223Y53753I1017J965D01*
G03X248244Y53192I295J-270D01*
G02X248309Y51073I-1031J-1092D01*
G03Y50527I292J-273D01*
G02X248253Y48416I-1096J-1027D01*
G37*
G36*
G01X211442D02*
G03X211427Y47855I277J-288D01*
G02X209377I-1025J-957D01*
G03X209362Y48416I-292J273D01*
G02X209306Y50527I1040J1084D01*
G03Y51073I-292J273D01*
G02X209351Y53173I1096J1027D01*
G03X209361Y53735I-280J286D01*
G02X211412Y53753I1017J965D01*
G03X211433Y53192I295J-270D01*
G02X211498Y51073I-1031J-1092D01*
G03Y50527I292J-273D01*
G02X211442Y48416I-1096J-1027D01*
G37*
G36*
G01X174631D02*
G03X174616Y47855I277J-288D01*
G02X172566I-1025J-957D01*
G03X172551Y48416I-292J273D01*
G02X172495Y50527I1040J1084D01*
G03Y51073I-292J273D01*
G02X172540Y53173I1096J1027D01*
G03X172550Y53735I-280J286D01*
G02X174601Y53753I1017J965D01*
G03X174622Y53192I295J-270D01*
G02X174687Y51073I-1031J-1092D01*
G03Y50527I292J-273D01*
G02X174631Y48416I-1096J-1027D01*
G37*
G36*
G01X137820D02*
G03X137805Y47855I277J-288D01*
G02X135755I-1025J-957D01*
G03X135740Y48416I-292J273D01*
G02X135684Y50527I1040J1084D01*
G03Y51073I-292J273D01*
G02X135729Y53173I1096J1027D01*
G03X135739Y53735I-280J286D01*
G02X137790Y53753I1017J965D01*
G03X137811Y53192I295J-270D01*
G02X137876Y51073I-1031J-1092D01*
G03Y50527I292J-273D01*
G02X137820Y48416I-1096J-1027D01*
G37*
G36*
G01X653040Y30143D02*
G03X652485Y30144I-278J-287D01*
G02X650411Y30133I-1043J1081D01*
G03X649870Y30140I-274J-291D01*
G02X649898Y32350I-1003J1118D01*
G03X650439Y32343I274J291D01*
G02X652546Y32244I1003J-1118D01*
G03X653101Y32212I294J271D01*
G02X653040Y30143I915J-1062D01*
G37*
G36*
G01X359577Y32318D02*
G03X359571Y31740I273J-292D01*
G02X357634Y31760I-979J-1004D01*
G03X357640Y32338I-273J292D01*
G02X359577Y32318I979J1004D01*
G37*
G36*
G01X285091Y29667D02*
G03X285075Y29106I277J-289D01*
G02X283025I-1025J-956D01*
G03X283009Y29667I-293J272D01*
G02X282962Y31785I1041J1083D01*
G03X282956Y32342I-290J275D01*
G02X282983Y34482I1068J1057D01*
G03X282999Y35043I-277J289D01*
G02X285049I1025J956D01*
G03X285065Y34482I293J-272D01*
G02X285112Y32364I-1041J-1083D01*
G03X285118Y31807I290J-275D01*
G02X285091Y29667I-1068J-1057D01*
G37*
G36*
G01X248280D02*
G03X248264Y29106I277J-289D01*
G02X246214I-1025J-956D01*
G03X246198Y29667I-293J272D01*
G02X246151Y31785I1041J1083D01*
G03X246145Y32342I-290J275D01*
G02X246172Y34482I1068J1057D01*
G03X246188Y35043I-277J289D01*
G02X248238I1025J956D01*
G03X248254Y34482I293J-272D01*
G02X248301Y32364I-1041J-1083D01*
G03X248307Y31807I290J-275D01*
G02X248280Y29667I-1068J-1057D01*
G37*
G36*
G01X211469D02*
G03X211453Y29106I277J-289D01*
G02X209403I-1025J-956D01*
G03X209387Y29667I-293J272D01*
G02X209340Y31785I1041J1083D01*
G03X209334Y32342I-290J275D01*
G02X209361Y34482I1068J1057D01*
G03X209377Y35043I-277J289D01*
G02X211427I1025J956D01*
G03X211443Y34482I293J-272D01*
G02X211490Y32364I-1041J-1083D01*
G03X211496Y31807I290J-275D01*
G02X211469Y29667I-1068J-1057D01*
G37*
G36*
G01X174658D02*
G03X174642Y29106I277J-289D01*
G02X172592I-1025J-956D01*
G03X172576Y29667I-293J272D01*
G02X172529Y31785I1041J1083D01*
G03X172523Y32342I-290J275D01*
G02X172550Y34482I1068J1057D01*
G03X172566Y35043I-277J289D01*
G02X174616I1025J956D01*
G03X174632Y34482I293J-272D01*
G02X174679Y32364I-1041J-1083D01*
G03X174685Y31807I290J-275D01*
G02X174658Y29667I-1068J-1057D01*
G37*
G36*
G01X137847D02*
G03X137831Y29106I277J-289D01*
G02X135781I-1025J-956D01*
G03X135765Y29667I-293J272D01*
G02X135718Y31785I1041J1083D01*
G03X135712Y32342I-290J275D01*
G02X135739Y34482I1068J1057D01*
G03X135755Y35043I-277J289D01*
G02X137805I1025J956D01*
G03X137821Y34482I293J-272D01*
G02X137868Y32364I-1041J-1083D01*
G03X137874Y31807I290J-275D01*
G02X137847Y29667I-1068J-1057D01*
G37*
G36*
G01X576213Y29648D02*
G03X576198Y29077I272J-293D01*
G02X574186I-1006J-977D01*
G03X574171Y29648I-287J278D01*
G02X574104Y31785I1021J1102D01*
G03X574098Y32342I-290J275D01*
G02X574125Y34482I1068J1057D01*
G03X574141Y35043I-277J289D01*
G02X576191I1025J956D01*
G03X576207Y34482I293J-272D01*
G02X576254Y32364I-1041J-1083D01*
G03X576260Y31807I290J-275D01*
G02X576213Y29648I-1068J-1057D01*
G37*
G36*
G01X539416Y29662D02*
G03X539408Y29089I275J-290D01*
G02X537397Y29064I-993J-989D01*
G03X537374Y29635I-291J274D01*
G02X537293Y31785I1007J1114D01*
G03X537287Y32342I-290J275D01*
G02X537314Y34482I1068J1057D01*
G03X537330Y35043I-277J289D01*
G02X539380I1025J956D01*
G03X539396Y34482I293J-272D01*
G02X539443Y32364I-1041J-1083D01*
G03X539449Y31807I290J-275D01*
G02X539416Y29662I-1068J-1056D01*
G37*
G36*
G01X502604D02*
G03X502596Y29089I275J-290D01*
G02X500585Y29064I-993J-989D01*
G03X500562Y29635I-291J274D01*
G02X500481Y31785I1007J1114D01*
G03X500475Y32342I-290J275D01*
G02X500503Y34482I1068J1056D01*
G03X500518Y35043I-277J288D01*
G02X502569I1025J956D01*
G03X502584Y34481I292J-273D01*
G02X502631Y32364I-1041J-1082D01*
G03X502637Y31807I290J-275D01*
G02X502604Y29662I-1068J-1056D01*
G37*
G36*
G01X465793D02*
G03X465785Y29089I275J-290D01*
G02X463774Y29064I-993J-989D01*
G03X463751Y29635I-291J274D01*
G02X463670Y31785I1007J1114D01*
G03X463664Y32342I-290J275D01*
G02X463691Y34482I1068J1057D01*
G03X463707Y35043I-277J289D01*
G02X465757I1025J956D01*
G03X465773Y34482I293J-272D01*
G02X465820Y32364I-1041J-1083D01*
G03X465826Y31807I290J-275D01*
G02X465793Y29662I-1068J-1056D01*
G37*
G36*
G01X581311Y29461D02*
G03X581298Y28899I278J-288D01*
G02X579250Y28889I-1019J-963D01*
G03X579232Y29450I-293J271D01*
G02X579173Y31570I1034J1090D01*
G03Y32119I-291J274D01*
G02X579196Y34203I1093J1030D01*
G03X579195Y34764I-286J280D01*
G02X581243Y34823I996J986D01*
G03X581275Y34262I300J-264D01*
G02X581359Y32119I-1009J-1113D01*
G03Y31570I291J-275D01*
G02X581311Y29461I-1093J-1030D01*
G37*
G36*
G01X544500D02*
G03X544487Y28899I278J-288D01*
G02X542439Y28889I-1019J-963D01*
G03X542421Y29450I-293J271D01*
G02X542362Y31570I1034J1090D01*
G03Y32119I-291J274D01*
G02X542418Y34236I1093J1030D01*
G03X542424Y34808I-276J289D01*
G02X544435Y34838I991J992D01*
G03X544459Y34266I291J-274D01*
G02X544548Y32119I-1004J-1117D01*
G03Y31570I291J-275D01*
G02X544500Y29461I-1093J-1030D01*
G37*
G36*
G01X507688D02*
G03X507676Y28899I278J-287D01*
G02X505628Y28888I-1019J-963D01*
G03X505610Y29450I-294J272D01*
G02X505550Y31570I1033J1090D01*
G03Y32119I-291J274D01*
G02X505606Y34236I1093J1030D01*
G03X505612Y34808I-276J289D01*
G02X507623Y34838I991J992D01*
G03X507647Y34266I291J-274D01*
G02X507736Y32119I-1004J-1117D01*
G03Y31570I291J-275D01*
G02X507688Y29461I-1093J-1030D01*
G37*
G36*
G01X470877D02*
G03X470864Y28899I278J-288D01*
G02X468816Y28889I-1019J-963D01*
G03X468798Y29450I-293J271D01*
G02X468739Y31570I1034J1090D01*
G03Y32119I-291J274D01*
G02X468795Y34236I1093J1030D01*
G03X468801Y34808I-276J289D01*
G02X470812Y34838I991J992D01*
G03X470836Y34266I291J-274D01*
G02X470925Y32119I-1004J-1117D01*
G03Y31570I291J-275D01*
G02X470877Y29461I-1093J-1030D01*
G37*
G36*
G01X290169D02*
G03X290156Y28899I278J-288D01*
G02X288108Y28889I-1019J-963D01*
G03X288090Y29450I-293J271D01*
G02X288031Y31570I1034J1090D01*
G03Y32119I-291J274D01*
G02X288094Y34243I1093J1031D01*
G03X288115Y34804I-274J291D01*
G02X290165Y34783I1035J946D01*
G03X290175Y34222I290J-275D01*
G02X290217Y32119I-1051J-1073D01*
G03Y31570I291J-275D01*
G02X290169Y29461I-1093J-1030D01*
G37*
G36*
G01X253358D02*
G03X253345Y28899I278J-288D01*
G02X251297Y28889I-1019J-963D01*
G03X251279Y29450I-293J271D01*
G02X251220Y31570I1034J1090D01*
G03Y32119I-291J274D01*
G02X251283Y34243I1093J1031D01*
G03X251304Y34804I-274J291D01*
G02X253354Y34783I1035J946D01*
G03X253364Y34222I290J-275D01*
G02X253406Y32119I-1051J-1073D01*
G03Y31570I291J-275D01*
G02X253358Y29461I-1093J-1030D01*
G37*
G36*
G01X216547D02*
G03X216534Y28899I278J-288D01*
G02X214486Y28889I-1019J-963D01*
G03X214468Y29450I-293J271D01*
G02X214409Y31570I1034J1090D01*
G03Y32119I-291J274D01*
G02X214472Y34243I1093J1031D01*
G03X214493Y34804I-274J291D01*
G02X216543Y34783I1035J946D01*
G03X216553Y34222I290J-275D01*
G02X216595Y32119I-1051J-1073D01*
G03Y31570I291J-275D01*
G02X216547Y29461I-1093J-1030D01*
G37*
G36*
G01X179736D02*
G03X179723Y28899I278J-288D01*
G02X177675Y28889I-1019J-963D01*
G03X177657Y29450I-293J271D01*
G02X177598Y31570I1034J1090D01*
G03Y32119I-291J274D01*
G02X177661Y34243I1093J1031D01*
G03X177682Y34804I-274J291D01*
G02X179732Y34783I1035J946D01*
G03X179742Y34222I290J-275D01*
G02X179784Y32119I-1051J-1073D01*
G03Y31570I291J-275D01*
G02X179736Y29461I-1093J-1030D01*
G37*
G36*
G01X142925D02*
G03X142912Y28899I278J-288D01*
G02X140864Y28889I-1019J-963D01*
G03X140846Y29450I-293J271D01*
G02X140787Y31570I1034J1090D01*
G03Y32119I-291J274D01*
G02X140850Y34243I1093J1031D01*
G03X140871Y34804I-274J291D01*
G02X142921Y34783I1035J946D01*
G03X142931Y34222I290J-275D01*
G02X142973Y32119I-1051J-1073D01*
G03Y31570I291J-275D01*
G02X142925Y29461I-1093J-1030D01*
G37*
G36*
G01X652310Y19027D02*
G03Y18473I288J-277D01*
G02X650290I-1010J-973D01*
G03Y19027I-288J277D01*
G02X652310I1010J973D01*
G37*
G36*
G01X375354Y18434D02*
G03X375122Y17963I155J-369D01*
G02X373089Y18965I-1452J-383D01*
G03X373321Y19436I-155J369D01*
G02X375354Y18434I1452J383D01*
G37*
G36*
G01X450519Y16087D02*
G03X449939Y16068I-281J-285D01*
G02X449823Y18048I-1047J932D01*
G03X450401Y18097I266J299D01*
G02X450519Y16087I1172J-940D01*
G37*
G36*
G01X364276Y15953D02*
G03X363719Y15947I-275J-290D01*
G02X363697Y18103I-1057J1067D01*
G03X364254Y18109I275J290D01*
G02X364276Y15953I1057J-1067D01*
G37*
G36*
G01X596456Y13817D02*
G03X596470Y13234I281J-285D01*
G02X594470I-1000J-1120D01*
G03X594484Y13817I-267J298D01*
G02X596456I986J997D01*
G37*
G36*
G01X589763D02*
G03X589777Y13234I281J-285D01*
G02X587777I-1000J-1120D01*
G03X587791Y13817I-267J298D01*
G02X589763I986J997D01*
G37*
G36*
G01X572331D02*
G03X572345Y13234I281J-285D01*
G02X570345I-1000J-1120D01*
G03X570359Y13817I-267J298D01*
G02X572331I986J997D01*
G37*
G36*
G01X566039Y13782D02*
G03X566067Y13221I299J-266D01*
G02X563987Y13173I-1015J-1107D01*
G03X563989Y13734I-284J282D01*
G02X566039Y13782I1003J980D01*
G37*
G36*
G01X559645Y13817D02*
G03X559659Y13234I281J-285D01*
G02X557659I-1000J-1120D01*
G03X557673Y13817I-267J298D01*
G02X559645I986J997D01*
G37*
G36*
G01X552952D02*
G03X552966Y13234I281J-285D01*
G02X550966I-1000J-1120D01*
G03X550980Y13817I-267J298D01*
G02X552952I986J997D01*
G37*
G36*
G01X535520D02*
G03X535534Y13234I281J-285D01*
G02X533534I-1000J-1120D01*
G03X533548Y13817I-267J298D01*
G02X535520I986J997D01*
G37*
G36*
G01X529234Y13778D02*
G03X529261Y13217I298J-267D01*
G02X527180Y13177I-1020J-1103D01*
G03X527184Y13738I-283J283D01*
G02X529234Y13778I1006J976D01*
G37*
G36*
G01X522834Y13817D02*
G03X522848Y13234I281J-285D01*
G02X520848I-1000J-1120D01*
G03X520862Y13817I-267J298D01*
G02X522834I986J997D01*
G37*
G36*
G01X516141D02*
G03X516155Y13234I281J-285D01*
G02X514155I-1000J-1120D01*
G03X514169Y13817I-267J298D01*
G02X516141I986J997D01*
G37*
G36*
G01X498709D02*
G03X498723Y13234I281J-285D01*
G02X496723I-1000J-1120D01*
G03X496737Y13817I-267J298D01*
G02X498709I986J997D01*
G37*
G36*
G01X492423Y13778D02*
G03X492450Y13217I298J-267D01*
G02X490369Y13177I-1020J-1103D01*
G03X490373Y13738I-283J283D01*
G02X492423Y13778I1006J976D01*
G37*
G36*
G01X486023Y13817D02*
G03X486037Y13234I281J-285D01*
G02X484037I-1000J-1120D01*
G03X484051Y13817I-267J298D01*
G02X486023I986J997D01*
G37*
G36*
G01X479330D02*
G03X479344Y13234I281J-285D01*
G02X477344I-1000J-1120D01*
G03X477358Y13817I-267J298D01*
G02X479330I986J997D01*
G37*
G36*
G01X461898D02*
G03X461912Y13234I281J-285D01*
G02X459912I-1000J-1120D01*
G03X459926Y13817I-267J298D01*
G02X461898I986J997D01*
G37*
G36*
G01X455612Y13778D02*
G03X455639Y13217I298J-267D01*
G02X453558Y13177I-1020J-1103D01*
G03X453562Y13738I-283J283D01*
G02X455612Y13778I1006J976D01*
G37*
G36*
G01X305314Y13817D02*
G03X305328Y13234I281J-285D01*
G02X303328I-1000J-1120D01*
G03X303342Y13817I-267J298D01*
G02X305314I986J997D01*
G37*
G36*
G01X298621D02*
G03X298635Y13234I281J-285D01*
G02X296635I-1000J-1120D01*
G03X296649Y13817I-267J298D01*
G02X298621I986J997D01*
G37*
G36*
G01X281189D02*
G03X281203Y13234I281J-285D01*
G02X279203I-1000J-1120D01*
G03X279217Y13817I-267J298D01*
G02X281189I986J997D01*
G37*
G36*
G01X274903Y13778D02*
G03X274930Y13217I298J-267D01*
G02X272849Y13177I-1020J-1103D01*
G03X272853Y13738I-283J283D01*
G02X274903Y13778I1006J976D01*
G37*
G36*
G01X268503Y13817D02*
G03X268517Y13234I281J-285D01*
G02X266517I-1000J-1120D01*
G03X266531Y13817I-267J298D01*
G02X268503I986J997D01*
G37*
G36*
G01X261810D02*
G03X261824Y13234I281J-285D01*
G02X259824I-1000J-1120D01*
G03X259838Y13817I-267J298D01*
G02X261810I986J997D01*
G37*
G36*
G01X244378D02*
G03X244392Y13234I281J-285D01*
G02X242392I-1000J-1120D01*
G03X242406Y13817I-267J298D01*
G02X244378I986J997D01*
G37*
G36*
G01X238092Y13778D02*
G03X238119Y13217I298J-267D01*
G02X236038Y13177I-1020J-1103D01*
G03X236042Y13738I-283J283D01*
G02X238092Y13778I1006J976D01*
G37*
G36*
G01X231692Y13817D02*
G03X231706Y13234I281J-285D01*
G02X229706I-1000J-1120D01*
G03X229720Y13817I-267J298D01*
G02X231692I986J997D01*
G37*
G36*
G01X224999D02*
G03X225013Y13234I281J-285D01*
G02X223013I-1000J-1120D01*
G03X223027Y13817I-267J298D01*
G02X224999I986J997D01*
G37*
G36*
G01X207567D02*
G03X207581Y13234I281J-285D01*
G02X205581I-1000J-1120D01*
G03X205595Y13817I-267J298D01*
G02X207567I986J997D01*
G37*
G36*
G01X201281Y13778D02*
G03X201308Y13217I298J-267D01*
G02X199227Y13177I-1020J-1103D01*
G03X199231Y13738I-283J283D01*
G02X201281Y13778I1006J976D01*
G37*
G36*
G01X194881Y13817D02*
G03X194895Y13234I281J-285D01*
G02X192895I-1000J-1120D01*
G03X192909Y13817I-267J298D01*
G02X194881I986J997D01*
G37*
G36*
G01X188188D02*
G03X188202Y13234I281J-285D01*
G02X186202I-1000J-1120D01*
G03X186216Y13817I-267J298D01*
G02X188188I986J997D01*
G37*
G36*
G01X170756D02*
G03X170770Y13234I281J-285D01*
G02X168770I-1000J-1120D01*
G03X168784Y13817I-267J298D01*
G02X170756I986J997D01*
G37*
G36*
G01X164470Y13778D02*
G03X164497Y13217I298J-267D01*
G02X162416Y13177I-1020J-1103D01*
G03X162420Y13738I-283J283D01*
G02X164470Y13778I1006J976D01*
G37*
G36*
G01X158070Y13817D02*
G03X158084Y13234I281J-285D01*
G02X156084I-1000J-1120D01*
G03X156098Y13817I-267J298D01*
G02X158070I986J997D01*
G37*
G36*
G01X151377D02*
G03X151391Y13234I281J-285D01*
G02X149391I-1000J-1120D01*
G03X149405Y13817I-267J298D01*
G02X151377I986J997D01*
G37*
G36*
G01X133945D02*
G03X133959Y13234I281J-285D01*
G02X131959I-1000J-1120D01*
G03X131973Y13817I-267J298D01*
G02X133945I986J997D01*
G37*
G36*
G01X127659Y13778D02*
G03X127686Y13217I298J-267D01*
G02X125605Y13177I-1020J-1103D01*
G03X125609Y13738I-283J283D01*
G02X127659Y13778I1006J976D01*
G37*
G36*
G01X358463Y13303D02*
G03Y12725I277J-289D01*
G02X356521I-971J-1011D01*
G03Y13303I-277J289D01*
G02X358463I971J1011D01*
G37*
G36*
G01X449293Y12718D02*
G03X449294Y12156I285J-280D01*
G02X447213Y12209I-1068J-1056D01*
G03X447243Y12770I-269J296D01*
G02X449293Y12718I1049J930D01*
G37*
G36*
G01X581270Y10797D02*
G03X581239Y10233I267J-298D01*
G02X579200Y10291I-1047J-933D01*
G03X579201Y10855I-283J283D01*
G02X579170Y12941I1065J1059D01*
G03Y13487I-292J273D01*
G02X579225Y15597I1096J1027D01*
G03X579241Y16158I-277J289D01*
G02X581291I1025J956D01*
G03X581307Y15597I293J-272D01*
G02X581362Y13487I-1041J-1083D01*
G03Y12941I292J-273D01*
G02X581270Y10797I-1096J-1027D01*
G37*
G36*
G01X544474Y10810D02*
G03X544450Y10246I271J-294D01*
G02X542410Y10277I-1035J-946D01*
G03X542403Y10842I-287J279D01*
G02X542359Y12941I1052J1072D01*
G03Y13487I-292J273D01*
G02X542414Y15597I1096J1027D01*
G03X542430Y16158I-277J289D01*
G02X544480I1025J956D01*
G03X544496Y15597I293J-272D01*
G02X544551Y13487I-1041J-1083D01*
G03Y12941I292J-273D01*
G02X544474Y10810I-1096J-1027D01*
G37*
G36*
G01X507663D02*
G03X507639Y10246I271J-294D01*
G02X505599Y10277I-1035J-946D01*
G03X505592Y10842I-287J279D01*
G02X505548Y12941I1052J1072D01*
G03Y13487I-292J273D01*
G02X505603Y15597I1096J1027D01*
G03X505619Y16158I-277J289D01*
G02X507669I1025J956D01*
G03X507685Y15597I293J-272D01*
G02X507740Y13487I-1041J-1083D01*
G03Y12941I292J-273D01*
G02X507663Y10810I-1096J-1027D01*
G37*
G36*
G01X470851D02*
G03X470827Y10246I271J-294D01*
G02X468787Y10277I-1035J-946D01*
G03X468780Y10842I-287J279D01*
G02X468736Y12941I1052J1072D01*
G03Y13487I-292J273D01*
G02X468791Y15597I1096J1027D01*
G03X468807Y16158I-277J289D01*
G02X470857I1025J956D01*
G03X470873Y15597I293J-272D01*
G02X470928Y13487I-1041J-1083D01*
G03Y12941I292J-273D01*
G02X470851Y10810I-1096J-1027D01*
G37*
G36*
G01X290064Y10743D02*
G03X290045Y10136I251J-312D01*
G02X288173Y10151I-944J-1036D01*
G03X288164Y10759I-265J300D01*
G02X288028Y12941I960J1155D01*
G03Y13487I-292J273D01*
G02X288083Y15597I1096J1027D01*
G03X288099Y16158I-277J289D01*
G02X290149I1025J956D01*
G03X290165Y15597I293J-272D01*
G02X290220Y13487I-1041J-1083D01*
G03Y12941I292J-273D01*
G02X290064Y10743I-1096J-1027D01*
G37*
G36*
G01X253253D02*
G03X253234Y10136I251J-312D01*
G02X251362Y10151I-944J-1036D01*
G03X251353Y10759I-265J300D01*
G02X251217Y12941I960J1155D01*
G03Y13487I-292J273D01*
G02X251272Y15597I1096J1027D01*
G03X251288Y16158I-277J289D01*
G02X253338I1025J956D01*
G03X253354Y15597I293J-272D01*
G02X253409Y13487I-1041J-1083D01*
G03Y12941I292J-273D01*
G02X253253Y10743I-1096J-1027D01*
G37*
G36*
G01X216442D02*
G03X216423Y10136I251J-312D01*
G02X214551Y10151I-944J-1036D01*
G03X214542Y10759I-265J300D01*
G02X214406Y12941I960J1155D01*
G03Y13487I-292J273D01*
G02X214461Y15597I1096J1027D01*
G03X214477Y16158I-277J289D01*
G02X216527I1025J956D01*
G03X216543Y15597I293J-272D01*
G02X216598Y13487I-1041J-1083D01*
G03Y12941I292J-273D01*
G02X216442Y10743I-1096J-1027D01*
G37*
G36*
G01X179631D02*
G03X179612Y10136I251J-312D01*
G02X177740Y10151I-944J-1036D01*
G03X177731Y10759I-265J300D01*
G02X177595Y12941I960J1155D01*
G03Y13487I-292J273D01*
G02X177650Y15597I1096J1027D01*
G03X177666Y16158I-277J289D01*
G02X179716I1025J956D01*
G03X179732Y15597I293J-272D01*
G02X179787Y13487I-1041J-1083D01*
G03Y12941I292J-273D01*
G02X179631Y10743I-1096J-1027D01*
G37*
G36*
G01X142820D02*
G03X142801Y10136I251J-312D01*
G02X140929Y10151I-944J-1036D01*
G03X140920Y10759I-265J300D01*
G02X140784Y12941I960J1155D01*
G03Y13487I-292J273D01*
G02X140839Y15597I1096J1027D01*
G03X140855Y16158I-277J289D01*
G02X142905I1025J956D01*
G03X142921Y15597I293J-272D01*
G02X142976Y13487I-1041J-1083D01*
G03Y12941I292J-273D01*
G02X142820Y10743I-1096J-1027D01*
G37*
G36*
G01X576206Y10616D02*
G03X576191Y10055I277J-288D01*
G02X574141I-1025J-957D01*
G03X574126Y10616I-292J273D01*
G02X574070Y12727I1040J1084D01*
G03Y13273I-292J273D01*
G02X574132Y15389I1096J1027D01*
G03X574151Y15950I-275J290D01*
G02X576202Y15938I1031J950D01*
G03X576213Y15376I290J-275D01*
G02X576262Y13273I-1047J-1076D01*
G03Y12727I292J-273D01*
G02X576206Y10616I-1096J-1027D01*
G37*
G36*
G01X539395D02*
G03X539380Y10055I277J-288D01*
G02X537330I-1025J-957D01*
G03X537315Y10616I-292J273D01*
G02X537259Y12727I1040J1084D01*
G03Y13273I-292J273D01*
G02X537298Y15367I1096J1027D01*
G03X537304Y15928I-282J284D01*
G02X539355Y15960I1011J972D01*
G03X539379Y15399I297J-268D01*
G02X539451Y13273I-1024J-1099D01*
G03Y12727I292J-273D01*
G02X539395Y10616I-1096J-1027D01*
G37*
G36*
G01X502584D02*
G03X502569Y10055I277J-288D01*
G02X500519I-1025J-957D01*
G03X500504Y10616I-292J273D01*
G02X500448Y12727I1040J1084D01*
G03Y13273I-292J273D01*
G02X500487Y15367I1096J1027D01*
G03X500493Y15928I-282J284D01*
G02X502544Y15960I1011J972D01*
G03X502568Y15399I297J-268D01*
G02X502640Y13273I-1024J-1099D01*
G03Y12727I292J-273D01*
G02X502584Y10616I-1096J-1027D01*
G37*
G36*
G01X465772D02*
G03X465757Y10055I277J-288D01*
G02X463707I-1025J-957D01*
G03X463692Y10616I-292J273D01*
G02X463636Y12727I1040J1084D01*
G03Y13273I-292J273D01*
G02X463675Y15367I1096J1027D01*
G03X463681Y15928I-282J284D01*
G02X465732Y15960I1011J972D01*
G03X465756Y15399I297J-268D01*
G02X465828Y13273I-1024J-1099D01*
G03Y12727I292J-273D01*
G02X465772Y10616I-1096J-1027D01*
G37*
G36*
G01X285064D02*
G03X285049Y10055I277J-288D01*
G02X282999I-1025J-957D01*
G03X282984Y10616I-292J273D01*
G02X282928Y12727I1040J1084D01*
G03Y13273I-292J273D01*
G02X282973Y15373I1096J1027D01*
G03X282983Y15935I-280J286D01*
G02X285034Y15953I1017J965D01*
G03X285055Y15392I295J-270D01*
G02X285120Y13273I-1031J-1092D01*
G03Y12727I292J-273D01*
G02X285064Y10616I-1096J-1027D01*
G37*
G36*
G01X248253D02*
G03X248238Y10055I277J-288D01*
G02X246188I-1025J-957D01*
G03X246173Y10616I-292J273D01*
G02X246117Y12727I1040J1084D01*
G03Y13273I-292J273D01*
G02X246162Y15373I1096J1027D01*
G03X246172Y15935I-280J286D01*
G02X248223Y15953I1017J965D01*
G03X248244Y15392I295J-270D01*
G02X248309Y13273I-1031J-1092D01*
G03Y12727I292J-273D01*
G02X248253Y10616I-1096J-1027D01*
G37*
G36*
G01X211442D02*
G03X211427Y10055I277J-288D01*
G02X209377I-1025J-957D01*
G03X209362Y10616I-292J273D01*
G02X209306Y12727I1040J1084D01*
G03Y13273I-292J273D01*
G02X209351Y15373I1096J1027D01*
G03X209361Y15935I-280J286D01*
G02X211412Y15953I1017J965D01*
G03X211433Y15392I295J-270D01*
G02X211498Y13273I-1031J-1092D01*
G03Y12727I292J-273D01*
G02X211442Y10616I-1096J-1027D01*
G37*
G36*
G01X174631D02*
G03X174616Y10055I277J-288D01*
G02X172566I-1025J-957D01*
G03X172551Y10616I-292J273D01*
G02X172495Y12727I1040J1084D01*
G03Y13273I-292J273D01*
G02X172540Y15373I1096J1027D01*
G03X172550Y15935I-280J286D01*
G02X174601Y15953I1017J965D01*
G03X174622Y15392I295J-270D01*
G02X174687Y13273I-1031J-1092D01*
G03Y12727I292J-273D01*
G02X174631Y10616I-1096J-1027D01*
G37*
G36*
G01X137820D02*
G03X137805Y10055I277J-288D01*
G02X135755I-1025J-957D01*
G03X135740Y10616I-292J273D01*
G02X135684Y12727I1040J1084D01*
G03Y13273I-292J273D01*
G02X135729Y15373I1096J1027D01*
G03X135739Y15935I-280J286D01*
G02X137790Y15953I1017J965D01*
G03X137811Y15392I295J-270D01*
G02X137876Y13273I-1031J-1092D01*
G03Y12727I292J-273D01*
G02X137820Y10616I-1096J-1027D01*
G37*
G36*
G01X115148Y5044D02*
G03X115127Y4493I279J-287D01*
G02X112952Y4576I-1127J-993D01*
G03X112973Y5127I-279J287D01*
G02X115148Y5044I1127J993D01*
G37*
G36*
G01X70101Y-2447D02*
G03X69547I-277J-288D01*
G02X67616Y-414I-973J1009D01*
G03X67624Y162I-274J292D01*
G02X69584Y2168I987J996D01*
G03X70138I277J288D01*
G02X72084I973J-1010D01*
G03X72638I277J288D01*
G02X74625Y2126I973J-1010D01*
G03X75210Y2133I289J276D01*
G02X77183Y146I1037J-943D01*
G03X77165Y-432I267J-298D01*
G02X75165Y-2398I-1000J-983D01*
G03X74590Y-2403I-285J-280D01*
G02X72601Y-2447I-1016J966D01*
G03X72047I-277J-288D01*
G02X70101I-973J1010D01*
G37*
G36*
G01X624830Y-2141D02*
G03X624458Y-2637I16J-399D01*
G02X622940Y-1499I-1458J-363D01*
G03X623312Y-1003I-16J399D01*
G02X624830Y-2141I1458J363D01*
G37*
G36*
G01X285091Y-8133D02*
G03X285075Y-8694I277J-289D01*
G02X283025I-1025J-956D01*
G03X283009Y-8133I-293J272D01*
G02X282962Y-6015I1041J1083D01*
G03X282956Y-5458I-290J275D01*
G02X282983Y-3318I1068J1057D01*
G03X282999Y-2757I-277J289D01*
G02X285049I1025J956D01*
G03X285065Y-3318I293J-272D01*
G02X285112Y-5436I-1041J-1083D01*
G03X285118Y-5993I290J-275D01*
G02X285091Y-8133I-1068J-1057D01*
G37*
G36*
G01X248280D02*
G03X248264Y-8694I277J-289D01*
G02X246214I-1025J-956D01*
G03X246198Y-8133I-293J272D01*
G02X246151Y-6015I1041J1083D01*
G03X246145Y-5458I-290J275D01*
G02X246172Y-3318I1068J1057D01*
G03X246188Y-2757I-277J289D01*
G02X248238I1025J956D01*
G03X248254Y-3318I293J-272D01*
G02X248301Y-5436I-1041J-1083D01*
G03X248307Y-5993I290J-275D01*
G02X248280Y-8133I-1068J-1057D01*
G37*
G36*
G01X211469D02*
G03X211453Y-8694I277J-289D01*
G02X209403I-1025J-956D01*
G03X209387Y-8133I-293J272D01*
G02X209340Y-6015I1041J1083D01*
G03X209334Y-5458I-290J275D01*
G02X209361Y-3318I1068J1057D01*
G03X209377Y-2757I-277J289D01*
G02X211427I1025J956D01*
G03X211443Y-3318I293J-272D01*
G02X211490Y-5436I-1041J-1083D01*
G03X211496Y-5993I290J-275D01*
G02X211469Y-8133I-1068J-1057D01*
G37*
G36*
G01X174658D02*
G03X174642Y-8694I277J-289D01*
G02X172592I-1025J-956D01*
G03X172576Y-8133I-293J272D01*
G02X172529Y-6015I1041J1083D01*
G03X172523Y-5458I-290J275D01*
G02X172550Y-3318I1068J1057D01*
G03X172566Y-2757I-277J289D01*
G02X174616I1025J956D01*
G03X174632Y-3318I293J-272D01*
G02X174679Y-5436I-1041J-1083D01*
G03X174685Y-5993I290J-275D01*
G02X174658Y-8133I-1068J-1057D01*
G37*
G36*
G01X137847D02*
G03X137831Y-8694I277J-289D01*
G02X135781I-1025J-956D01*
G03X135765Y-8133I-293J272D01*
G02X135718Y-6015I1041J1083D01*
G03X135712Y-5458I-290J275D01*
G02X135739Y-3318I1068J1057D01*
G03X135755Y-2757I-277J289D01*
G02X137805I1025J956D01*
G03X137821Y-3318I293J-272D01*
G02X137868Y-5436I-1041J-1083D01*
G03X137874Y-5993I290J-275D01*
G02X137847Y-8133I-1068J-1057D01*
G37*
G36*
G01X465798Y-8134D02*
G03X465783Y-8695I277J-288D01*
G02X463733I-1025J-957D01*
G03X463718Y-8134I-292J273D01*
G02X463670Y-6015I1040J1084D01*
G03X463664Y-5458I-290J275D01*
G02X463691Y-3318I1068J1057D01*
G03X463707Y-2757I-277J289D01*
G02X465757I1025J956D01*
G03X465773Y-3318I293J-272D01*
G02X465820Y-5436I-1041J-1083D01*
G03X465826Y-5993I290J-275D01*
G02X465798Y-8134I-1068J-1057D01*
G37*
G36*
G01X576222Y-8143D02*
G03X576212Y-8715I274J-291D01*
G02X574200Y-8732I-998J-985D01*
G03X574180Y-8160I-289J276D01*
G02X574104Y-6015I1012J1110D01*
G03X574098Y-5458I-290J275D01*
G02X574125Y-3318I1068J1057D01*
G03X574141Y-2757I-277J289D01*
G02X576191I1025J956D01*
G03X576207Y-3318I293J-272D01*
G02X576254Y-5436I-1041J-1083D01*
G03X576260Y-5993I290J-275D01*
G02X576222Y-8143I-1068J-1056D01*
G37*
G36*
G01X539411D02*
G03X539401Y-8715I274J-291D01*
G02X537389Y-8732I-998J-985D01*
G03X537369Y-8160I-289J276D01*
G02X537293Y-6015I1012J1110D01*
G03X537287Y-5458I-290J275D01*
G02X537314Y-3318I1068J1057D01*
G03X537330Y-2757I-277J289D01*
G02X539380I1025J956D01*
G03X539396Y-3318I293J-272D01*
G02X539443Y-5436I-1041J-1083D01*
G03X539449Y-5993I290J-275D01*
G02X539411Y-8143I-1068J-1056D01*
G37*
G36*
G01X502600D02*
G03X502590Y-8715I274J-291D01*
G02X500578Y-8732I-998J-985D01*
G03X500558Y-8160I-289J276D01*
G02X500482Y-6015I1012J1110D01*
G03X500476Y-5458I-290J275D01*
G02X500503Y-3318I1068J1057D01*
G03X500519Y-2757I-277J289D01*
G02X502569I1025J956D01*
G03X502585Y-3318I293J-272D01*
G02X502632Y-5436I-1041J-1083D01*
G03X502638Y-5993I290J-275D01*
G02X502600Y-8143I-1068J-1056D01*
G37*
G36*
G01X581311Y-8339D02*
G03X581298Y-8901I278J-288D01*
G02X579250Y-8911I-1019J-963D01*
G03X579232Y-8350I-293J271D01*
G02X579173Y-6230I1034J1090D01*
G03Y-5681I-291J274D01*
G02X579266Y-3531I1093J1030D01*
G03X579291Y-2959I-267J298D01*
G02X581302Y-2995I1023J959D01*
G03X581306Y-3568I281J-285D01*
G02X581359Y-5681I-1040J-1083D01*
G03Y-6230I291J-274D01*
G02X581311Y-8339I-1093J-1030D01*
G37*
G36*
G01X544500D02*
G03X544487Y-8901I278J-288D01*
G02X542439Y-8911I-1019J-963D01*
G03X542421Y-8350I-293J271D01*
G02X542362Y-6230I1034J1090D01*
G03Y-5681I-291J274D01*
G02X542455Y-3531I1093J1030D01*
G03X542480Y-2959I-267J298D01*
G02X544491Y-2995I1023J959D01*
G03X544495Y-3568I281J-285D01*
G02X544548Y-5681I-1040J-1083D01*
G03Y-6230I291J-274D01*
G02X544500Y-8339I-1093J-1030D01*
G37*
G36*
G01X507689D02*
G03X507676Y-8901I278J-288D01*
G02X505628Y-8911I-1019J-963D01*
G03X505610Y-8350I-293J271D01*
G02X505551Y-6230I1034J1090D01*
G03Y-5681I-291J274D01*
G02X505644Y-3531I1093J1030D01*
G03X505669Y-2959I-267J298D01*
G02X507680Y-2995I1023J959D01*
G03X507684Y-3568I281J-285D01*
G02X507737Y-5681I-1040J-1083D01*
G03Y-6230I291J-274D01*
G02X507689Y-8339I-1093J-1030D01*
G37*
G36*
G01X470877D02*
G03X470864Y-8901I278J-288D01*
G02X468816Y-8911I-1019J-963D01*
G03X468798Y-8350I-293J271D01*
G02X468739Y-6230I1034J1090D01*
G03Y-5681I-291J274D01*
G02X468791Y-3568I1093J1030D01*
G03X468807Y-3007I-277J289D01*
G02X470857I1025J956D01*
G03X470873Y-3568I293J-272D01*
G02X470925Y-5681I-1041J-1083D01*
G03Y-6230I291J-274D01*
G02X470877Y-8339I-1093J-1030D01*
G37*
G36*
G01X290169D02*
G03X290156Y-8901I278J-288D01*
G02X288108Y-8911I-1019J-963D01*
G03X288090Y-8350I-293J271D01*
G02X288031Y-6230I1034J1090D01*
G03Y-5681I-291J274D01*
G02X288094Y-3557I1093J1031D01*
G03X288115Y-2996I-274J291D01*
G02X290165Y-3017I1035J946D01*
G03X290175Y-3578I290J-275D01*
G02X290217Y-5681I-1051J-1073D01*
G03Y-6230I291J-274D01*
G02X290169Y-8339I-1093J-1030D01*
G37*
G36*
G01X253358D02*
G03X253345Y-8901I278J-288D01*
G02X251297Y-8911I-1019J-963D01*
G03X251279Y-8350I-293J271D01*
G02X251220Y-6230I1034J1090D01*
G03Y-5681I-291J274D01*
G02X251283Y-3557I1093J1031D01*
G03X251304Y-2996I-274J291D01*
G02X253354Y-3017I1035J946D01*
G03X253364Y-3578I290J-275D01*
G02X253406Y-5681I-1051J-1073D01*
G03Y-6230I291J-274D01*
G02X253358Y-8339I-1093J-1030D01*
G37*
G36*
G01X216547D02*
G03X216534Y-8901I278J-288D01*
G02X214486Y-8911I-1019J-963D01*
G03X214468Y-8350I-293J271D01*
G02X214409Y-6230I1034J1090D01*
G03Y-5681I-291J274D01*
G02X214472Y-3557I1093J1031D01*
G03X214493Y-2996I-274J291D01*
G02X216543Y-3017I1035J946D01*
G03X216553Y-3578I290J-275D01*
G02X216595Y-5681I-1051J-1073D01*
G03Y-6230I291J-274D01*
G02X216547Y-8339I-1093J-1030D01*
G37*
G36*
G01X179736D02*
G03X179723Y-8901I278J-288D01*
G02X177675Y-8911I-1019J-963D01*
G03X177657Y-8350I-293J271D01*
G02X177598Y-6230I1034J1090D01*
G03Y-5681I-291J274D01*
G02X177661Y-3557I1093J1031D01*
G03X177682Y-2996I-274J291D01*
G02X179732Y-3017I1035J946D01*
G03X179742Y-3578I290J-275D01*
G02X179784Y-5681I-1051J-1073D01*
G03Y-6230I291J-274D01*
G02X179736Y-8339I-1093J-1030D01*
G37*
G36*
G01X142925D02*
G03X142912Y-8901I278J-288D01*
G02X140864Y-8911I-1019J-963D01*
G03X140846Y-8350I-293J271D01*
G02X140787Y-6230I1034J1090D01*
G03Y-5681I-291J274D01*
G02X140850Y-3557I1093J1031D01*
G03X140871Y-2996I-274J291D01*
G02X142921Y-3017I1035J946D01*
G03X142931Y-3578I290J-275D01*
G02X142973Y-5681I-1051J-1073D01*
G03Y-6230I291J-274D01*
G02X142925Y-8339I-1093J-1030D01*
G37*
G36*
G01X80729Y-12405D02*
G03X80175I-277J-288D01*
G02Y-10385I-973J1010D01*
G03X80729I277J288D01*
G02X82675I973J-1010D01*
G03X83229I277J288D01*
G02Y-12405I973J-1010D01*
G03X82675I-277J-288D01*
G02X80729I-973J1010D01*
G37*
G36*
G01X648096Y-10527D02*
G03Y-11073I292J-273D01*
G02X645904I-1096J-1027D01*
G03Y-10527I-292J273D01*
G02X646086Y-8308I1096J1027D01*
G03X646170Y-7762I-244J317D01*
G02X648314Y-8092I1230J862D01*
G03X648230Y-8638I244J-317D01*
G02X648096Y-10527I-1230J-862D01*
G37*
G36*
G01X81211Y-17483D02*
G03X80589I-311J-252D01*
G02Y-15717I-1089J883D01*
G03X81211I311J252D01*
G02Y-17483I1089J-883D01*
G37*
G36*
G01X606831Y91885D02*
G02Y93313I-1321J714D01*
G03X607535I352J191D01*
G02X610178I1321J-714D01*
G03X610881I352J190D01*
G02X613524I1321J-714D01*
G03X614228I352J191D01*
G02Y91885I1321J-714D01*
G03X613524I-352J-191D01*
G02X610881I-1321J714D01*
G03X610178I-352J-190D01*
G02X607535I-1321J714D01*
G03X606831I-352J-191D01*
G37*
G36*
G01X450568Y85691D02*
G02X450273Y84189I1005J-977D01*
G03X449615Y84319I-371J-149D01*
G02X449910Y85821I-1005J977D01*
G03X450568Y85691I371J149D01*
G37*
G36*
G01X603485Y84043D02*
G02Y85471I-1322J714D01*
G03X604188I351J190D01*
G02X606831I1322J-714D01*
G03X607535I352J191D01*
G02X610178I1321J-714D01*
G03X610881I352J190D01*
G02X613524I1321J-714D01*
G03X614228I352J191D01*
G02Y84043I1321J-714D01*
G03X613524I-352J-191D01*
G02X610881I-1321J714D01*
G03X610178I-352J-190D01*
G02X607535I-1321J714D01*
G03X606831I-352J-191D01*
G02X604188I-1321J714D01*
G03X603485I-352J-190D01*
G37*
G36*
G01X100054Y84670D02*
G02X98641Y83270I86J-1500D01*
G03X98022Y83630I-399J26D01*
G02X99700Y85293I-3339J5048D01*
G03X100054Y84670I331J-224D01*
G37*
G36*
G01X96484Y77755D02*
G02X93632Y77689I-1443J696D01*
G03X92932Y77695I-352J-191D01*
G02X92945Y79243I-1396J786D01*
G03X93645Y79237I352J191D01*
G02X96472Y79171I1396J-786D01*
G03X97190Y79177I358J179D01*
G02X97202Y77761I1443J-696D01*
G03X96484Y77755I-358J-179D01*
G37*
G36*
G01X375007Y75306D02*
G02X373577I-715J-1206D01*
G03Y75994I-204J344D01*
G02X375007I715J1206D01*
G03Y75306I204J-344D01*
G37*
G36*
G01X603485Y73143D02*
G02Y74571I-1322J714D01*
G03X604188I351J190D01*
G02X606831I1322J-714D01*
G03X607535I352J191D01*
G02X610178I1321J-714D01*
G03X610881I352J190D01*
G02X613524I1321J-714D01*
G03X614228I352J191D01*
G02Y73143I1321J-714D01*
G03X613524I-352J-191D01*
G02X610881I-1321J714D01*
G03X610178I-352J-190D01*
G02X607535I-1321J714D01*
G03X606831I-352J-191D01*
G02X604188I-1321J714D01*
G03X603485I-352J-190D01*
G37*
G36*
G01X116770Y71668D02*
G02X115465Y71581I-570J-1281D01*
G03X115408Y72291I-210J340D01*
G02X116732Y72380I572J1389D01*
G03X116770Y71668I200J-346D01*
G37*
G36*
G01X449516Y69174D02*
G02X447757Y69189I-889J-1084D01*
G03X447762Y69812I-249J314D01*
G02X447699Y71926I889J1084D01*
G03X447688Y72523I-271J294D01*
G02X449700Y74456I910J1066D01*
G03X450361Y74503I315J248D01*
G02X450472Y72932I1212J-704D01*
G03X449811Y72885I-315J-248D01*
G02X449551Y72559I-1214J702D01*
G03X449562Y71962I271J-294D01*
G02X449521Y69797I-911J-1066D01*
G03X449516Y69174I249J-314D01*
G37*
G36*
G01X606831Y64985D02*
G02Y66413I-1321J714D01*
G03X607535I352J191D01*
G02X610178I1321J-714D01*
G03X610881I352J190D01*
G02X613524I1321J-714D01*
G03X614228I352J191D01*
G02Y64985I1321J-714D01*
G03X613524I-352J-191D01*
G02X610881I-1321J714D01*
G03X610178I-352J-190D01*
G02X607535I-1321J714D01*
G03X606831I-352J-191D01*
G37*
G36*
G01X362540Y54128D02*
G02Y55556I-1322J714D01*
G03X363243I352J190D01*
G02Y54128I1322J-714D01*
G03X362540I-351J-190D01*
G37*
G36*
G01X603485Y54085D02*
G02X600829Y54108I-1322J714D01*
G03X600126Y54120I-355J-184D01*
G02X600151Y55548I-1309J737D01*
G03X600854Y55536I355J184D01*
G02X603485Y55513I1309J-737D01*
G03X604188I351J190D01*
G02X606831I1322J-714D01*
G03X607535I352J191D01*
G02X610178I1321J-714D01*
G03X610881I352J190D01*
G02X613524I1321J-714D01*
G03X614228I352J191D01*
G02Y54085I1321J-714D01*
G03X613524I-352J-191D01*
G02X610881I-1321J714D01*
G03X610178I-352J-190D01*
G02X607535I-1321J714D01*
G03X606831I-352J-191D01*
G02X604188I-1321J714D01*
G03X603485I-352J-190D01*
G37*
G36*
G01X566047Y51039D02*
G02X564304Y51217I-995J-1125D01*
G03X564382Y51852I-199J347D01*
G02X566099Y51677I971J1012D01*
G03X566047Y51039I213J-338D01*
G37*
G36*
G01X455482Y50793D02*
G02X453715Y50763I-863J-1229D01*
G03X453717Y51400I-241J319D01*
G02X455458Y51430I852J1114D01*
G03X455482Y50793I254J-309D01*
G37*
G36*
G01X450402Y47672D02*
G02X450366Y46187I1171J-771D01*
G03X449688Y46203I-344J-204D01*
G02X449724Y47688I-1171J771D01*
G03X450402Y47672I344J204D01*
G37*
G36*
G01X603485Y46243D02*
G02Y47671I-1322J714D01*
G03X604188I351J190D01*
G02X606831I1322J-714D01*
G03X607535I352J191D01*
G02X610178I1321J-714D01*
G03X610881I352J190D01*
G02X613524I1321J-714D01*
G03X614228I352J191D01*
G02Y46243I1321J-714D01*
G03X613524I-352J-191D01*
G02X610881I-1321J714D01*
G03X610178I-352J-190D01*
G02X607535I-1321J714D01*
G03X606831I-352J-191D01*
G02X604188I-1321J714D01*
G03X603485I-352J-190D01*
G37*
G36*
G01Y35343D02*
G02Y36771I-1322J714D01*
G03X604188I351J190D01*
G02X606831I1322J-714D01*
G03X607535I352J191D01*
G02X610178I1321J-714D01*
G03X610881I352J190D01*
G02X613524I1321J-714D01*
G03X614228I352J191D01*
G02Y35343I1321J-714D01*
G03X613524I-352J-191D01*
G02X610881I-1321J714D01*
G03X610178I-352J-190D01*
G02X607535I-1321J714D01*
G03X606831I-352J-191D01*
G02X604188I-1321J714D01*
G03X603485I-352J-190D01*
G37*
G36*
G01X362540Y35228D02*
G02Y36656I-1322J714D01*
G03X363243I352J190D01*
G02Y35228I1322J-714D01*
G03X362540I-351J-190D01*
G37*
G36*
G01X449693Y35187D02*
G02X449593Y36520I-1279J574D01*
G03X450294Y36573I336J217D01*
G02X450394Y35240I1279J-574D01*
G03X449693Y35187I-336J-217D01*
G37*
G36*
G01X603485Y27185D02*
G02Y28613I-1322J714D01*
G03X604188I351J190D01*
G02X606831I1322J-714D01*
G03X607535I352J191D01*
G02X610178I1321J-714D01*
G03X610881I352J190D01*
G02X613524I1321J-714D01*
G03X614228I352J191D01*
G02Y27185I1321J-714D01*
G03X613524I-352J-191D01*
G02X610881I-1321J714D01*
G03X610178I-352J-190D01*
G02X607535I-1321J714D01*
G03X606831I-352J-191D01*
G02X604188I-1321J714D01*
G03X603485I-352J-190D01*
G37*
G36*
G01X381635Y26053D02*
G02X379949I-843J-1120D01*
G03Y26692I-241J320D01*
G02X381635I843J1120D01*
G03Y26053I241J-320D01*
G37*
G36*
G01X606831Y16285D02*
G02Y17713I-1321J714D01*
G03X607535I352J191D01*
G02X610178I1321J-714D01*
G03X610881I352J190D01*
G02X613524I1321J-714D01*
G03X614228I352J191D01*
G02Y16285I1321J-714D01*
G03X613524I-352J-191D01*
G02X610881I-1321J714D01*
G03X610178I-352J-190D01*
G02X607535I-1321J714D01*
G03X606831I-352J-191D01*
G37*
G36*
G01X603485Y8443D02*
G02Y9871I-1322J714D01*
G03X604188I351J190D01*
G02X606831I1322J-714D01*
G03X607535I352J191D01*
G02X610178I1321J-714D01*
G03X610881I352J190D01*
G02X613524I1321J-714D01*
G03X614228I352J191D01*
G02Y8443I1321J-714D01*
G03X613524I-352J-191D01*
G02X610881I-1321J714D01*
G03X610178I-352J-190D01*
G02X607535I-1321J714D01*
G03X606831I-352J-191D01*
G02X604188I-1321J714D01*
G03X603485I-352J-190D01*
G37*
G36*
G01X362540Y8400D02*
G02Y9828I-1322J714D01*
G03X363243I352J190D01*
G02Y8400I1322J-714D01*
G03X362540I-351J-190D01*
G37*
G36*
G01X649601Y7476D02*
G02X647633Y9740I-1051J1074D01*
G03X647622Y10381I-244J316D01*
G02X649485Y12734I879J1218D01*
G03X650031Y12755I262J302D01*
G02X651998Y10496I1069J-1055D01*
G03Y9854I239J-321D01*
G02X650137Y7498I-898J-1204D01*
G03X649601Y7476I-256J-307D01*
G37*
G36*
G01X376959Y5723D02*
G02Y7277I-1167J777D01*
G03X377625I333J222D01*
G02Y5723I1167J-777D01*
G03X376959I-333J-222D01*
G37*
G36*
G01X603485Y-2457D02*
G02Y-1029I-1322J714D01*
G03X604188I351J190D01*
G02X606831I1322J-714D01*
G03X607535I352J191D01*
G02X610178I1321J-714D01*
G03X610881I352J190D01*
G02X613524I1321J-714D01*
G03X614228I352J191D01*
G02Y-2457I1321J-714D01*
G03X613524I-352J-191D01*
G02X610881I-1321J714D01*
G03X610178I-352J-190D01*
G02X607535I-1321J714D01*
G03X606831I-352J-191D01*
G02X604188I-1321J714D01*
G03X603485I-352J-190D01*
G37*
G36*
G01X362540Y-2572D02*
G02Y-1144I-1322J714D01*
G03X363243I352J190D01*
G02Y-2572I1322J-714D01*
G03X362540I-351J-190D01*
G37*
G36*
G01Y-10500D02*
G02Y-9072I-1322J714D01*
G03X363243I352J190D01*
G02Y-10500I1322J-714D01*
G03X362540I-351J-190D01*
G37*
G36*
G01X606831Y-10615D02*
G02Y-9187I-1321J714D01*
G03X607535I352J191D01*
G02X610178I1321J-714D01*
G03X610881I352J190D01*
G02X613524I1321J-714D01*
G03X614228I352J191D01*
G02Y-10615I1321J-714D01*
G03X613524I-352J-191D01*
G02X610881I-1321J714D01*
G03X610178I-352J-190D01*
G02X607535I-1321J714D01*
G03X606831I-352J-191D01*
G37*
G36*
G01X375810Y-11867D02*
G02X375602Y-10444I-1409J521D01*
G03X376292Y-10354I320J240D01*
G02X378626Y-9933I1300J-526D01*
G03X379212Y-9938I295J270D01*
G02X379198Y-11847I1020J-962D01*
G03X378612Y-11842I-295J-270D01*
G02X376497Y-11756I-1020J962D01*
G03X375810Y-11867I-312J-250D01*
G37*
G36*
G01X99328Y-10626D02*
G02X97720Y-11775I-226J-1384D01*
G03X97162Y-11343I-394J67D01*
G02X90822Y-10483I-2479J5521D01*
G03X90170Y-10745I-255J-308D01*
G02X88916Y-9191I-1393J159D01*
G03X89311Y-8609I40J398D01*
G02X99101Y-9958I5372J2787D01*
G03X99328Y-10626I292J-273D01*
G37*
G36*
G01X72453Y-19271D02*
G02X72429Y-17664I-1281J785D01*
G03X73105Y-17654I335J219D01*
G02X73129Y-19261I1281J-785D01*
G03X72453Y-19271I-335J-219D01*
G37*
G36*
G01X108874Y392919D02*
G03X108274I-300J-265D01*
G02Y394777I-1050J929D01*
G03X108874I300J265D01*
G02Y392919I1050J-929D01*
G37*
G36*
G01X118570Y384194D02*
G02X116059Y379642I59J-3001D01*
G02X115807Y385639I-59J3001D01*
G02X118364Y384493I1256J-622D01*
G02X118570Y384194I-2364J-1849D01*
G37*
G36*
G01X124461Y379637D02*
G03X124474Y380166I-293J272D01*
G02X124492Y382120I1150J966D01*
G03Y382646I-302J263D01*
G02X126756I1132J987D01*
G03Y382120I302J-263D01*
G02X126726Y380112I-1132J-987D01*
G03X126713Y379583I293J-272D01*
G02X126837Y379411I-1153J-962D01*
G03X127182Y379421I170J106D01*
G02X127368Y377713I1318J-721D01*
G03X126750Y377696I-302J-262D01*
G02X124461Y379637I-1187J920D01*
G37*
G36*
G01X121407Y373181D02*
G03X121446Y373762I-254J309D01*
G02X123366Y373635I1027J954D01*
G03X123327Y373054I254J-309D01*
G02X121407Y373181I-1027J-954D01*
G37*
G36*
G01X127135Y345549D02*
G03X126602Y345531I-256J-307D01*
G02X124461Y347637I-1039J1085D01*
G03X124474Y348166I-293J272D01*
G02X124492Y350120I1150J966D01*
G03Y350646I-302J263D01*
G02X126756I1132J987D01*
G03Y350120I302J-263D01*
G02X126608Y347998I-1132J-987D01*
G03X126600Y347702I131J-152D01*
G02X126649Y347653I-1037J-1086D01*
G03X126947Y347663I145J138D01*
G02X127135Y345549I1153J-963D01*
G37*
G36*
G01X114446Y347320D02*
G03X114504Y348041I-142J374D01*
G02X115807Y353639I1496J2602D01*
G02X118364Y352493I1256J-622D01*
G02X118723Y351907I-2363J-1851D01*
G02X118627Y346054I-715J-2916D01*
G03X118333Y345527I83J-392D01*
G02X118344Y343528I-2825J-1015D01*
G03X118795Y343004I378J-131D01*
G02X118511Y340331I255J-1379D01*
G03X118253Y340231I-77J-185D01*
G02X112923Y342986I-2717J1278D01*
G02X114446Y347320I2585J1526D01*
G37*
G36*
G01X129349Y311914D02*
G03X126844Y310009I975J-3881D01*
G03X126462Y310121I-808J-2048D01*
G03X125946Y312657I-3969J513D01*
G02X125898Y312787I345J201D01*
G03X125517Y313115I-394J-72D01*
G02X124461Y315637I46J1501D01*
G03X124474Y316166I-293J272D01*
G02X124492Y318120I1150J966D01*
G03Y318646I-302J263D01*
G02X126756I1132J987D01*
G03Y318120I302J-263D01*
G02X126608Y315998I-1132J-987D01*
G03X126600Y315702I131J-152D01*
G02X126661Y315641I-1031J-1092D01*
G03X126971Y315663I146J137D01*
G02X129392Y313886I1230J-862D01*
G03X129405Y313384I317J-243D01*
G02X129498Y313164I-305J-259D01*
G01Y311951D01*
X129349Y311914D01*
G37*
G36*
G01X122105Y308776D02*
G03X121926Y309351I-341J209D01*
G02X123689Y309901I567J1282D01*
G03X123868Y309326I341J-209D01*
G02X122105Y308776I-567J-1282D01*
G37*
G36*
G01X114446Y315320D02*
G03X114504Y316041I-142J374D01*
G02X115807Y321639I1496J2602D01*
G02X118364Y320493I1256J-622D01*
G02X118723Y319907I-2363J-1851D01*
G02X118627Y314054I-715J-2916D01*
G03X118333Y313527I83J-392D01*
G02X118121Y311034I-2825J-1015D01*
G02X112923Y310986I-2585J-1526D01*
G02X114446Y315320I2585J1526D01*
G37*
G36*
G01X129349Y279914D02*
G03X126867Y278049I975J-3881D01*
G03X126556Y278121I-651J-2104D01*
G02X126388Y278335I31J197D01*
G03X125885Y280639I-3988J336D01*
G02X125838Y280777I348J196D01*
G03X125467Y281117I-396J-59D01*
G02X124461Y283637I96J1499D01*
G03X124474Y284166I-293J272D01*
G02X124492Y286120I1150J966D01*
G03Y286646I-302J263D01*
G02X126756I1132J987D01*
G03Y286120I302J-263D01*
G02X126726Y284112I-1132J-987D01*
G03X126713Y283583I293J-272D01*
G02X126732Y283559I-1168J-944D01*
G03X127042Y283557I156J125D01*
G02X129392Y281686I1158J-957D01*
G03X129405Y281184I317J-243D01*
G02X129498Y280964I-305J-259D01*
G01Y279951D01*
X129349Y279914D01*
G37*
G36*
G01X114446Y283320D02*
G03X114504Y284041I-142J374D01*
G02X115807Y289639I1496J2602D01*
G02X118364Y288493I1256J-622D01*
G02X118723Y287907I-2363J-1851D01*
G02X118627Y282054I-715J-2916D01*
G03X118333Y281527I83J-392D01*
G02X118121Y279034I-2825J-1015D01*
G02X112923Y278986I-2585J-1526D01*
G02X114446Y283320I2585J1526D01*
G37*
G36*
G01X129498Y247951D02*
X129349Y247914D01*
G03X126905Y246112I975J-3881D01*
G03X126380Y246224I-718J-2081D01*
G02X126198Y246436I18J199D01*
G03X125717Y248591I-3995J239D01*
G02X125669Y248760I351J191D01*
G03X125331Y249132I-399J-23D01*
G02X124461Y251637I232J1484D01*
G03X124474Y252166I-293J272D01*
G02X124492Y254120I1150J966D01*
G03Y254646I-302J263D01*
G02X126756I1132J987D01*
G03Y254120I302J-263D01*
G02X126608Y251998I-1132J-987D01*
G03X126600Y251702I131J-152D01*
G02X126696Y251602I-1034J-1089D01*
G03X127006Y251612I151J131D01*
G02X129392Y249786I1193J-913D01*
G03X129405Y249284I317J-243D01*
G02X129498Y249064I-305J-259D01*
G01Y247951D01*
G37*
G36*
G01X123380Y245914D02*
G03X123517Y245349I336J-218D01*
G02X121643Y244894I-697J-1216D01*
G03X121506Y245459I-336J218D01*
G02X123380Y245914I697J1216D01*
G37*
G36*
G01X118576Y250043D02*
G03X118280Y249501I75J-393D01*
G02X118110Y246898I-2783J-1125D01*
G02X112912Y246850I-2585J-1526D01*
G02X114575Y251233I2585J1526D01*
G03X114634Y251970I-123J381D01*
G02X115807Y257639I1366J2673D01*
G02X118364Y256493I1256J-622D01*
G02X118723Y255907I-2363J-1851D01*
G02X118576Y250043I-715J-2916D01*
G37*
G36*
G01X114889Y219449D02*
G03X115183Y219976I-83J392D01*
G02X115116Y220186I2824J1017D01*
G02X115798Y225898I1194J2754D01*
G02X118452Y225043I1282J-568D01*
G02X119202Y223745I-2142J-2103D01*
G02X118627Y218054I-1194J-2754D01*
G03X118333Y217527I83J-392D01*
G02X118121Y215034I-2825J-1015D01*
G02X112923Y214986I-2585J-1526D01*
G02X114889Y219449I2585J1526D01*
G37*
G36*
G01X109073Y405734D02*
G02X108570Y407543I-1502J557D01*
G03X109182Y407686I250J313D01*
G02X109687Y408267I1270J-594D01*
G03X109679Y408943I-218J335D01*
G02X109660Y411659I840J1364D01*
G03X109596Y412368I-214J338D01*
G02X111058Y412500I603J1484D01*
G03X111122Y411791I214J-338D01*
G02X111302Y408909I-603J-1484D01*
G03X111265Y408234I195J-349D01*
G02X109671Y405928I-813J-1142D01*
G03X109073Y405734I-223J-332D01*
G37*
G36*
G01X128750Y371148D02*
G02X128552Y372417I-1330J442D01*
G03X129255Y372527I323J236D01*
G02X129453Y371258I1330J-442D01*
G03X128750Y371148I-323J-236D01*
G37*
G36*
G01X113766Y367078D02*
G02X112134Y367622I-1166J-778D01*
G03X112334Y368222I-133J378D01*
G02X113966Y367678I1166J778D01*
G03X113766Y367078I133J-378D01*
G37*
G36*
G01X128370Y338700D02*
G02X127731Y340196I-1370J299D01*
G03X128330Y340452I208J341D01*
G02X128969Y338956I1370J-299D01*
G03X128370Y338700I-208J-341D01*
G37*
G36*
G01X128755Y306876D02*
G02X128442Y308539I-1255J625D01*
G03X129069Y308657I269J296D01*
G02X129382Y306994I1255J-625D01*
G03X128755Y306876I-269J-296D01*
G37*
G36*
G01X123666Y277219D02*
G02X121957Y276796I-592J-1271D01*
G03X121808Y277400I-318J242D01*
G02X123517Y277823I592J1271D01*
G03X123666Y277219I318J-242D01*
G37*
G36*
G01X128755Y274876D02*
G02X128442Y276539I-1255J625D01*
G03X129069Y276657I269J296D01*
G02X129382Y274994I1255J-625D01*
G03X128755Y274876I-269J-296D01*
G37*
G36*
G01Y242876D02*
G02X128442Y244539I-1255J625D01*
G03X129069Y244657I269J296D01*
G02X129382Y242994I1255J-625D01*
G03X128755Y242876I-269J-296D01*
G37*
G36*
G01X128822Y210945D02*
G02X126588Y211074I-1068J908D01*
G03X125954Y211114I-332J-222D01*
G02X123725Y211260I-1059J919D01*
G02X125461Y213316I-1183J2759D01*
G02X126061Y212812I-566J-1283D01*
G03X126695Y212772I332J222D01*
G02X126725Y212805I1052J-926D01*
G03X126688Y213108I-147J136D01*
G02X126510Y213495I218J335D01*
G03X125672Y216512I-3968J523D01*
G02X125585Y216756I313J249D01*
G03X125265Y217144I-400J-4D01*
G02X124461Y219637I298J1472D01*
G03X124474Y220166I-293J272D01*
G02X124492Y222120I1150J966D01*
G03Y222646I-302J263D01*
G02X126756I1132J987D01*
G03Y222120I302J-263D01*
G02X126726Y220112I-1132J-987D01*
G03X126713Y219583I293J-272D01*
G02X126837Y219411I-1153J-962D01*
G03X127182Y219421I170J106D01*
G02X129518Y217596I1318J-721D01*
G03X129445Y217098I271J-294D01*
G02X129498Y216935I-345J-202D01*
G01Y213784D01*
G03X129993Y213395I400J0D01*
G02X129393Y210985I331J-1362D01*
G03X128822Y210945I-266J-299D01*
G37*
G36*
G01X108013Y214026D02*
G02X105406Y209103I-313J-2986D01*
G03X104796Y209104I-305J-258D01*
G02X104801Y212984I-2289J1943D01*
G03X105411Y212983I305J258D01*
G02X106167Y213621I2288J-1944D01*
G03X106126Y214330I-204J344D01*
G02X107753Y214687I572J1280D01*
G03X108013Y214026I301J-263D01*
G37*
G36*
G01X656071Y613089D02*
G03Y612511I277J-289D01*
G02X654129I-971J-1011D01*
G03Y613089I-277J289D01*
G02X656071I971J1011D01*
G37*
G36*
G01X576233Y606267D02*
G03X576217Y605706I277J-289D01*
G02X574167I-1025J-956D01*
G03X574151Y606267I-293J272D01*
G02X574104Y608385I1041J1083D01*
G03X574098Y608942I-290J275D01*
G02X574125Y611082I1068J1057D01*
G03X574141Y611643I-277J289D01*
G02X576191I1025J956D01*
G03X576207Y611082I293J-272D01*
G02X576254Y608964I-1041J-1083D01*
G03X576260Y608407I290J-275D01*
G02X576233Y606267I-1068J-1057D01*
G37*
G36*
G01X539422D02*
G03X539406Y605706I277J-289D01*
G02X537356I-1025J-956D01*
G03X537340Y606267I-293J272D01*
G02X537293Y608385I1041J1083D01*
G03X537287Y608942I-290J275D01*
G02X537314Y611082I1068J1057D01*
G03X537330Y611643I-277J289D01*
G02X539380I1025J956D01*
G03X539396Y611082I293J-272D01*
G02X539443Y608964I-1041J-1083D01*
G03X539449Y608407I290J-275D01*
G02X539422Y606267I-1068J-1057D01*
G37*
G36*
G01X502611D02*
G03X502595Y605706I277J-289D01*
G02X500545I-1025J-956D01*
G03X500529Y606267I-293J272D01*
G02X500482Y608385I1041J1083D01*
G03X500476Y608942I-290J275D01*
G02X500503Y611082I1068J1057D01*
G03X500519Y611643I-277J289D01*
G02X502569I1025J956D01*
G03X502585Y611082I293J-272D01*
G02X502632Y608964I-1041J-1083D01*
G03X502638Y608407I290J-275D01*
G02X502611Y606267I-1068J-1057D01*
G37*
G36*
G01X465799D02*
G03X465783Y605706I277J-289D01*
G02X463733I-1025J-956D01*
G03X463717Y606267I-293J272D01*
G02X463670Y608385I1041J1083D01*
G03X463664Y608942I-290J275D01*
G02X463691Y611082I1068J1057D01*
G03X463707Y611643I-277J289D01*
G02X465757I1025J956D01*
G03X465773Y611082I293J-272D01*
G02X465820Y608964I-1041J-1083D01*
G03X465826Y608407I290J-275D01*
G02X465799Y606267I-1068J-1057D01*
G37*
G36*
G01X285091D02*
G03X285075Y605706I277J-289D01*
G02X283025I-1025J-956D01*
G03X283009Y606267I-293J272D01*
G02X282962Y608385I1041J1083D01*
G03X282956Y608942I-290J275D01*
G02X282983Y611082I1068J1057D01*
G03X282999Y611643I-277J289D01*
G02X285049I1025J956D01*
G03X285065Y611082I293J-272D01*
G02X285112Y608964I-1041J-1083D01*
G03X285118Y608407I290J-275D01*
G02X285091Y606267I-1068J-1057D01*
G37*
G36*
G01X248280D02*
G03X248264Y605706I277J-289D01*
G02X246214I-1025J-956D01*
G03X246198Y606267I-293J272D01*
G02X246151Y608385I1041J1083D01*
G03X246145Y608942I-290J275D01*
G02X246172Y611082I1068J1057D01*
G03X246188Y611643I-277J289D01*
G02X248238I1025J956D01*
G03X248254Y611082I293J-272D01*
G02X248301Y608964I-1041J-1083D01*
G03X248307Y608407I290J-275D01*
G02X248280Y606267I-1068J-1057D01*
G37*
G36*
G01X211469D02*
G03X211453Y605706I277J-289D01*
G02X209403I-1025J-956D01*
G03X209387Y606267I-293J272D01*
G02X209340Y608385I1041J1083D01*
G03X209334Y608942I-290J275D01*
G02X209361Y611082I1068J1057D01*
G03X209377Y611643I-277J289D01*
G02X211427I1025J956D01*
G03X211443Y611082I293J-272D01*
G02X211490Y608964I-1041J-1083D01*
G03X211496Y608407I290J-275D01*
G02X211469Y606267I-1068J-1057D01*
G37*
G36*
G01X174658D02*
G03X174642Y605706I277J-289D01*
G02X172592I-1025J-956D01*
G03X172576Y606267I-293J272D01*
G02X172529Y608385I1041J1083D01*
G03X172523Y608942I-290J275D01*
G02X172550Y611082I1068J1057D01*
G03X172566Y611643I-277J289D01*
G02X174616I1025J956D01*
G03X174632Y611082I293J-272D01*
G02X174679Y608964I-1041J-1083D01*
G03X174685Y608407I290J-275D01*
G02X174658Y606267I-1068J-1057D01*
G37*
G36*
G01X135781Y605706D02*
G03X135765Y606267I-293J272D01*
G02X135718Y608385I1041J1083D01*
G03X135712Y608942I-290J275D01*
G02X135739Y611082I1068J1057D01*
G03X135755Y611643I-277J289D01*
G02X137805I1025J956D01*
G03X137821Y611082I293J-272D01*
G02X137868Y608964I-1041J-1083D01*
G03X137874Y608407I290J-275D01*
G02X137847Y606267I-1068J-1057D01*
G03X137831Y605706I277J-289D01*
G02X135781I-1025J-956D01*
G37*
G36*
G01X581311Y606061D02*
G03X581298Y605499I278J-288D01*
G02X579250Y605489I-1019J-963D01*
G03X579232Y606050I-293J271D01*
G02X579173Y608170I1034J1090D01*
G03Y608719I-291J274D01*
G02X579236Y610843I1093J1031D01*
G03X579257Y611404I-274J291D01*
G02X581307Y611383I1035J946D01*
G03X581317Y610822I290J-275D01*
G02X581359Y608719I-1051J-1073D01*
G03Y608170I291J-274D01*
G02X581311Y606061I-1093J-1030D01*
G37*
G36*
G01X544500D02*
G03X544487Y605499I278J-288D01*
G02X542439Y605489I-1019J-963D01*
G03X542421Y606050I-293J271D01*
G02X542362Y608170I1034J1090D01*
G03Y608719I-291J274D01*
G02X542425Y610843I1093J1031D01*
G03X542446Y611404I-274J291D01*
G02X544496Y611383I1035J946D01*
G03X544506Y610822I290J-275D01*
G02X544548Y608719I-1051J-1073D01*
G03Y608170I291J-274D01*
G02X544500Y606061I-1093J-1030D01*
G37*
G36*
G01X507689D02*
G03X507676Y605499I278J-288D01*
G02X505628Y605489I-1019J-963D01*
G03X505610Y606050I-293J271D01*
G02X505551Y608170I1034J1090D01*
G03Y608719I-291J274D01*
G02X505614Y610843I1093J1031D01*
G03X505635Y611404I-274J291D01*
G02X507685Y611383I1035J946D01*
G03X507695Y610822I290J-275D01*
G02X507737Y608719I-1051J-1073D01*
G03Y608170I291J-274D01*
G02X507689Y606061I-1093J-1030D01*
G37*
G36*
G01X470877Y606060D02*
G03X470865Y605498I278J-287D01*
G02X468817Y605489I-1020J-962D01*
G03X468799Y606051I-294J272D01*
G02X468740Y608170I1034J1089D01*
G03X468739Y608718I-292J273D01*
G02X468802Y610843I1093J1031D01*
G03X468823Y611404I-274J291D01*
G02X470873Y611383I1035J946D01*
G03X470883Y610822I290J-275D01*
G02X470925Y608719I-1051J-1073D01*
G03X470926Y608171I292J-273D01*
G02X470877Y606060I-1093J-1031D01*
G37*
G36*
G01X290169Y606061D02*
G03X290156Y605499I278J-288D01*
G02X288108Y605489I-1019J-963D01*
G03X288090Y606050I-293J271D01*
G02X288031Y608170I1034J1090D01*
G03Y608719I-291J274D01*
G02X288094Y610843I1093J1031D01*
G03X288115Y611404I-274J291D01*
G02X290165Y611383I1035J946D01*
G03X290175Y610822I290J-275D01*
G02X290217Y608719I-1051J-1073D01*
G03Y608170I291J-274D01*
G02X290169Y606061I-1093J-1030D01*
G37*
G36*
G01X253358D02*
G03X253345Y605499I278J-288D01*
G02X251297Y605489I-1019J-963D01*
G03X251279Y606050I-293J271D01*
G02X251220Y608170I1034J1090D01*
G03Y608719I-291J274D01*
G02X251283Y610843I1093J1031D01*
G03X251304Y611404I-274J291D01*
G02X253354Y611383I1035J946D01*
G03X253364Y610822I290J-275D01*
G02X253406Y608719I-1051J-1073D01*
G03Y608170I291J-274D01*
G02X253358Y606061I-1093J-1030D01*
G37*
G36*
G01X216547D02*
G03X216534Y605499I278J-288D01*
G02X214486Y605489I-1019J-963D01*
G03X214468Y606050I-293J271D01*
G02X214409Y608170I1034J1090D01*
G03Y608719I-291J274D01*
G02X214472Y610843I1093J1031D01*
G03X214493Y611404I-274J291D01*
G02X216543Y611383I1035J946D01*
G03X216553Y610822I290J-275D01*
G02X216595Y608719I-1051J-1073D01*
G03Y608170I291J-274D01*
G02X216547Y606061I-1093J-1030D01*
G37*
G36*
G01X179736D02*
G03X179723Y605499I278J-288D01*
G02X177675Y605489I-1019J-963D01*
G03X177657Y606050I-293J271D01*
G02X177598Y608170I1034J1090D01*
G03Y608719I-291J274D01*
G02X177661Y610843I1093J1031D01*
G03X177682Y611404I-274J291D01*
G02X179732Y611383I1035J946D01*
G03X179742Y610822I290J-275D01*
G02X179784Y608719I-1051J-1073D01*
G03Y608170I291J-274D01*
G02X179736Y606061I-1093J-1030D01*
G37*
G36*
G01X142925D02*
G03X142912Y605499I278J-288D01*
G02X140864Y605489I-1019J-963D01*
G03X140846Y606050I-293J271D01*
G02X140787Y608170I1034J1090D01*
G03Y608719I-291J274D01*
G02X140850Y610843I1093J1031D01*
G03X140871Y611404I-274J291D01*
G02X142921Y611383I1035J946D01*
G03X142931Y610822I290J-275D01*
G02X142973Y608719I-1051J-1073D01*
G03Y608170I291J-274D01*
G02X142925Y606061I-1093J-1030D01*
G37*
G36*
G01X116026Y591716D02*
G03X115998Y592320I-276J290D01*
G02X117910Y592364I929J1180D01*
G03Y591760I262J-302D01*
G02X116026Y591716I-918J-1060D01*
G37*
G36*
G01X648222Y592647D02*
G03X648520Y592165I389J-93D01*
G02X646718Y591047I-340J-1463D01*
G03X646420Y591529I-389J93D01*
G02X645300Y592638I340J1463D01*
G03X644825Y592934I-389J-95D01*
G02X645960Y594754I-325J1466D01*
G03X646435Y594458I389J95D01*
G02X648222Y592647I325J-1466D01*
G37*
G36*
G01X596456Y590417D02*
G03X596470Y589834I281J-285D01*
G02X594470I-1000J-1120D01*
G03X594484Y590417I-267J298D01*
G02X596456I986J997D01*
G37*
G36*
G01X589763D02*
G03X589777Y589834I281J-285D01*
G02X587777I-1000J-1120D01*
G03X587791Y590417I-267J298D01*
G02X589763I986J997D01*
G37*
G36*
G01X572331D02*
G03X572345Y589834I281J-285D01*
G02X570345I-1000J-1120D01*
G03X570359Y590417I-267J298D01*
G02X572331I986J997D01*
G37*
G36*
G01X559645D02*
G03X559659Y589834I281J-285D01*
G02X557659I-1000J-1120D01*
G03X557673Y590417I-267J298D01*
G02X559645I986J997D01*
G37*
G36*
G01X552952D02*
G03X552966Y589834I281J-285D01*
G02X550966I-1000J-1120D01*
G03X550980Y590417I-267J298D01*
G02X552952I986J997D01*
G37*
G36*
G01X535520D02*
G03X535534Y589834I281J-285D01*
G02X533534I-1000J-1120D01*
G03X533548Y590417I-267J298D01*
G02X535520I986J997D01*
G37*
G36*
G01X529234Y590378D02*
G03X529261Y589817I298J-267D01*
G02X527180Y589777I-1020J-1103D01*
G03X527184Y590338I-283J283D01*
G02X529234Y590378I1006J976D01*
G37*
G36*
G01X520848Y589834D02*
G03X520862Y590417I-267J298D01*
G02X522834I986J997D01*
G03X522848Y589834I281J-285D01*
G02X520848I-1000J-1120D01*
G37*
G36*
G01X516141Y590417D02*
G03X516155Y589834I281J-285D01*
G02X514155I-1000J-1120D01*
G03X514169Y590417I-267J298D01*
G02X516141I986J997D01*
G37*
G36*
G01X498709D02*
G03X498723Y589834I281J-285D01*
G02X496723I-1000J-1120D01*
G03X496737Y590417I-267J298D01*
G02X498709I986J997D01*
G37*
G36*
G01X492423Y590378D02*
G03X492450Y589817I298J-267D01*
G02X490369Y589777I-1020J-1103D01*
G03X490373Y590338I-283J283D01*
G02X492423Y590378I1006J976D01*
G37*
G36*
G01X486710Y589695D02*
G03X486461Y589191I130J-378D01*
G02X484623Y590158I-1424J-477D01*
G03X484898Y590648I-111J384D01*
G02X486710Y589695I1352J372D01*
G37*
G36*
G01X479330Y590417D02*
G03X479344Y589834I281J-285D01*
G02X477344I-1000J-1120D01*
G03X477358Y590417I-267J298D01*
G02X479330I986J997D01*
G37*
G36*
G01X461937Y590358D02*
G03X461953Y589797I293J-272D01*
G02X459871I-1041J-1083D01*
G03X459887Y590358I-277J289D01*
G02X461937I1025J956D01*
G37*
G36*
G01X455612Y590378D02*
G03X455639Y589817I298J-267D01*
G02X453558Y589777I-1020J-1103D01*
G03X453562Y590338I-283J283D01*
G02X455612Y590378I1006J976D01*
G37*
G36*
G01X305282Y590435D02*
G03X305307Y589853I286J-279D01*
G02X303307Y589816I-979J-1139D01*
G03X303311Y590399I-272J293D01*
G02X305282Y590435I967J1015D01*
G37*
G36*
G01X298621Y590417D02*
G03X298635Y589834I281J-285D01*
G02X296635I-1000J-1120D01*
G03X296649Y590417I-267J298D01*
G02X298621I986J997D01*
G37*
G36*
G01X281189D02*
G03X281203Y589834I281J-285D01*
G02X279203I-1000J-1120D01*
G03X279217Y590417I-267J298D01*
G02X281189I986J997D01*
G37*
G36*
G01X274903Y590378D02*
G03X274930Y589817I298J-267D01*
G02X272849Y589777I-1020J-1103D01*
G03X272853Y590338I-283J283D01*
G02X274903Y590378I1006J976D01*
G37*
G36*
G01X266517Y589834D02*
G03X266531Y590417I-267J298D01*
G02X268503I986J997D01*
G03X268517Y589834I281J-285D01*
G02X266517I-1000J-1120D01*
G37*
G36*
G01X261810Y590417D02*
G03X261824Y589834I281J-285D01*
G02X259824I-1000J-1120D01*
G03X259838Y590417I-267J298D01*
G02X261810I986J997D01*
G37*
G36*
G01X244378D02*
G03X244392Y589834I281J-285D01*
G02X242392I-1000J-1120D01*
G03X242406Y590417I-267J298D01*
G02X244378I986J997D01*
G37*
G36*
G01X238092Y590378D02*
G03X238119Y589817I298J-267D01*
G02X236038Y589777I-1020J-1103D01*
G03X236042Y590338I-283J283D01*
G02X238092Y590378I1006J976D01*
G37*
G36*
G01X229706Y589834D02*
G03X229720Y590417I-267J298D01*
G02X231692I986J997D01*
G03X231706Y589834I281J-285D01*
G02X229706I-1000J-1120D01*
G37*
G36*
G01X224999Y590417D02*
G03X225013Y589834I281J-285D01*
G02X223013I-1000J-1120D01*
G03X223027Y590417I-267J298D01*
G02X224999I986J997D01*
G37*
G36*
G01X207567D02*
G03X207581Y589834I281J-285D01*
G02X205581I-1000J-1120D01*
G03X205595Y590417I-267J298D01*
G02X207567I986J997D01*
G37*
G36*
G01X201281Y590378D02*
G03X201308Y589817I298J-267D01*
G02X199227Y589777I-1020J-1103D01*
G03X199231Y590338I-283J283D01*
G02X201281Y590378I1006J976D01*
G37*
G36*
G01X192895Y589834D02*
G03X192909Y590417I-267J298D01*
G02X194881I986J997D01*
G03X194895Y589834I281J-285D01*
G02X192895I-1000J-1120D01*
G37*
G36*
G01X188188Y590417D02*
G03X188202Y589834I281J-285D01*
G02X186202I-1000J-1120D01*
G03X186216Y590417I-267J298D01*
G02X188188I986J997D01*
G37*
G36*
G01X170776Y590387D02*
G03X170791Y589816I287J-278D01*
G02X168749I-1021J-1102D01*
G03X168764Y590387I-272J293D01*
G02X170776I1006J977D01*
G37*
G36*
G01X164470Y590378D02*
G03X164497Y589817I298J-267D01*
G02X162416Y589777I-1020J-1103D01*
G03X162420Y590338I-283J283D01*
G02X164470Y590378I1006J976D01*
G37*
G36*
G01X156084Y589834D02*
G03X156098Y590417I-267J298D01*
G02X158070I986J997D01*
G03X158084Y589834I281J-285D01*
G02X156084I-1000J-1120D01*
G37*
G36*
G01X151377Y590417D02*
G03X151391Y589834I281J-285D01*
G02X149391I-1000J-1120D01*
G03X149405Y590417I-267J298D01*
G02X151377I986J997D01*
G37*
G36*
G01X133945D02*
G03X133959Y589834I281J-285D01*
G02X131959I-1000J-1120D01*
G03X131973Y590417I-267J298D01*
G02X133945I986J997D01*
G37*
G36*
G01X127659Y590378D02*
G03X127686Y589817I298J-267D01*
G02X125605Y589777I-1020J-1103D01*
G03X125609Y590338I-283J283D01*
G02X127659Y590378I1006J976D01*
G37*
G36*
G01X357780Y589938D02*
G03Y589367I280J-286D01*
G02X355816I-982J-1001D01*
G03Y589938I-280J285D01*
G02X357780I982J1001D01*
G37*
G36*
G01X308818Y589947D02*
G03X308808Y589356I264J-300D01*
G02X306922Y589387I-960J-1022D01*
G03X306932Y589978I-264J300D01*
G02X306867Y591957I960J1022D01*
G03X306819Y592547I-292J273D01*
G02X308700Y592700I856J1110D01*
G03X308748Y592110I292J-273D01*
G02X308818Y589947I-856J-1110D01*
G37*
G36*
G01X447191Y589794D02*
G03X447411Y590330I-145J373D01*
G02X449266Y589621I1281J570D01*
G03X449074Y589075I164J-365D01*
G02X447191Y589794I-1339J-681D01*
G37*
G36*
G01X581206Y587343D02*
G03X581187Y586736I251J-312D01*
G02X579315Y586751I-944J-1036D01*
G03X579306Y587359I-265J300D01*
G02X579170Y589541I960J1155D01*
G03Y590087I-292J273D01*
G02X579225Y592197I1096J1027D01*
G03X579241Y592758I-277J289D01*
G02X581291I1025J956D01*
G03X581307Y592197I293J-272D01*
G02X581362Y590087I-1041J-1083D01*
G03Y589541I292J-273D01*
G02X581206Y587343I-1096J-1027D01*
G37*
G36*
G01X544395D02*
G03X544376Y586736I251J-312D01*
G02X542504Y586751I-944J-1036D01*
G03X542495Y587359I-265J300D01*
G02X542359Y589541I960J1155D01*
G03Y590087I-292J273D01*
G02X542414Y592197I1096J1027D01*
G03X542430Y592758I-277J289D01*
G02X544480I1025J956D01*
G03X544496Y592197I293J-272D01*
G02X544551Y590087I-1041J-1083D01*
G03Y589541I292J-273D01*
G02X544395Y587343I-1096J-1027D01*
G37*
G36*
G01X507584D02*
G03X507565Y586736I251J-312D01*
G02X505693Y586751I-944J-1036D01*
G03X505684Y587359I-265J300D01*
G02X505548Y589541I960J1155D01*
G03Y590087I-292J273D01*
G02X505603Y592197I1096J1027D01*
G03X505619Y592758I-277J289D01*
G02X507669I1025J956D01*
G03X507685Y592197I293J-272D01*
G02X507740Y590087I-1041J-1083D01*
G03Y589541I292J-273D01*
G02X507584Y587343I-1096J-1027D01*
G37*
G36*
G01X470772D02*
G03X470753Y586736I251J-312D01*
G02X468881Y586751I-944J-1036D01*
G03X468872Y587359I-265J300D01*
G02X468736Y589541I960J1155D01*
G03Y590087I-292J273D01*
G02X468791Y592197I1096J1027D01*
G03X468807Y592758I-277J289D01*
G02X470857I1025J956D01*
G03X470873Y592197I293J-272D01*
G02X470928Y590087I-1041J-1083D01*
G03Y589541I292J-273D01*
G02X470772Y587343I-1096J-1027D01*
G37*
G36*
G01X290064D02*
G03X290045Y586736I251J-312D01*
G02X288173Y586751I-944J-1036D01*
G03X288164Y587359I-265J300D01*
G02X288028Y589541I960J1155D01*
G03Y590087I-292J273D01*
G02X288083Y592197I1096J1027D01*
G03X288099Y592758I-277J289D01*
G02X290149I1025J956D01*
G03X290165Y592197I293J-272D01*
G02X290220Y590087I-1041J-1083D01*
G03Y589541I292J-273D01*
G02X290064Y587343I-1096J-1027D01*
G37*
G36*
G01X253253D02*
G03X253234Y586736I251J-312D01*
G02X251362Y586751I-944J-1036D01*
G03X251353Y587359I-265J300D01*
G02X251217Y589541I960J1155D01*
G03Y590087I-292J273D01*
G02X251272Y592197I1096J1027D01*
G03X251288Y592758I-277J289D01*
G02X253338I1025J956D01*
G03X253354Y592197I293J-272D01*
G02X253409Y590087I-1041J-1083D01*
G03Y589541I292J-273D01*
G02X253253Y587343I-1096J-1027D01*
G37*
G36*
G01X216442D02*
G03X216423Y586736I251J-312D01*
G02X214551Y586751I-944J-1036D01*
G03X214542Y587359I-265J300D01*
G02X214406Y589541I960J1155D01*
G03Y590087I-292J273D01*
G02X214461Y592197I1096J1027D01*
G03X214477Y592758I-277J289D01*
G02X216527I1025J956D01*
G03X216543Y592197I293J-272D01*
G02X216598Y590087I-1041J-1083D01*
G03Y589541I292J-273D01*
G02X216442Y587343I-1096J-1027D01*
G37*
G36*
G01X179631D02*
G03X179612Y586736I251J-312D01*
G02X177740Y586751I-944J-1036D01*
G03X177731Y587359I-265J300D01*
G02X177595Y589541I960J1155D01*
G03Y590087I-292J273D01*
G02X177650Y592197I1096J1027D01*
G03X177666Y592758I-277J289D01*
G02X179716I1025J956D01*
G03X179732Y592197I293J-272D01*
G02X179787Y590087I-1041J-1083D01*
G03Y589541I292J-273D01*
G02X179631Y587343I-1096J-1027D01*
G37*
G36*
G01X142820D02*
G03X142801Y586736I251J-312D01*
G02X140929Y586751I-944J-1036D01*
G03X140920Y587359I-265J300D01*
G02X140784Y589541I960J1155D01*
G03Y590087I-292J273D01*
G02X140839Y592197I1096J1027D01*
G03X140855Y592758I-277J289D01*
G02X142905I1025J956D01*
G03X142921Y592197I293J-272D01*
G02X142976Y590087I-1041J-1083D01*
G03Y589541I292J-273D01*
G02X142820Y587343I-1096J-1027D01*
G37*
G36*
G01X576206Y587216D02*
G03X576191Y586655I277J-288D01*
G02X574141I-1025J-957D01*
G03X574126Y587216I-292J273D01*
G02X574070Y589327I1040J1084D01*
G03Y589873I-292J273D01*
G02X574115Y591973I1096J1027D01*
G03X574125Y592535I-280J286D01*
G02X576176Y592553I1017J965D01*
G03X576197Y591992I295J-270D01*
G02X576262Y589873I-1031J-1092D01*
G03Y589327I292J-273D01*
G02X576206Y587216I-1096J-1027D01*
G37*
G36*
G01X539395D02*
G03X539380Y586655I277J-288D01*
G02X537330I-1025J-957D01*
G03X537315Y587216I-292J273D01*
G02X537259Y589327I1040J1084D01*
G03Y589873I-292J273D01*
G02X537304Y591973I1096J1027D01*
G03X537314Y592535I-280J286D01*
G02X539365Y592553I1017J965D01*
G03X539386Y591992I295J-270D01*
G02X539451Y589873I-1031J-1092D01*
G03Y589327I292J-273D01*
G02X539395Y587216I-1096J-1027D01*
G37*
G36*
G01X502584D02*
G03X502569Y586655I277J-288D01*
G02X500519I-1025J-957D01*
G03X500504Y587216I-292J273D01*
G02X500448Y589327I1040J1084D01*
G03Y589873I-292J273D01*
G02X500493Y591973I1096J1027D01*
G03X500503Y592535I-280J286D01*
G02X502554Y592553I1017J965D01*
G03X502575Y591992I295J-270D01*
G02X502640Y589873I-1031J-1092D01*
G03Y589327I292J-273D01*
G02X502584Y587216I-1096J-1027D01*
G37*
G36*
G01X463707Y586655D02*
G03X463692Y587216I-292J273D01*
G02X463636Y589327I1040J1084D01*
G03Y589873I-292J273D01*
G02X463681Y591973I1096J1027D01*
G03X463691Y592535I-280J286D01*
G02X465742Y592553I1017J965D01*
G03X465763Y591992I295J-270D01*
G02X465828Y589873I-1031J-1092D01*
G03Y589327I292J-273D01*
G02X465772Y587216I-1096J-1027D01*
G03X465757Y586655I277J-288D01*
G02X463707I-1025J-957D01*
G37*
G36*
G01X285064Y587216D02*
G03X285049Y586655I277J-288D01*
G02X282999I-1025J-957D01*
G03X282984Y587216I-292J273D01*
G02X282928Y589327I1040J1084D01*
G03Y589873I-292J273D01*
G02X282973Y591973I1096J1027D01*
G03X282983Y592535I-280J286D01*
G02X285034Y592553I1017J965D01*
G03X285055Y591992I295J-270D01*
G02X285120Y589873I-1031J-1092D01*
G03Y589327I292J-273D01*
G02X285064Y587216I-1096J-1027D01*
G37*
G36*
G01X248253D02*
G03X248238Y586655I277J-288D01*
G02X246188I-1025J-957D01*
G03X246173Y587216I-292J273D01*
G02X246117Y589327I1040J1084D01*
G03Y589873I-292J273D01*
G02X246162Y591973I1096J1027D01*
G03X246172Y592535I-280J286D01*
G02X248223Y592553I1017J965D01*
G03X248244Y591992I295J-270D01*
G02X248309Y589873I-1031J-1092D01*
G03Y589327I292J-273D01*
G02X248253Y587216I-1096J-1027D01*
G37*
G36*
G01X211442D02*
G03X211427Y586655I277J-288D01*
G02X209377I-1025J-957D01*
G03X209362Y587216I-292J273D01*
G02X209306Y589327I1040J1084D01*
G03Y589873I-292J273D01*
G02X209351Y591973I1096J1027D01*
G03X209361Y592535I-280J286D01*
G02X211412Y592553I1017J965D01*
G03X211433Y591992I295J-270D01*
G02X211498Y589873I-1031J-1092D01*
G03Y589327I292J-273D01*
G02X211442Y587216I-1096J-1027D01*
G37*
G36*
G01X174631D02*
G03X174616Y586655I277J-288D01*
G02X172566I-1025J-957D01*
G03X172551Y587216I-292J273D01*
G02X172495Y589327I1040J1084D01*
G03Y589873I-292J273D01*
G02X172540Y591973I1096J1027D01*
G03X172550Y592535I-280J286D01*
G02X174601Y592553I1017J965D01*
G03X174622Y591992I295J-270D01*
G02X174687Y589873I-1031J-1092D01*
G03Y589327I292J-273D01*
G02X174631Y587216I-1096J-1027D01*
G37*
G36*
G01X135755Y586655D02*
G03X135740Y587216I-292J273D01*
G02X135684Y589327I1040J1084D01*
G03Y589873I-292J273D01*
G02X135729Y591973I1096J1027D01*
G03X135739Y592535I-280J286D01*
G02X137790Y592553I1017J965D01*
G03X137811Y591992I295J-270D01*
G02X137876Y589873I-1031J-1092D01*
G03Y589327I292J-273D01*
G02X137820Y587216I-1096J-1027D01*
G03X137805Y586655I277J-288D01*
G02X135755I-1025J-957D01*
G37*
G36*
G01X363180Y584675D02*
G03X362603I-289J-277D01*
G02Y586753I-1085J1039D01*
G03X363180I289J277D01*
G02Y584675I1085J-1039D01*
G37*
G36*
G01X651229Y573317D02*
G03X650716Y573294I-243J-318D01*
G02X648604Y575427I-1015J1107D01*
G03Y575973I-292J273D01*
G02X650658Y578157I1096J1027D01*
G03X651171Y578159I255J308D01*
G02X653272Y576024I969J-1148D01*
G03Y575498I302J-263D01*
G02X651229Y573317I-1132J-987D01*
G37*
G36*
G01X358734Y571001D02*
G03Y570446I288J-278D01*
G02X356714I-1010J-972D01*
G03Y571001I-288J277D01*
G02X358734I1010J972D01*
G37*
G36*
G01X576233Y568467D02*
G03X576217Y567906I277J-289D01*
G02X574167I-1025J-956D01*
G03X574151Y568467I-293J272D01*
G02X574104Y570585I1041J1083D01*
G03X574098Y571142I-290J275D01*
G02X574125Y573282I1068J1057D01*
G03X574141Y573843I-277J289D01*
G02X576191I1025J956D01*
G03X576207Y573282I293J-272D01*
G02X576254Y571164I-1041J-1083D01*
G03X576260Y570607I290J-275D01*
G02X576233Y568467I-1068J-1057D01*
G37*
G36*
G01X539422D02*
G03X539406Y567906I277J-289D01*
G02X537356I-1025J-956D01*
G03X537340Y568467I-293J272D01*
G02X537293Y570585I1041J1083D01*
G03X537287Y571142I-290J275D01*
G02X537314Y573282I1068J1057D01*
G03X537330Y573843I-277J289D01*
G02X539380I1025J956D01*
G03X539396Y573282I293J-272D01*
G02X539443Y571164I-1041J-1083D01*
G03X539449Y570607I290J-275D01*
G02X539422Y568467I-1068J-1057D01*
G37*
G36*
G01X502611D02*
G03X502595Y567906I277J-289D01*
G02X500545I-1025J-956D01*
G03X500529Y568467I-293J272D01*
G02X500482Y570585I1041J1083D01*
G03X500476Y571142I-290J275D01*
G02X500503Y573282I1068J1057D01*
G03X500519Y573843I-277J289D01*
G02X502569I1025J956D01*
G03X502585Y573282I293J-272D01*
G02X502632Y571164I-1041J-1083D01*
G03X502638Y570607I290J-275D01*
G02X502611Y568467I-1068J-1057D01*
G37*
G36*
G01X465799D02*
G03X465783Y567906I277J-289D01*
G02X463733I-1025J-956D01*
G03X463717Y568467I-293J272D01*
G02X463670Y570585I1041J1083D01*
G03X463664Y571142I-290J275D01*
G02X463691Y573282I1068J1057D01*
G03X463707Y573843I-277J289D01*
G02X465757I1025J956D01*
G03X465773Y573282I293J-272D01*
G02X465820Y571164I-1041J-1083D01*
G03X465826Y570607I290J-275D01*
G02X465799Y568467I-1068J-1057D01*
G37*
G36*
G01X285091D02*
G03X285075Y567906I277J-289D01*
G02X283025I-1025J-956D01*
G03X283009Y568467I-293J272D01*
G02X282962Y570585I1041J1083D01*
G03X282956Y571142I-290J275D01*
G02X282983Y573282I1068J1057D01*
G03X282999Y573843I-277J289D01*
G02X285049I1025J956D01*
G03X285065Y573282I293J-272D01*
G02X285112Y571164I-1041J-1083D01*
G03X285118Y570607I290J-275D01*
G02X285091Y568467I-1068J-1057D01*
G37*
G36*
G01X248280D02*
G03X248264Y567906I277J-289D01*
G02X246214I-1025J-956D01*
G03X246198Y568467I-293J272D01*
G02X246151Y570585I1041J1083D01*
G03X246145Y571142I-290J275D01*
G02X246172Y573282I1068J1057D01*
G03X246188Y573843I-277J289D01*
G02X248238I1025J956D01*
G03X248254Y573282I293J-272D01*
G02X248301Y571164I-1041J-1083D01*
G03X248307Y570607I290J-275D01*
G02X248280Y568467I-1068J-1057D01*
G37*
G36*
G01X211469D02*
G03X211453Y567906I277J-289D01*
G02X209403I-1025J-956D01*
G03X209387Y568467I-293J272D01*
G02X209340Y570585I1041J1083D01*
G03X209334Y571142I-290J275D01*
G02X209361Y573282I1068J1057D01*
G03X209377Y573843I-277J289D01*
G02X211427I1025J956D01*
G03X211443Y573282I293J-272D01*
G02X211490Y571164I-1041J-1083D01*
G03X211496Y570607I290J-275D01*
G02X211469Y568467I-1068J-1057D01*
G37*
G36*
G01X174658D02*
G03X174642Y567906I277J-289D01*
G02X172592I-1025J-956D01*
G03X172576Y568467I-293J272D01*
G02X172529Y570585I1041J1083D01*
G03X172523Y571142I-290J275D01*
G02X172550Y573282I1068J1057D01*
G03X172566Y573843I-277J289D01*
G02X174616I1025J956D01*
G03X174632Y573282I293J-272D01*
G02X174679Y571164I-1041J-1083D01*
G03X174685Y570607I290J-275D01*
G02X174658Y568467I-1068J-1057D01*
G37*
G36*
G01X135781Y567906D02*
G03X135765Y568467I-293J272D01*
G02X135718Y570585I1041J1083D01*
G03X135712Y571142I-290J275D01*
G02X135739Y573282I1068J1057D01*
G03X135755Y573843I-277J289D01*
G02X137805I1025J956D01*
G03X137821Y573282I293J-272D01*
G02X137868Y571164I-1041J-1083D01*
G03X137874Y570607I290J-275D01*
G02X137847Y568467I-1068J-1057D01*
G03X137831Y567906I277J-289D01*
G02X135781I-1025J-956D01*
G37*
G36*
G01X581311Y568261D02*
G03X581298Y567699I278J-288D01*
G02X579250Y567689I-1019J-963D01*
G03X579232Y568250I-293J271D01*
G02X579173Y570370I1034J1090D01*
G03Y570919I-291J274D01*
G02X579236Y573043I1093J1031D01*
G03X579257Y573604I-274J291D01*
G02X581307Y573583I1035J946D01*
G03X581317Y573022I290J-275D01*
G02X581359Y570919I-1051J-1073D01*
G03Y570370I291J-274D01*
G02X581311Y568261I-1093J-1030D01*
G37*
G36*
G01X544500D02*
G03X544487Y567699I278J-288D01*
G02X542439Y567689I-1019J-963D01*
G03X542421Y568250I-293J271D01*
G02X542362Y570370I1034J1090D01*
G03Y570919I-291J274D01*
G02X542425Y573043I1093J1031D01*
G03X542446Y573604I-274J291D01*
G02X544496Y573583I1035J946D01*
G03X544506Y573022I290J-275D01*
G02X544548Y570919I-1051J-1073D01*
G03Y570370I291J-274D01*
G02X544500Y568261I-1093J-1030D01*
G37*
G36*
G01X507689D02*
G03X507676Y567699I278J-288D01*
G02X505628Y567689I-1019J-963D01*
G03X505610Y568250I-293J271D01*
G02X505551Y570370I1034J1090D01*
G03Y570919I-291J274D01*
G02X505614Y573043I1093J1031D01*
G03X505635Y573604I-274J291D01*
G02X507685Y573583I1035J946D01*
G03X507695Y573022I290J-275D01*
G02X507737Y570919I-1051J-1073D01*
G03Y570370I291J-274D01*
G02X507689Y568261I-1093J-1030D01*
G37*
G36*
G01X470877D02*
G03X470864Y567699I278J-288D01*
G02X468816Y567689I-1019J-963D01*
G03X468798Y568250I-293J271D01*
G02X468739Y570370I1034J1090D01*
G03Y570919I-291J274D01*
G02X468802Y573043I1093J1031D01*
G03X468823Y573604I-274J291D01*
G02X470873Y573583I1035J946D01*
G03X470883Y573022I290J-275D01*
G02X470925Y570919I-1051J-1073D01*
G03Y570370I291J-274D01*
G02X470877Y568261I-1093J-1030D01*
G37*
G36*
G01X290169D02*
G03X290156Y567699I278J-288D01*
G02X288108Y567689I-1019J-963D01*
G03X288090Y568250I-293J271D01*
G02X288031Y570370I1034J1090D01*
G03Y570919I-291J274D01*
G02X288094Y573043I1093J1031D01*
G03X288115Y573604I-274J291D01*
G02X290165Y573583I1035J946D01*
G03X290175Y573022I290J-275D01*
G02X290217Y570919I-1051J-1073D01*
G03Y570370I291J-274D01*
G02X290169Y568261I-1093J-1030D01*
G37*
G36*
G01X253358D02*
G03X253345Y567699I278J-288D01*
G02X251297Y567689I-1019J-963D01*
G03X251279Y568250I-293J271D01*
G02X251220Y570370I1034J1090D01*
G03Y570919I-291J274D01*
G02X251283Y573043I1093J1031D01*
G03X251304Y573604I-274J291D01*
G02X253354Y573583I1035J946D01*
G03X253364Y573022I290J-275D01*
G02X253406Y570919I-1051J-1073D01*
G03Y570370I291J-274D01*
G02X253358Y568261I-1093J-1030D01*
G37*
G36*
G01X216547D02*
G03X216534Y567699I278J-288D01*
G02X214486Y567689I-1019J-963D01*
G03X214468Y568250I-293J271D01*
G02X214409Y570370I1034J1090D01*
G03Y570919I-291J274D01*
G02X214472Y573043I1093J1031D01*
G03X214493Y573604I-274J291D01*
G02X216543Y573583I1035J946D01*
G03X216553Y573022I290J-275D01*
G02X216595Y570919I-1051J-1073D01*
G03Y570370I291J-274D01*
G02X216547Y568261I-1093J-1030D01*
G37*
G36*
G01X179736D02*
G03X179723Y567699I278J-288D01*
G02X177675Y567689I-1019J-963D01*
G03X177657Y568250I-293J271D01*
G02X177598Y570370I1034J1090D01*
G03Y570919I-291J274D01*
G02X177661Y573043I1093J1031D01*
G03X177682Y573604I-274J291D01*
G02X179732Y573583I1035J946D01*
G03X179742Y573022I290J-275D01*
G02X179784Y570919I-1051J-1073D01*
G03Y570370I291J-274D01*
G02X179736Y568261I-1093J-1030D01*
G37*
G36*
G01X142925D02*
G03X142912Y567699I278J-288D01*
G02X140864Y567689I-1019J-963D01*
G03X140846Y568250I-293J271D01*
G02X140787Y570370I1034J1090D01*
G03Y570919I-291J274D01*
G02X140850Y573043I1093J1031D01*
G03X140871Y573604I-274J291D01*
G02X142921Y573583I1035J946D01*
G03X142931Y573022I290J-275D01*
G02X142973Y570919I-1051J-1073D01*
G03Y570370I291J-274D01*
G02X142925Y568261I-1093J-1030D01*
G37*
G36*
G01X646615Y562377D02*
G03X645985I-315J-246D01*
G02Y564223I-1185J923D01*
G03X646615I315J246D01*
G02X648985I1185J-923D01*
G03X649615I315J246D01*
G02X651985I1185J-923D01*
G03X652615I315J246D01*
G02Y562377I1185J-923D01*
G03X651985I-315J-246D01*
G02X649615I-1185J923D01*
G03X648985I-315J-246D01*
G02X646615I-1185J923D01*
G37*
G36*
G01X596456Y552617D02*
G03X596470Y552034I281J-285D01*
G02X594470I-1000J-1120D01*
G03X594484Y552617I-267J298D01*
G02X596456I986J997D01*
G37*
G36*
G01X589763D02*
G03X589777Y552034I281J-285D01*
G02X587777I-1000J-1120D01*
G03X587791Y552617I-267J298D01*
G02X589763I986J997D01*
G37*
G36*
G01X572331D02*
G03X572345Y552034I281J-285D01*
G02X570345I-1000J-1120D01*
G03X570359Y552617I-267J298D01*
G02X572331I986J997D01*
G37*
G36*
G01X559645D02*
G03X559659Y552034I281J-285D01*
G02X557659I-1000J-1120D01*
G03X557673Y552617I-267J298D01*
G02X559645I986J997D01*
G37*
G36*
G01X552952D02*
G03X552966Y552034I281J-285D01*
G02X550966I-1000J-1120D01*
G03X550980Y552617I-267J298D01*
G02X552952I986J997D01*
G37*
G36*
G01X535520D02*
G03X535534Y552034I281J-285D01*
G02X533534I-1000J-1120D01*
G03X533548Y552617I-267J298D01*
G02X535520I986J997D01*
G37*
G36*
G01X529234Y552578D02*
G03X529261Y552017I298J-267D01*
G02X527180Y551977I-1020J-1103D01*
G03X527184Y552538I-283J283D01*
G02X529234Y552578I1006J976D01*
G37*
G36*
G01X520848Y552034D02*
G03X520862Y552617I-267J298D01*
G02X522834I986J997D01*
G03X522848Y552034I281J-285D01*
G02X520848I-1000J-1120D01*
G37*
G36*
G01X516141Y552617D02*
G03X516155Y552034I281J-285D01*
G02X514155I-1000J-1120D01*
G03X514169Y552617I-267J298D01*
G02X516141I986J997D01*
G37*
G36*
G01X498709D02*
G03X498723Y552034I281J-285D01*
G02X496723I-1000J-1120D01*
G03X496737Y552617I-267J298D01*
G02X498709I986J997D01*
G37*
G36*
G01X492423Y552578D02*
G03X492450Y552017I298J-267D01*
G02X490369Y551977I-1020J-1103D01*
G03X490373Y552538I-283J283D01*
G02X492423Y552578I1006J976D01*
G37*
G36*
G01X484037Y552034D02*
G03X484051Y552617I-267J298D01*
G02X486023I986J997D01*
G03X486037Y552034I281J-285D01*
G02X484037I-1000J-1120D01*
G37*
G36*
G01X479330Y552617D02*
G03X479344Y552034I281J-285D01*
G02X477344I-1000J-1120D01*
G03X477358Y552617I-267J298D01*
G02X479330I986J997D01*
G37*
G36*
G01X461937Y552558D02*
G03X461953Y551997I293J-272D01*
G02X459871I-1041J-1083D01*
G03X459887Y552558I-277J289D01*
G02X461937I1025J956D01*
G37*
G36*
G01X455612Y552578D02*
G03X455639Y552017I298J-267D01*
G02X453558Y551977I-1020J-1103D01*
G03X453562Y552538I-283J283D01*
G02X455612Y552578I1006J976D01*
G37*
G36*
G01X305282Y552635D02*
G03X305307Y552053I286J-279D01*
G02X303307Y552016I-979J-1139D01*
G03X303311Y552599I-272J293D01*
G02X305282Y552635I967J1015D01*
G37*
G36*
G01X298621Y552617D02*
G03X298635Y552034I281J-285D01*
G02X296635I-1000J-1120D01*
G03X296649Y552617I-267J298D01*
G02X298621I986J997D01*
G37*
G36*
G01X281189D02*
G03X281203Y552034I281J-285D01*
G02X279203I-1000J-1120D01*
G03X279217Y552617I-267J298D01*
G02X281189I986J997D01*
G37*
G36*
G01X274903Y552578D02*
G03X274930Y552017I298J-267D01*
G02X272849Y551977I-1020J-1103D01*
G03X272853Y552538I-283J283D01*
G02X274903Y552578I1006J976D01*
G37*
G36*
G01X266517Y552034D02*
G03X266531Y552617I-267J298D01*
G02X268503I986J997D01*
G03X268517Y552034I281J-285D01*
G02X266517I-1000J-1120D01*
G37*
G36*
G01X261810Y552617D02*
G03X261824Y552034I281J-285D01*
G02X259824I-1000J-1120D01*
G03X259838Y552617I-267J298D01*
G02X261810I986J997D01*
G37*
G36*
G01X244378D02*
G03X244392Y552034I281J-285D01*
G02X242392I-1000J-1120D01*
G03X242406Y552617I-267J298D01*
G02X244378I986J997D01*
G37*
G36*
G01X238092Y552578D02*
G03X238119Y552017I298J-267D01*
G02X236038Y551977I-1020J-1103D01*
G03X236042Y552538I-283J283D01*
G02X238092Y552578I1006J976D01*
G37*
G36*
G01X229706Y552034D02*
G03X229720Y552617I-267J298D01*
G02X231692I986J997D01*
G03X231706Y552034I281J-285D01*
G02X229706I-1000J-1120D01*
G37*
G36*
G01X224999Y552617D02*
G03X225013Y552034I281J-285D01*
G02X223013I-1000J-1120D01*
G03X223027Y552617I-267J298D01*
G02X224999I986J997D01*
G37*
G36*
G01X207567D02*
G03X207581Y552034I281J-285D01*
G02X205581I-1000J-1120D01*
G03X205595Y552617I-267J298D01*
G02X207567I986J997D01*
G37*
G36*
G01X201281Y552578D02*
G03X201308Y552017I298J-267D01*
G02X199227Y551977I-1020J-1103D01*
G03X199231Y552538I-283J283D01*
G02X201281Y552578I1006J976D01*
G37*
G36*
G01X192895Y552034D02*
G03X192909Y552617I-267J298D01*
G02X194881I986J997D01*
G03X194895Y552034I281J-285D01*
G02X192895I-1000J-1120D01*
G37*
G36*
G01X188188Y552617D02*
G03X188202Y552034I281J-285D01*
G02X186202I-1000J-1120D01*
G03X186216Y552617I-267J298D01*
G02X188188I986J997D01*
G37*
G36*
G01X170776Y552587D02*
G03X170791Y552016I287J-278D01*
G02X168749I-1021J-1102D01*
G03X168764Y552587I-272J293D01*
G02X170776I1006J977D01*
G37*
G36*
G01X164470Y552578D02*
G03X164497Y552017I298J-267D01*
G02X162416Y551977I-1020J-1103D01*
G03X162420Y552538I-283J283D01*
G02X164470Y552578I1006J976D01*
G37*
G36*
G01X156084Y552034D02*
G03X156098Y552617I-267J298D01*
G02X158070I986J997D01*
G03X158084Y552034I281J-285D01*
G02X156084I-1000J-1120D01*
G37*
G36*
G01X151377Y552617D02*
G03X151391Y552034I281J-285D01*
G02X149391I-1000J-1120D01*
G03X149405Y552617I-267J298D01*
G02X151377I986J997D01*
G37*
G36*
G01X133945D02*
G03X133959Y552034I281J-285D01*
G02X131959I-1000J-1120D01*
G03X131973Y552617I-267J298D01*
G02X133945I986J997D01*
G37*
G36*
G01X125605Y551977D02*
G03X125609Y552538I-283J283D01*
G02X127659Y552578I1006J976D01*
G03X127686Y552017I298J-267D01*
G02X125605Y551977I-1020J-1103D01*
G37*
G36*
G01X358510Y552100D02*
G03Y551522I277J-289D01*
G02X356568I-971J-1011D01*
G03Y552100I-277J289D01*
G02X358510I971J1011D01*
G37*
G36*
G01X581206Y549543D02*
G03X581187Y548936I251J-312D01*
G02X579315Y548951I-944J-1036D01*
G03X579306Y549559I-265J300D01*
G02X579170Y551741I960J1155D01*
G03Y552287I-292J273D01*
G02X579225Y554397I1096J1027D01*
G03X579241Y554958I-277J289D01*
G02X581291I1025J956D01*
G03X581307Y554397I293J-272D01*
G02X581362Y552287I-1041J-1083D01*
G03Y551741I292J-273D01*
G02X581206Y549543I-1096J-1027D01*
G37*
G36*
G01X544395D02*
G03X544376Y548936I251J-312D01*
G02X542504Y548951I-944J-1036D01*
G03X542495Y549559I-265J300D01*
G02X542359Y551741I960J1155D01*
G03Y552287I-292J273D01*
G02X542414Y554397I1096J1027D01*
G03X542430Y554958I-277J289D01*
G02X544480I1025J956D01*
G03X544496Y554397I293J-272D01*
G02X544551Y552287I-1041J-1083D01*
G03Y551741I292J-273D01*
G02X544395Y549543I-1096J-1027D01*
G37*
G36*
G01X507584D02*
G03X507565Y548936I251J-312D01*
G02X505693Y548951I-944J-1036D01*
G03X505684Y549559I-265J300D01*
G02X505548Y551741I960J1155D01*
G03Y552287I-292J273D01*
G02X505603Y554397I1096J1027D01*
G03X505619Y554958I-277J289D01*
G02X507669I1025J956D01*
G03X507685Y554397I293J-272D01*
G02X507740Y552287I-1041J-1083D01*
G03Y551741I292J-273D01*
G02X507584Y549543I-1096J-1027D01*
G37*
G36*
G01X470772D02*
G03X470753Y548936I251J-312D01*
G02X468881Y548951I-944J-1036D01*
G03X468872Y549559I-265J300D01*
G02X468736Y551741I960J1155D01*
G03Y552287I-292J273D01*
G02X468791Y554397I1096J1027D01*
G03X468807Y554958I-277J289D01*
G02X470857I1025J956D01*
G03X470873Y554397I293J-272D01*
G02X470928Y552287I-1041J-1083D01*
G03Y551741I292J-273D01*
G02X470772Y549543I-1096J-1027D01*
G37*
G36*
G01X290064D02*
G03X290045Y548936I251J-312D01*
G02X288173Y548951I-944J-1036D01*
G03X288164Y549559I-265J300D01*
G02X288028Y551741I960J1155D01*
G03Y552287I-292J273D01*
G02X288083Y554397I1096J1027D01*
G03X288099Y554958I-277J289D01*
G02X290149I1025J956D01*
G03X290165Y554397I293J-272D01*
G02X290220Y552287I-1041J-1083D01*
G03Y551741I292J-273D01*
G02X290064Y549543I-1096J-1027D01*
G37*
G36*
G01X253253D02*
G03X253234Y548936I251J-312D01*
G02X251362Y548951I-944J-1036D01*
G03X251353Y549559I-265J300D01*
G02X251217Y551741I960J1155D01*
G03Y552287I-292J273D01*
G02X251272Y554397I1096J1027D01*
G03X251288Y554958I-277J289D01*
G02X253338I1025J956D01*
G03X253354Y554397I293J-272D01*
G02X253409Y552287I-1041J-1083D01*
G03Y551741I292J-273D01*
G02X253253Y549543I-1096J-1027D01*
G37*
G36*
G01X216442D02*
G03X216423Y548936I251J-312D01*
G02X214551Y548951I-944J-1036D01*
G03X214542Y549559I-265J300D01*
G02X214406Y551741I960J1155D01*
G03Y552287I-292J273D01*
G02X214461Y554397I1096J1027D01*
G03X214477Y554958I-277J289D01*
G02X216527I1025J956D01*
G03X216543Y554397I293J-272D01*
G02X216598Y552287I-1041J-1083D01*
G03Y551741I292J-273D01*
G02X216442Y549543I-1096J-1027D01*
G37*
G36*
G01X179631D02*
G03X179612Y548936I251J-312D01*
G02X177740Y548951I-944J-1036D01*
G03X177731Y549559I-265J300D01*
G02X177595Y551741I960J1155D01*
G03Y552287I-292J273D01*
G02X177650Y554397I1096J1027D01*
G03X177666Y554958I-277J289D01*
G02X179716I1025J956D01*
G03X179732Y554397I293J-272D01*
G02X179787Y552287I-1041J-1083D01*
G03Y551741I292J-273D01*
G02X179631Y549543I-1096J-1027D01*
G37*
G36*
G01X142820D02*
G03X142801Y548936I251J-312D01*
G02X140929Y548951I-944J-1036D01*
G03X140920Y549559I-265J300D01*
G02X140784Y551741I960J1155D01*
G03Y552287I-292J273D01*
G02X140839Y554397I1096J1027D01*
G03X140855Y554958I-277J289D01*
G02X142905I1025J956D01*
G03X142921Y554397I293J-272D01*
G02X142976Y552287I-1041J-1083D01*
G03Y551741I292J-273D01*
G02X142820Y549543I-1096J-1027D01*
G37*
G36*
G01X576206Y549416D02*
G03X576191Y548855I277J-288D01*
G02X574141I-1025J-957D01*
G03X574126Y549416I-292J273D01*
G02X574070Y551527I1040J1084D01*
G03Y552073I-292J273D01*
G02X574115Y554173I1096J1027D01*
G03X574125Y554735I-280J286D01*
G02X576176Y554753I1017J965D01*
G03X576197Y554192I295J-270D01*
G02X576262Y552073I-1031J-1092D01*
G03Y551527I292J-273D01*
G02X576206Y549416I-1096J-1027D01*
G37*
G36*
G01X539395D02*
G03X539380Y548855I277J-288D01*
G02X537330I-1025J-957D01*
G03X537315Y549416I-292J273D01*
G02X537259Y551527I1040J1084D01*
G03Y552073I-292J273D01*
G02X537304Y554173I1096J1027D01*
G03X537314Y554735I-280J286D01*
G02X539365Y554753I1017J965D01*
G03X539386Y554192I295J-270D01*
G02X539451Y552073I-1031J-1092D01*
G03Y551527I292J-273D01*
G02X539395Y549416I-1096J-1027D01*
G37*
G36*
G01X502584D02*
G03X502569Y548855I277J-288D01*
G02X500519I-1025J-957D01*
G03X500504Y549416I-292J273D01*
G02X500448Y551527I1040J1084D01*
G03Y552073I-292J273D01*
G02X500493Y554173I1096J1027D01*
G03X500503Y554735I-280J286D01*
G02X502554Y554753I1017J965D01*
G03X502575Y554192I295J-270D01*
G02X502640Y552073I-1031J-1092D01*
G03Y551527I292J-273D01*
G02X502584Y549416I-1096J-1027D01*
G37*
G36*
G01X463707Y548855D02*
G03X463692Y549416I-292J273D01*
G02X463636Y551527I1040J1084D01*
G03Y552073I-292J273D01*
G02X463681Y554173I1096J1027D01*
G03X463691Y554735I-280J286D01*
G02X465742Y554753I1017J965D01*
G03X465763Y554192I295J-270D01*
G02X465828Y552073I-1031J-1092D01*
G03Y551527I292J-273D01*
G02X465772Y549416I-1096J-1027D01*
G03X465757Y548855I277J-288D01*
G02X463707I-1025J-957D01*
G37*
G36*
G01X285064Y549416D02*
G03X285049Y548855I277J-288D01*
G02X282999I-1025J-957D01*
G03X282984Y549416I-292J273D01*
G02X282928Y551527I1040J1084D01*
G03Y552073I-292J273D01*
G02X282973Y554173I1096J1027D01*
G03X282983Y554735I-280J286D01*
G02X285034Y554753I1017J965D01*
G03X285055Y554192I295J-270D01*
G02X285120Y552073I-1031J-1092D01*
G03Y551527I292J-273D01*
G02X285064Y549416I-1096J-1027D01*
G37*
G36*
G01X248253D02*
G03X248238Y548855I277J-288D01*
G02X246188I-1025J-957D01*
G03X246173Y549416I-292J273D01*
G02X246117Y551527I1040J1084D01*
G03Y552073I-292J273D01*
G02X246162Y554173I1096J1027D01*
G03X246172Y554735I-280J286D01*
G02X248223Y554753I1017J965D01*
G03X248244Y554192I295J-270D01*
G02X248309Y552073I-1031J-1092D01*
G03Y551527I292J-273D01*
G02X248253Y549416I-1096J-1027D01*
G37*
G36*
G01X211442D02*
G03X211427Y548855I277J-288D01*
G02X209377I-1025J-957D01*
G03X209362Y549416I-292J273D01*
G02X209306Y551527I1040J1084D01*
G03Y552073I-292J273D01*
G02X209351Y554173I1096J1027D01*
G03X209361Y554735I-280J286D01*
G02X211412Y554753I1017J965D01*
G03X211433Y554192I295J-270D01*
G02X211498Y552073I-1031J-1092D01*
G03Y551527I292J-273D01*
G02X211442Y549416I-1096J-1027D01*
G37*
G36*
G01X174631D02*
G03X174616Y548855I277J-288D01*
G02X172566I-1025J-957D01*
G03X172551Y549416I-292J273D01*
G02X172495Y551527I1040J1084D01*
G03Y552073I-292J273D01*
G02X172540Y554173I1096J1027D01*
G03X172550Y554735I-280J286D01*
G02X174601Y554753I1017J965D01*
G03X174622Y554192I295J-270D01*
G02X174687Y552073I-1031J-1092D01*
G03Y551527I292J-273D01*
G02X174631Y549416I-1096J-1027D01*
G37*
G36*
G01X135755Y548855D02*
G03X135740Y549416I-292J273D01*
G02X135684Y551527I1040J1084D01*
G03Y552073I-292J273D01*
G02X135729Y554173I1096J1027D01*
G03X135739Y554735I-280J286D01*
G02X137790Y554753I1017J965D01*
G03X137811Y554192I295J-270D01*
G02X137876Y552073I-1031J-1092D01*
G03Y551527I292J-273D01*
G02X137820Y549416I-1096J-1027D01*
G03X137805Y548855I277J-288D01*
G02X135755I-1025J-957D01*
G37*
G36*
G01X363180Y546875D02*
G03X362603I-289J-277D01*
G02Y548953I-1085J1039D01*
G03X363180I289J277D01*
G02Y546875I1085J-1039D01*
G37*
G36*
G01X375768Y544799D02*
G03X375791Y545360I-273J292D01*
G02X377840Y545331I1038J943D01*
G03X377847Y544769I288J-277D01*
G02X375768Y544799I-1055J-1069D01*
G37*
G36*
G01X248301Y533364D02*
G03X248307Y532807I290J-275D01*
G02X246151Y532785I-1067J-1057D01*
G03X246145Y533342I-290J275D01*
G02X246172Y535482I1068J1057D01*
G03X246188Y536043I-277J289D01*
G02X248238I1025J956D01*
G03X248254Y535482I293J-272D01*
G02X248301Y533364I-1041J-1083D01*
G37*
G36*
G01X358688Y533045D02*
G03Y532501I293J-272D01*
G02X356634I-1027J-955D01*
G03Y533045I-293J272D01*
G02X358688I1027J955D01*
G37*
G36*
G01X576233Y530667D02*
G03X576217Y530106I277J-289D01*
G02X574167I-1025J-956D01*
G03X574151Y530667I-293J272D01*
G02X574104Y532785I1041J1083D01*
G03X574098Y533342I-290J275D01*
G02X574125Y535482I1068J1057D01*
G03X574141Y536043I-277J289D01*
G02X576191I1025J956D01*
G03X576207Y535482I293J-272D01*
G02X576254Y533364I-1041J-1083D01*
G03X576260Y532807I290J-275D01*
G02X576233Y530667I-1068J-1057D01*
G37*
G36*
G01X539422D02*
G03X539406Y530106I277J-289D01*
G02X537356I-1025J-956D01*
G03X537340Y530667I-293J272D01*
G02X537293Y532785I1041J1083D01*
G03X537287Y533342I-290J275D01*
G02X537314Y535482I1068J1057D01*
G03X537330Y536043I-277J289D01*
G02X539380I1025J956D01*
G03X539396Y535482I293J-272D01*
G02X539443Y533364I-1041J-1083D01*
G03X539449Y532807I290J-275D01*
G02X539422Y530667I-1068J-1057D01*
G37*
G36*
G01X502611D02*
G03X502595Y530106I277J-289D01*
G02X500545I-1025J-956D01*
G03X500529Y530667I-293J272D01*
G02X500482Y532785I1041J1083D01*
G03X500476Y533342I-290J275D01*
G02X500503Y535482I1068J1057D01*
G03X500519Y536043I-277J289D01*
G02X502569I1025J956D01*
G03X502585Y535482I293J-272D01*
G02X502632Y533364I-1041J-1083D01*
G03X502638Y532807I290J-275D01*
G02X502611Y530667I-1068J-1057D01*
G37*
G36*
G01X465799D02*
G03X465783Y530106I277J-289D01*
G02X463733I-1025J-956D01*
G03X463717Y530667I-293J272D01*
G02X463670Y532785I1041J1083D01*
G03X463664Y533342I-290J275D01*
G02X463691Y535482I1068J1057D01*
G03X463707Y536043I-277J289D01*
G02X465757I1025J956D01*
G03X465773Y535482I293J-272D01*
G02X465820Y533364I-1041J-1083D01*
G03X465826Y532807I290J-275D01*
G02X465799Y530667I-1068J-1057D01*
G37*
G36*
G01X285091D02*
G03X285075Y530106I277J-289D01*
G02X283025I-1025J-956D01*
G03X283009Y530667I-293J272D01*
G02X282962Y532785I1041J1083D01*
G03X282956Y533342I-290J275D01*
G02X282983Y535482I1068J1057D01*
G03X282999Y536043I-277J289D01*
G02X285049I1025J956D01*
G03X285065Y535482I293J-272D01*
G02X285112Y533364I-1041J-1083D01*
G03X285118Y532807I290J-275D01*
G02X285091Y530667I-1068J-1057D01*
G37*
G36*
G01X211469D02*
G03X211453Y530106I277J-289D01*
G02X209403I-1025J-956D01*
G03X209387Y530667I-293J272D01*
G02X209340Y532785I1041J1083D01*
G03X209334Y533342I-290J275D01*
G02X209361Y535482I1068J1057D01*
G03X209377Y536043I-277J289D01*
G02X211427I1025J956D01*
G03X211443Y535482I293J-272D01*
G02X211490Y533364I-1041J-1083D01*
G03X211496Y532807I290J-275D01*
G02X211469Y530667I-1068J-1057D01*
G37*
G36*
G01X174658D02*
G03X174642Y530106I277J-289D01*
G02X172592I-1025J-956D01*
G03X172576Y530667I-293J272D01*
G02X172529Y532785I1041J1083D01*
G03X172523Y533342I-290J275D01*
G02X172550Y535482I1068J1057D01*
G03X172566Y536043I-277J289D01*
G02X174616I1025J956D01*
G03X174632Y535482I293J-272D01*
G02X174679Y533364I-1041J-1083D01*
G03X174685Y532807I290J-275D01*
G02X174658Y530667I-1068J-1057D01*
G37*
G36*
G01X135781Y530106D02*
G03X135765Y530667I-293J272D01*
G02X135718Y532785I1041J1083D01*
G03X135712Y533342I-290J275D01*
G02X135739Y535482I1068J1057D01*
G03X135755Y536043I-277J289D01*
G02X137805I1025J956D01*
G03X137821Y535482I293J-272D01*
G02X137868Y533364I-1041J-1083D01*
G03X137874Y532807I290J-275D01*
G02X137847Y530667I-1068J-1057D01*
G03X137831Y530106I277J-289D01*
G02X135781I-1025J-956D01*
G37*
G36*
G01X581311Y530461D02*
G03X581298Y529899I278J-288D01*
G02X579250Y529889I-1019J-963D01*
G03X579232Y530450I-293J271D01*
G02X579173Y532570I1034J1090D01*
G03Y533119I-291J274D01*
G02X579236Y535243I1093J1031D01*
G03X579257Y535804I-274J291D01*
G02X581307Y535783I1035J946D01*
G03X581317Y535222I290J-275D01*
G02X581359Y533119I-1051J-1073D01*
G03Y532570I291J-274D01*
G02X581311Y530461I-1093J-1030D01*
G37*
G36*
G01X544500D02*
G03X544487Y529899I278J-288D01*
G02X542439Y529889I-1019J-963D01*
G03X542421Y530450I-293J271D01*
G02X542362Y532570I1034J1090D01*
G03Y533119I-291J274D01*
G02X542425Y535243I1093J1031D01*
G03X542446Y535804I-274J291D01*
G02X544496Y535783I1035J946D01*
G03X544506Y535222I290J-275D01*
G02X544548Y533119I-1051J-1073D01*
G03Y532570I291J-274D01*
G02X544500Y530461I-1093J-1030D01*
G37*
G36*
G01X507689D02*
G03X507676Y529899I278J-288D01*
G02X505628Y529889I-1019J-963D01*
G03X505610Y530450I-293J271D01*
G02X505551Y532570I1034J1090D01*
G03Y533119I-291J274D01*
G02X505614Y535243I1093J1031D01*
G03X505635Y535804I-274J291D01*
G02X507685Y535783I1035J946D01*
G03X507695Y535222I290J-275D01*
G02X507737Y533119I-1051J-1073D01*
G03Y532570I291J-274D01*
G02X507689Y530461I-1093J-1030D01*
G37*
G36*
G01X470877D02*
G03X470864Y529899I278J-288D01*
G02X468816Y529889I-1019J-963D01*
G03X468798Y530450I-293J271D01*
G02X468739Y532570I1034J1090D01*
G03Y533119I-291J274D01*
G02X468802Y535243I1093J1031D01*
G03X468823Y535804I-274J291D01*
G02X470873Y535783I1035J946D01*
G03X470883Y535222I290J-275D01*
G02X470925Y533119I-1051J-1073D01*
G03Y532570I291J-274D01*
G02X470877Y530461I-1093J-1030D01*
G37*
G36*
G01X290169D02*
G03X290156Y529899I278J-288D01*
G02X288108Y529889I-1019J-963D01*
G03X288090Y530450I-293J271D01*
G02X288031Y532570I1034J1090D01*
G03Y533119I-291J274D01*
G02X288094Y535243I1093J1031D01*
G03X288115Y535804I-274J291D01*
G02X290165Y535783I1035J946D01*
G03X290175Y535222I290J-275D01*
G02X290217Y533119I-1051J-1073D01*
G03Y532570I291J-274D01*
G02X290169Y530461I-1093J-1030D01*
G37*
G36*
G01X253358D02*
G03X253345Y529899I278J-288D01*
G02X251297Y529889I-1019J-963D01*
G03X251279Y530450I-293J271D01*
G02X251220Y532570I1034J1090D01*
G03Y533119I-291J274D01*
G02X251283Y535243I1093J1031D01*
G03X251304Y535804I-274J291D01*
G02X253354Y535783I1035J946D01*
G03X253364Y535222I290J-275D01*
G02X253406Y533119I-1051J-1073D01*
G03Y532570I291J-274D01*
G02X253358Y530461I-1093J-1030D01*
G37*
G36*
G01X216547D02*
G03X216534Y529899I278J-288D01*
G02X214486Y529889I-1019J-963D01*
G03X214468Y530450I-293J271D01*
G02X214409Y532570I1034J1090D01*
G03Y533119I-291J274D01*
G02X214472Y535243I1093J1031D01*
G03X214493Y535804I-274J291D01*
G02X216543Y535783I1035J946D01*
G03X216553Y535222I290J-275D01*
G02X216595Y533119I-1051J-1073D01*
G03Y532570I291J-274D01*
G02X216547Y530461I-1093J-1030D01*
G37*
G36*
G01X179736D02*
G03X179723Y529899I278J-288D01*
G02X177675Y529889I-1019J-963D01*
G03X177657Y530450I-293J271D01*
G02X177598Y532570I1034J1090D01*
G03Y533119I-291J274D01*
G02X177661Y535243I1093J1031D01*
G03X177682Y535804I-274J291D01*
G02X179732Y535783I1035J946D01*
G03X179742Y535222I290J-275D01*
G02X179784Y533119I-1051J-1073D01*
G03Y532570I291J-274D01*
G02X179736Y530461I-1093J-1030D01*
G37*
G36*
G01X142925D02*
G03X142912Y529899I278J-288D01*
G02X140864Y529889I-1019J-963D01*
G03X140846Y530450I-293J271D01*
G02X140787Y532570I1034J1090D01*
G03Y533119I-291J274D01*
G02X140850Y535243I1093J1031D01*
G03X140871Y535804I-274J291D01*
G02X142921Y535783I1035J946D01*
G03X142931Y535222I290J-275D01*
G02X142973Y533119I-1051J-1073D01*
G03Y532570I291J-274D01*
G02X142925Y530461I-1093J-1030D01*
G37*
G36*
G01X90087Y523218D02*
G03X90675Y523142I328J229D01*
G02X90418Y521141I975J-1142D01*
G03X89830Y521217I-328J-229D01*
G02X90087Y523218I-975J1142D01*
G37*
G36*
G01X376324Y517869D02*
G03Y517343I302J-263D01*
G02X374060I-1132J-987D01*
G03Y517869I-302J263D01*
G02X376324I1132J987D01*
G37*
G36*
G01X362698Y516269D02*
G03X363249Y516258I281J284D01*
G02X363209Y514083I1016J-1107D01*
G03X362658Y514094I-281J-284D01*
G02X362698Y516269I-1016J1107D01*
G37*
G36*
G01X596456Y514817D02*
G03X596470Y514234I281J-285D01*
G02X594470I-1000J-1120D01*
G03X594484Y514817I-267J298D01*
G02X596456I986J997D01*
G37*
G36*
G01X589763D02*
G03X589777Y514234I281J-285D01*
G02X587777I-1000J-1120D01*
G03X587791Y514817I-267J298D01*
G02X589763I986J997D01*
G37*
G36*
G01X572331D02*
G03X572345Y514234I281J-285D01*
G02X570345I-1000J-1120D01*
G03X570359Y514817I-267J298D01*
G02X572331I986J997D01*
G37*
G36*
G01X559645D02*
G03X559659Y514234I281J-285D01*
G02X557659I-1000J-1120D01*
G03X557673Y514817I-267J298D01*
G02X559645I986J997D01*
G37*
G36*
G01X552952D02*
G03X552966Y514234I281J-285D01*
G02X550966I-1000J-1120D01*
G03X550980Y514817I-267J298D01*
G02X552952I986J997D01*
G37*
G36*
G01X535520D02*
G03X535534Y514234I281J-285D01*
G02X533534I-1000J-1120D01*
G03X533548Y514817I-267J298D01*
G02X535520I986J997D01*
G37*
G36*
G01X529234Y514778D02*
G03X529261Y514217I298J-267D01*
G02X527180Y514177I-1020J-1103D01*
G03X527184Y514738I-283J283D01*
G02X529234Y514778I1006J976D01*
G37*
G36*
G01X520848Y514234D02*
G03X520862Y514817I-267J298D01*
G02X522834I986J997D01*
G03X522848Y514234I281J-285D01*
G02X520848I-1000J-1120D01*
G37*
G36*
G01X516141Y514817D02*
G03X516155Y514234I281J-285D01*
G02X514155I-1000J-1120D01*
G03X514169Y514817I-267J298D01*
G02X516141I986J997D01*
G37*
G36*
G01X498709D02*
G03X498723Y514234I281J-285D01*
G02X496723I-1000J-1120D01*
G03X496737Y514817I-267J298D01*
G02X498709I986J997D01*
G37*
G36*
G01X492423Y514778D02*
G03X492450Y514217I298J-267D01*
G02X490369Y514177I-1020J-1103D01*
G03X490373Y514738I-283J283D01*
G02X492423Y514778I1006J976D01*
G37*
G36*
G01X484037Y514234D02*
G03X484051Y514817I-267J298D01*
G02X486023I986J997D01*
G03X486037Y514234I281J-285D01*
G02X484037I-1000J-1120D01*
G37*
G36*
G01X479330Y514817D02*
G03X479344Y514234I281J-285D01*
G02X477344I-1000J-1120D01*
G03X477358Y514817I-267J298D01*
G02X479330I986J997D01*
G37*
G36*
G01X461937Y514758D02*
G03X461953Y514197I293J-272D01*
G02X459871I-1041J-1083D01*
G03X459887Y514758I-277J289D01*
G02X461937I1025J956D01*
G37*
G36*
G01X455612Y514778D02*
G03X455639Y514217I298J-267D01*
G02X453558Y514177I-1020J-1103D01*
G03X453562Y514738I-283J283D01*
G02X455612Y514778I1006J976D01*
G37*
G36*
G01X305282Y514835D02*
G03X305307Y514253I286J-279D01*
G02X303307Y514216I-979J-1139D01*
G03X303311Y514799I-272J293D01*
G02X305282Y514835I967J1015D01*
G37*
G36*
G01X298621Y514817D02*
G03X298635Y514234I281J-285D01*
G02X296635I-1000J-1120D01*
G03X296649Y514817I-267J298D01*
G02X298621I986J997D01*
G37*
G36*
G01X281189D02*
G03X281203Y514234I281J-285D01*
G02X279203I-1000J-1120D01*
G03X279217Y514817I-267J298D01*
G02X281189I986J997D01*
G37*
G36*
G01X274903Y514778D02*
G03X274930Y514217I298J-267D01*
G02X272849Y514177I-1020J-1103D01*
G03X272853Y514738I-283J283D01*
G02X274903Y514778I1006J976D01*
G37*
G36*
G01X266517Y514234D02*
G03X266531Y514817I-267J298D01*
G02X268503I986J997D01*
G03X268517Y514234I281J-285D01*
G02X266517I-1000J-1120D01*
G37*
G36*
G01X261810Y514817D02*
G03X261824Y514234I281J-285D01*
G02X259824I-1000J-1120D01*
G03X259838Y514817I-267J298D01*
G02X261810I986J997D01*
G37*
G36*
G01X244378D02*
G03X244392Y514234I281J-285D01*
G02X242392I-1000J-1120D01*
G03X242406Y514817I-267J298D01*
G02X244378I986J997D01*
G37*
G36*
G01X238092Y514778D02*
G03X238119Y514217I298J-267D01*
G02X236038Y514177I-1020J-1103D01*
G03X236042Y514738I-283J283D01*
G02X238092Y514778I1006J976D01*
G37*
G36*
G01X229706Y514234D02*
G03X229720Y514817I-267J298D01*
G02X231692I986J997D01*
G03X231706Y514234I281J-285D01*
G02X229706I-1000J-1120D01*
G37*
G36*
G01X224999Y514817D02*
G03X225013Y514234I281J-285D01*
G02X223013I-1000J-1120D01*
G03X223027Y514817I-267J298D01*
G02X224999I986J997D01*
G37*
G36*
G01X207567D02*
G03X207581Y514234I281J-285D01*
G02X205581I-1000J-1120D01*
G03X205595Y514817I-267J298D01*
G02X207567I986J997D01*
G37*
G36*
G01X201281Y514778D02*
G03X201308Y514217I298J-267D01*
G02X199227Y514177I-1020J-1103D01*
G03X199231Y514738I-283J283D01*
G02X201281Y514778I1006J976D01*
G37*
G36*
G01X192895Y514234D02*
G03X192909Y514817I-267J298D01*
G02X194881I986J997D01*
G03X194895Y514234I281J-285D01*
G02X192895I-1000J-1120D01*
G37*
G36*
G01X188188Y514817D02*
G03X188202Y514234I281J-285D01*
G02X186202I-1000J-1120D01*
G03X186216Y514817I-267J298D01*
G02X188188I986J997D01*
G37*
G36*
G01X170776Y514787D02*
G03X170791Y514216I287J-278D01*
G02X168749I-1021J-1102D01*
G03X168764Y514787I-272J293D01*
G02X170776I1006J977D01*
G37*
G36*
G01X164470Y514778D02*
G03X164497Y514217I298J-267D01*
G02X162416Y514177I-1020J-1103D01*
G03X162420Y514738I-283J283D01*
G02X164470Y514778I1006J976D01*
G37*
G36*
G01X156084Y514234D02*
G03X156098Y514817I-267J298D01*
G02X158070I986J997D01*
G03X158084Y514234I281J-285D01*
G02X156084I-1000J-1120D01*
G37*
G36*
G01X151377Y514817D02*
G03X151391Y514234I281J-285D01*
G02X149391I-1000J-1120D01*
G03X149405Y514817I-267J298D01*
G02X151377I986J997D01*
G37*
G36*
G01X133945D02*
G03X133959Y514234I281J-285D01*
G02X131959I-1000J-1120D01*
G03X131973Y514817I-267J298D01*
G02X133945I986J997D01*
G37*
G36*
G01X125605Y514177D02*
G03X125609Y514738I-283J283D01*
G02X127659Y514778I1006J976D01*
G03X127686Y514217I298J-267D01*
G02X125605Y514177I-1020J-1103D01*
G37*
G36*
G01X468736Y513941D02*
G03Y514487I-292J273D01*
G02X468791Y516597I1096J1027D01*
G03X468807Y517158I-277J289D01*
G02X470857I1025J956D01*
G03X470873Y516597I293J-272D01*
G02X470928Y514487I-1041J-1083D01*
G03Y513941I292J-273D01*
G02X468736I-1096J-1027D01*
G37*
G36*
G01X177595D02*
G03Y514487I-292J273D01*
G02X177650Y516597I1096J1027D01*
G03X177666Y517158I-277J289D01*
G02X179716I1025J956D01*
G03X179732Y516597I293J-272D01*
G02X179787Y514487I-1041J-1083D01*
G03Y513941I292J-273D01*
G02X177595I-1096J-1027D01*
G37*
G36*
G01X449194Y513991D02*
G03X448982Y513435I144J-373D01*
G02X447233Y514103I-1247J-641D01*
G03X447445Y514659I-144J373D01*
G02X449194Y513991I1247J641D01*
G37*
G36*
G01X581206Y511743D02*
G03X581187Y511136I251J-312D01*
G02X579315Y511151I-944J-1036D01*
G03X579306Y511759I-265J300D01*
G02X579170Y513941I960J1155D01*
G03Y514487I-292J273D01*
G02X579225Y516597I1096J1027D01*
G03X579241Y517158I-277J289D01*
G02X581291I1025J956D01*
G03X581307Y516597I293J-272D01*
G02X581362Y514487I-1041J-1083D01*
G03Y513941I292J-273D01*
G02X581206Y511743I-1096J-1027D01*
G37*
G36*
G01X544395D02*
G03X544376Y511136I251J-312D01*
G02X542504Y511151I-944J-1036D01*
G03X542495Y511759I-265J300D01*
G02X542359Y513941I960J1155D01*
G03Y514487I-292J273D01*
G02X542414Y516597I1096J1027D01*
G03X542430Y517158I-277J289D01*
G02X544480I1025J956D01*
G03X544496Y516597I293J-272D01*
G02X544551Y514487I-1041J-1083D01*
G03Y513941I292J-273D01*
G02X544395Y511743I-1096J-1027D01*
G37*
G36*
G01X507584D02*
G03X507565Y511136I251J-312D01*
G02X505693Y511151I-944J-1036D01*
G03X505684Y511759I-265J300D01*
G02X505548Y513941I960J1155D01*
G03Y514487I-292J273D01*
G02X505603Y516597I1096J1027D01*
G03X505619Y517158I-277J289D01*
G02X507669I1025J956D01*
G03X507685Y516597I293J-272D01*
G02X507740Y514487I-1041J-1083D01*
G03Y513941I292J-273D01*
G02X507584Y511743I-1096J-1027D01*
G37*
G36*
G01X290064D02*
G03X290045Y511136I251J-312D01*
G02X288173Y511151I-944J-1036D01*
G03X288164Y511759I-265J300D01*
G02X288028Y513941I960J1155D01*
G03Y514487I-292J273D01*
G02X288083Y516597I1096J1027D01*
G03X288099Y517158I-277J289D01*
G02X290149I1025J956D01*
G03X290165Y516597I293J-272D01*
G02X290220Y514487I-1041J-1083D01*
G03Y513941I292J-273D01*
G02X290064Y511743I-1096J-1027D01*
G37*
G36*
G01X253253D02*
G03X253234Y511136I251J-312D01*
G02X251362Y511151I-944J-1036D01*
G03X251353Y511759I-265J300D01*
G02X251217Y513941I960J1155D01*
G03Y514487I-292J273D01*
G02X251272Y516597I1096J1027D01*
G03X251288Y517158I-277J289D01*
G02X253338I1025J956D01*
G03X253354Y516597I293J-272D01*
G02X253409Y514487I-1041J-1083D01*
G03Y513941I292J-273D01*
G02X253253Y511743I-1096J-1027D01*
G37*
G36*
G01X216442D02*
G03X216423Y511136I251J-312D01*
G02X214551Y511151I-944J-1036D01*
G03X214542Y511759I-265J300D01*
G02X214406Y513941I960J1155D01*
G03Y514487I-292J273D01*
G02X214461Y516597I1096J1027D01*
G03X214477Y517158I-277J289D01*
G02X216527I1025J956D01*
G03X216543Y516597I293J-272D01*
G02X216598Y514487I-1041J-1083D01*
G03Y513941I292J-273D01*
G02X216442Y511743I-1096J-1027D01*
G37*
G36*
G01X142820D02*
G03X142801Y511136I251J-312D01*
G02X140929Y511151I-944J-1036D01*
G03X140920Y511759I-265J300D01*
G02X140784Y513941I960J1155D01*
G03Y514487I-292J273D01*
G02X140839Y516597I1096J1027D01*
G03X140855Y517158I-277J289D01*
G02X142905I1025J956D01*
G03X142921Y516597I293J-272D01*
G02X142976Y514487I-1041J-1083D01*
G03Y513941I292J-273D01*
G02X142820Y511743I-1096J-1027D01*
G37*
G36*
G01X576206Y511616D02*
G03X576191Y511055I277J-288D01*
G02X574141I-1025J-957D01*
G03X574126Y511616I-292J273D01*
G02X574070Y513727I1040J1084D01*
G03Y514273I-292J273D01*
G02X574115Y516373I1096J1027D01*
G03X574125Y516935I-280J286D01*
G02X576176Y516953I1017J965D01*
G03X576197Y516392I295J-270D01*
G02X576262Y514273I-1031J-1092D01*
G03Y513727I292J-273D01*
G02X576206Y511616I-1096J-1027D01*
G37*
G36*
G01X539395D02*
G03X539380Y511055I277J-288D01*
G02X537330I-1025J-957D01*
G03X537315Y511616I-292J273D01*
G02X537259Y513727I1040J1084D01*
G03Y514273I-292J273D01*
G02X537304Y516373I1096J1027D01*
G03X537314Y516935I-280J286D01*
G02X539365Y516953I1017J965D01*
G03X539386Y516392I295J-270D01*
G02X539451Y514273I-1031J-1092D01*
G03Y513727I292J-273D01*
G02X539395Y511616I-1096J-1027D01*
G37*
G36*
G01X502554Y516953D02*
G03X502575Y516392I295J-270D01*
G02X502640Y514273I-1031J-1092D01*
G03Y513727I292J-273D01*
G02X502584Y511616I-1096J-1027D01*
G03X502569Y511055I277J-288D01*
G02X500519I-1025J-957D01*
G03X500504Y511616I-292J273D01*
G02X500448Y513727I1040J1084D01*
G03Y514273I-292J273D01*
G02X500493Y516373I1096J1027D01*
G03X500503Y516935I-280J286D01*
G02X502554Y516953I1017J965D01*
G37*
G36*
G01X465742D02*
G03X465763Y516392I295J-270D01*
G02X465828Y514273I-1031J-1092D01*
G03Y513727I292J-273D01*
G02X465772Y511616I-1096J-1027D01*
G03X465757Y511055I277J-288D01*
G02X463707I-1025J-957D01*
G03X463692Y511616I-292J273D01*
G02X463636Y513727I1040J1084D01*
G03Y514273I-292J273D01*
G02X463681Y516373I1096J1027D01*
G03X463691Y516935I-280J286D01*
G02X465742Y516953I1017J965D01*
G37*
G36*
G01X285034D02*
G03X285055Y516392I295J-270D01*
G02X285120Y514273I-1031J-1092D01*
G03Y513727I292J-273D01*
G02X285064Y511616I-1096J-1027D01*
G03X285049Y511055I277J-288D01*
G02X282999I-1025J-957D01*
G03X282984Y511616I-292J273D01*
G02X282928Y513727I1040J1084D01*
G03Y514273I-292J273D01*
G02X282973Y516373I1096J1027D01*
G03X282983Y516935I-280J286D01*
G02X285034Y516953I1017J965D01*
G37*
G36*
G01X248253Y511616D02*
G03X248238Y511055I277J-288D01*
G02X246188I-1025J-957D01*
G03X246173Y511616I-292J273D01*
G02X246117Y513727I1040J1084D01*
G03Y514273I-292J273D01*
G02X246162Y516373I1096J1027D01*
G03X246172Y516935I-280J286D01*
G02X248223Y516953I1017J965D01*
G03X248244Y516392I295J-270D01*
G02X248309Y514273I-1031J-1092D01*
G03Y513727I292J-273D01*
G02X248253Y511616I-1096J-1027D01*
G37*
G36*
G01X209377Y511055D02*
G03X209362Y511616I-292J273D01*
G02X209306Y513727I1040J1084D01*
G03Y514273I-292J273D01*
G02X209351Y516373I1096J1027D01*
G03X209361Y516935I-280J286D01*
G02X211412Y516953I1017J965D01*
G03X211433Y516392I295J-270D01*
G02X211498Y514273I-1031J-1092D01*
G03Y513727I292J-273D01*
G02X211442Y511616I-1096J-1027D01*
G03X211427Y511055I277J-288D01*
G02X209377I-1025J-957D01*
G37*
G36*
G01X174631Y511616D02*
G03X174616Y511055I277J-288D01*
G02X172566I-1025J-957D01*
G03X172551Y511616I-292J273D01*
G02X172495Y513727I1040J1084D01*
G03Y514273I-292J273D01*
G02X172540Y516373I1096J1027D01*
G03X172550Y516935I-280J286D01*
G02X174601Y516953I1017J965D01*
G03X174622Y516392I295J-270D01*
G02X174687Y514273I-1031J-1092D01*
G03Y513727I292J-273D01*
G02X174631Y511616I-1096J-1027D01*
G37*
G36*
G01X135755Y511055D02*
G03X135740Y511616I-292J273D01*
G02X135684Y513727I1040J1084D01*
G03Y514273I-292J273D01*
G02X135729Y516373I1096J1027D01*
G03X135739Y516935I-280J286D01*
G02X137790Y516953I1017J965D01*
G03X137811Y516392I295J-270D01*
G02X137876Y514273I-1031J-1092D01*
G03Y513727I292J-273D01*
G02X137820Y511616I-1096J-1027D01*
G03X137805Y511055I277J-288D01*
G02X135755I-1025J-957D01*
G37*
G36*
G01X363180Y509075D02*
G03X362603I-289J-277D01*
G02Y511153I-1085J1039D01*
G03X363180I289J277D01*
G02Y509075I1085J-1039D01*
G37*
G36*
G01X92680Y619112D02*
G02X92697Y617091I1120J-1001D01*
G03X92140Y617120I-293J-272D01*
G02X89653Y618377I-990J1130D01*
G03X89277Y618810I-398J34D01*
G02X88140Y619433I83J1500D01*
G03X87482Y619421I-325J-233D01*
G02X87450Y621127I-1252J830D01*
G03X88108Y621139I325J233D01*
G02X90211Y621548I1252J-829D01*
G03X90774Y621660I227J329D01*
G02X92371Y619562I1178J-760D01*
G03X92280Y619239I59J-191D01*
G02X92369Y619128I-1126J-994D01*
G03X92680Y619112I162J117D01*
G37*
G36*
G01X603485Y611943D02*
G02Y613371I-1322J714D01*
G03X604188I351J190D01*
G02X606831I1322J-714D01*
G03X607535I352J191D01*
G02X610178I1321J-714D01*
G03X610881I352J190D01*
G02X613524I1321J-714D01*
G03X614228I352J191D01*
G02Y611943I1321J-714D01*
G03X613524I-352J-191D01*
G02X610881I-1321J714D01*
G03X610178I-352J-190D01*
G02X607535I-1321J714D01*
G03X606831I-352J-191D01*
G02X604188I-1321J714D01*
G03X603485I-352J-190D01*
G37*
G36*
G01X362540Y611528D02*
G02Y612956I-1322J714D01*
G03X363243I352J190D01*
G02Y611528I1322J-714D01*
G03X362540I-351J-190D01*
G37*
G36*
G01X629077Y611362D02*
G02X628127Y613414I-1372J611D01*
G03X628605Y613635I113J384D01*
G02X630020Y614525I1372J-611D01*
G03X630391Y615101I12J400D01*
G02X631698Y614258I1350J658D01*
G03X631327Y613682I-12J-400D01*
G02X629555Y611583I-1350J-658D01*
G03X629077Y611362I-113J-384D01*
G37*
G36*
G01X373249Y612344D02*
G02X372653Y610977I790J-1158D01*
G03X372021Y611241I-396J-59D01*
G02X372626Y612628I-887J1212D01*
G03X373249Y612344I397J46D01*
G37*
G36*
G01X479845Y610757D02*
G02X478979Y612061I-1501J-57D01*
G03X479548Y612425I169J363D01*
G02X480401Y611140I1402J5D01*
G03X479845Y610757I-156J-368D01*
G37*
G36*
G01X362540Y603900D02*
G02Y605328I-1322J714D01*
G03X363243I352J190D01*
G02Y603900I1322J-714D01*
G03X362540I-351J-190D01*
G37*
G36*
G01X606831Y603785D02*
G02Y605213I-1321J714D01*
G03X607535I352J191D01*
G02X610178I1321J-714D01*
G03X610881I352J190D01*
G02X613524I1321J-714D01*
G03X614228I352J191D01*
G02Y603785I1321J-714D01*
G03X613524I-352J-191D01*
G02X610881I-1321J714D01*
G03X610178I-352J-190D01*
G02X607535I-1321J714D01*
G03X606831I-352J-191D01*
G37*
G36*
G01X100596Y609843D02*
G02X99822Y611752I-5914J-1286D01*
G03X100547Y611857I339J211D01*
G02X101047Y612597I1351J-374D01*
G03X101105Y613178I-243J318D01*
G02X103253Y615272I1130J989D01*
G03X103852Y615337I271J294D01*
G02X104100Y613458I1148J-804D01*
G03X103506Y613365I-256J-307D01*
G02X103086Y612929I-1269J803D01*
G03X102999Y612351I227J-330D01*
G02X101189Y610273I-1101J-868D01*
G03X100596Y609843I-202J-345D01*
G37*
G36*
G01X371834Y592755D02*
G02X371756Y594717I-1175J936D01*
G03X372348Y594726I292J274D01*
G02X374538Y594619I1052J-926D01*
G03X375160Y594586I324J234D01*
G02X375066Y592831I1044J-936D01*
G03X374444Y592864I-324J-234D01*
G02X372425Y592793I-1044J936D01*
G03X371834Y592755I-278J-287D01*
G37*
G36*
G01X363286Y592928D02*
G02Y594356I-1322J714D01*
G03X363989I351J190D01*
G02Y592928I1322J-714D01*
G03X363286I-351J-190D01*
G37*
G36*
G01X606831Y592885D02*
G02Y594313I-1321J714D01*
G03X607535I352J191D01*
G02X610178I1321J-714D01*
G03X610881I352J190D01*
G02X613524I1321J-714D01*
G03X614228I352J191D01*
G02X616648Y594623I1321J-714D01*
G03X617218Y594608I292J273D01*
G02X617219Y592591I974J-1008D01*
G03X616648Y592576I-278J-288D01*
G02X614228Y592885I-1099J1023D01*
G03X613524I-352J-191D01*
G02X610881I-1321J714D01*
G03X610178I-352J-190D01*
G02X607535I-1321J714D01*
G03X606831I-352J-191D01*
G37*
G36*
G01X603485Y585043D02*
G02Y586471I-1322J714D01*
G03X604188I351J190D01*
G02X606831I1322J-714D01*
G03X607535I352J191D01*
G02X610178I1321J-714D01*
G03X610881I352J190D01*
G02X613524I1321J-714D01*
G03X614228I352J191D01*
G02Y585043I1321J-714D01*
G03X613524I-352J-191D01*
G02X610881I-1321J714D01*
G03X610178I-352J-190D01*
G02X607535I-1321J714D01*
G03X606831I-352J-191D01*
G02X604188I-1321J714D01*
G03X603485I-352J-190D01*
G37*
G36*
G01X652889Y584968D02*
G02X651662Y585549I-1138J-818D01*
G03X651961Y586182I-25J399D01*
G02X653188Y585601I1138J818D01*
G03X652889Y584968I25J-399D01*
G37*
G36*
G01X362540Y574028D02*
G02Y575456I-1322J714D01*
G03X363243I352J190D01*
G02Y574028I1322J-714D01*
G03X362540I-351J-190D01*
G37*
G36*
G01X617463Y575431D02*
G02X617088Y573582I829J-1131D01*
G03X616493Y573689I-344J-204D01*
G02X614228Y574143I-944J1168D01*
G03X613524I-352J-191D01*
G02X610881I-1321J714D01*
G03X610178I-352J-190D01*
G02X607535I-1321J714D01*
G03X606831I-352J-191D01*
G02X604188I-1321J714D01*
G03X603485I-352J-190D01*
G02Y575571I-1322J714D01*
G03X604188I351J190D01*
G02X606831I1322J-714D01*
G03X607535I352J191D01*
G02X610178I1321J-714D01*
G03X610881I352J190D01*
G02X613524I1321J-714D01*
G03X614228I352J191D01*
G02X616874Y575565I1321J-714D01*
G03X617463Y575431I353J188D01*
G37*
G36*
G01X362540Y566100D02*
G02Y567528I-1322J714D01*
G03X363243I352J190D01*
G02Y566100I1322J-714D01*
G03X362540I-351J-190D01*
G37*
G36*
G01X603485Y565985D02*
G02Y567413I-1322J714D01*
G03X604188I351J190D01*
G02X606831I1322J-714D01*
G03X607535I352J191D01*
G02X610178I1321J-714D01*
G03X610881I352J190D01*
G02X613524I1321J-714D01*
G03X614228I352J191D01*
G02Y565985I1321J-714D01*
G03X613524I-352J-191D01*
G02X610881I-1321J714D01*
G03X610178I-352J-190D01*
G02X607535I-1321J714D01*
G03X606831I-352J-191D01*
G02X604188I-1321J714D01*
G03X603485I-352J-190D01*
G37*
G36*
G01X362601Y555058D02*
G02Y556626I-1281J784D01*
G03X363284I341J208D01*
G02Y555058I1281J-784D01*
G03X362601I-341J-208D01*
G37*
G36*
G01X603485Y555085D02*
G02X600829Y555108I-1322J714D01*
G03X600126Y555120I-355J-184D01*
G02X600151Y556548I-1309J737D01*
G03X600854Y556536I355J184D01*
G02X603485Y556513I1309J-737D01*
G03X604188I351J190D01*
G02X606831I1322J-714D01*
G03X607535I352J191D01*
G02X610178I1321J-714D01*
G03X610881I352J190D01*
G02X613524I1321J-714D01*
G03X614228I352J191D01*
G02Y555085I1321J-714D01*
G03X613524I-352J-191D01*
G02X610881I-1321J714D01*
G03X610178I-352J-190D01*
G02X607535I-1321J714D01*
G03X606831I-352J-191D01*
G02X604188I-1321J714D01*
G03X603485I-352J-190D01*
G37*
G36*
G01Y547243D02*
G02Y548671I-1322J714D01*
G03X604188I351J190D01*
G02X606831I1322J-714D01*
G03X607535I352J191D01*
G02X610178I1321J-714D01*
G03X610881I352J190D01*
G02X613524I1321J-714D01*
G03X614228I352J191D01*
G02Y547243I1321J-714D01*
G03X613524I-352J-191D01*
G02X610881I-1321J714D01*
G03X610178I-352J-190D01*
G02X607535I-1321J714D01*
G03X606831I-352J-191D01*
G02X604188I-1321J714D01*
G03X603485I-352J-190D01*
G37*
G36*
G01Y536343D02*
G02Y537771I-1322J714D01*
G03X604188I351J190D01*
G02X606831I1322J-714D01*
G03X607535I352J191D01*
G02X610178I1321J-714D01*
G03X610881I352J190D01*
G02X613524I1321J-714D01*
G03X614228I352J191D01*
G02Y536343I1321J-714D01*
G03X613524I-352J-191D01*
G02X610881I-1321J714D01*
G03X610178I-352J-190D01*
G02X607535I-1321J714D01*
G03X606831I-352J-191D01*
G02X604188I-1321J714D01*
G03X603485I-352J-190D01*
G37*
G36*
G01X449294Y532244D02*
G02X447640Y532328I-884J-1088D01*
G03X447673Y532973I-219J335D01*
G02X447566Y535052I884J1088D01*
G03X447538Y535643I-283J283D01*
G02X449594Y537507I894J1080D01*
G03X450292Y537568I332J223D01*
G02X450411Y536215I1281J-569D01*
G03X449713Y536154I-332J-223D01*
G02X449423Y535732I-1281J570D01*
G03X449451Y535141I283J-283D01*
G02X449327Y532889I-894J-1080D01*
G03X449294Y532244I219J-335D01*
G37*
G36*
G01X606831Y528185D02*
G02Y529613I-1321J714D01*
G03X607535I352J191D01*
G02X610178I1321J-714D01*
G03X610881I352J190D01*
G02X613524I1321J-714D01*
G03X614228I352J191D01*
G02Y528185I1321J-714D01*
G03X613524I-352J-191D01*
G02X610881I-1321J714D01*
G03X610178I-352J-190D01*
G02X607535I-1321J714D01*
G03X606831I-352J-191D01*
G37*
G36*
G01Y517285D02*
G02Y518713I-1321J714D01*
G03X607535I352J191D01*
G02X610178I1321J-714D01*
G03X610881I352J190D01*
G02X613524I1321J-714D01*
G03X614228I352J191D01*
G02Y517285I1321J-714D01*
G03X613524I-352J-191D01*
G02X610881I-1321J714D01*
G03X610178I-352J-190D01*
G02X607535I-1321J714D01*
G03X606831I-352J-191D01*
G37*
G36*
G01X193499Y359219D02*
G03X192922Y359213I-286J-280D01*
G02X192901Y361154I-1022J960D01*
G03X193478Y361160I286J280D01*
G02X195472Y361211I1022J-960D01*
G03X196057Y361244I277J288D01*
G02X196165Y359339I1080J-894D01*
G03X195580Y359306I-277J-288D01*
G02X193499Y359219I-1080J894D01*
G37*
G36*
G01X417627Y339572D02*
G03X418248Y339563I314J248D01*
G02X418221Y337669I1152J-964D01*
G03X417600Y337678I-314J-248D01*
G02X415461Y337509I-1152J963D01*
G03X414935I-263J-302D01*
G02X412763Y337718I-987J1132D01*
G03X412133I-315J-246D01*
G02Y339564I-1185J923D01*
G03X412763I315J246D01*
G02X414935Y339773I1185J-923D01*
G03X415461I263J302D01*
G02X417627Y339572I987J-1132D01*
G37*
G36*
G01X399963Y337418D02*
G03X399333I-315J-246D01*
G02Y339264I-1185J923D01*
G03X399963I315J246D01*
G02X402135Y339473I1185J-923D01*
G03X402661I263J302D01*
G02Y337209I987J-1132D01*
G03X402135I-263J-302D01*
G02X399963Y337418I-987J1132D01*
G37*
G36*
G01X193564Y331470D02*
G03X193010I-277J-288D01*
G02Y333490I-973J1010D01*
G03X193564I277J288D01*
G02X195510I973J-1010D01*
G03X196064I277J288D01*
G02Y331470I973J-1010D01*
G03X195510I-277J-288D01*
G02X193564I-973J1010D01*
G37*
G36*
G01X376998Y330627D02*
G03X377585Y330641I287J279D01*
G02X379464Y328129I1200J-1061D01*
G03X379286Y327569I170J-362D01*
G02X376816Y325592I-1392J-792D01*
G03X376282Y325596I-269J-296D01*
G02X374111Y325645I-1059J1202D01*
G03X373545Y325635I-278J-288D01*
G02X371263Y325609I-1154J1111D01*
G03X370735Y325640I-282J-284D01*
G02X368626Y325759I-987J1262D01*
G03X368101Y325790I-280J-286D01*
G02X368083Y325776I-992J1257D01*
G03X368050Y325488I120J-160D01*
G02X365736Y325637I-1228J-1029D01*
G03X365796Y326156I-271J294D01*
G02X368243Y328200I1325J901D01*
G03X368768Y328169I280J286D01*
G02X370876Y328039I980J-1267D01*
G03X371404Y328008I282J284D01*
G02X373503Y327899I987J-1262D01*
G03X374069Y327909I278J288D01*
G02X374351Y328142I1155J-1110D01*
G03X374476Y328684I-217J336D01*
G02X376998Y330627I1371J828D01*
G37*
G36*
G01X434694Y323112D02*
G03X434094I-300J-265D01*
G02Y325234I-1200J1061D01*
G03X434694I300J265D01*
G02Y323112I1200J-1061D01*
G37*
G36*
G01X427494D02*
G03X426894I-300J-265D01*
G02Y325234I-1200J1061D01*
G03X427494I300J265D01*
G02Y323112I1200J-1061D01*
G37*
G36*
G01X367579Y311230D02*
G03X367069Y311072I-167J-363D01*
G02X366528Y313260I-1376J821D01*
G03X367053Y313358I208J342D01*
G02X369157Y313494I1112J-854D01*
G03X369709Y313480I283J283D01*
G02X371644Y313430I941J-1039D01*
G03X372201Y313421I283J282D01*
G02X374123I961J-1021D01*
G03X374680Y313430I274J291D01*
G02X376640Y313458I994J-989D01*
G03X377190I275J290D01*
G02Y311424I966J-1017D01*
G03X376640I-275J-290D01*
G02X374713Y311420I-966J1017D01*
G03X374156Y311411I-274J-291D01*
G02X372168I-994J989D01*
G03X371611Y311420I-283J-282D01*
G02X369658Y311451I-961J1021D01*
G03X369106Y311465I-283J-283D01*
G02X367579Y311230I-941J1039D01*
G37*
G36*
G01X193564Y298740D02*
G03X193010I-277J-288D01*
G02Y300760I-973J1010D01*
G03X193564I277J288D01*
G02X195510I973J-1010D01*
G03X196064I277J288D01*
G02Y298740I973J-1010D01*
G03X195510I-277J-288D01*
G02X193564I-973J1010D01*
G37*
G36*
G01X398694Y294843D02*
G03X398094I-300J-265D01*
G02Y296965I-1200J1061D01*
G03X398694I300J265D01*
G02Y294843I1200J-1061D01*
G37*
G36*
G01X391494D02*
G03X390894I-300J-265D01*
G02Y296965I-1200J1061D01*
G03X391494I300J265D01*
G02Y294843I1200J-1061D01*
G37*
G36*
G01X384294D02*
G03X383694I-300J-265D01*
G02Y296965I-1200J1061D01*
G03X384294I300J265D01*
G02Y294843I1200J-1061D01*
G37*
G36*
G01X377094D02*
G03X376494I-300J-265D01*
G02Y296965I-1200J1061D01*
G03X377094I300J265D01*
G02Y294843I1200J-1061D01*
G37*
G36*
G01X369894D02*
G03X369294I-300J-265D01*
G02Y296965I-1200J1061D01*
G03X369894I300J265D01*
G02Y294843I1200J-1061D01*
G37*
G36*
G01X391494Y277843D02*
G03X390894I-300J-265D01*
G02Y279965I-1200J1061D01*
G03X391494I300J265D01*
G02Y277843I1200J-1061D01*
G37*
G36*
G01X377094D02*
G03X376494I-300J-265D01*
G02Y279965I-1200J1061D01*
G03X377094I300J265D01*
G02Y277843I1200J-1061D01*
G37*
G36*
G01X369894D02*
G03X369294I-300J-265D01*
G02Y279965I-1200J1061D01*
G03X369894I300J265D01*
G02Y277843I1200J-1061D01*
G37*
G36*
G01X193564Y269740D02*
G03X193010I-277J-288D01*
G02Y271760I-973J1010D01*
G03X193564I277J288D01*
G02X195510I973J-1010D01*
G03X196064I277J288D01*
G02Y269740I973J-1010D01*
G03X195510I-277J-288D01*
G02X193564I-973J1010D01*
G37*
G36*
G01X381946Y272676D02*
G03Y272076I265J-300D01*
G02X379824I-1061J-1200D01*
G03Y272676I-265J300D01*
G02X381946I1061J1200D01*
G37*
G36*
G01X399209Y263976D02*
G03X398579I-315J-246D01*
G02Y265822I-1185J923D01*
G03X399209I315J246D01*
G02Y263976I1185J-923D01*
G37*
G36*
G01X392709D02*
G03X392079I-315J-246D01*
G02Y265822I-1185J923D01*
G03X392709I315J246D01*
G02Y263976I1185J-923D01*
G37*
G36*
G01X198627Y239616D02*
G03Y239062I288J-277D01*
G02X196607I-1010J-973D01*
G03Y239616I-288J277D01*
G02Y241562I1010J973D01*
G03Y242116I-288J277D01*
G02X198627I1010J973D01*
G03Y241562I288J-277D01*
G02Y239616I-1010J-973D01*
G37*
G36*
G01X192547Y239516D02*
G03Y238962I288J-277D01*
G02X190527I-1010J-973D01*
G03Y239516I-288J277D01*
G02Y241462I1010J973D01*
G03Y242016I-288J277D01*
G02X192547I1010J973D01*
G03Y241462I288J-277D01*
G02Y239516I-1010J-973D01*
G37*
G36*
G01X386654Y323068D02*
G02Y325278I-1160J1105D01*
G03X387234I290J275D01*
G02X389494Y325337I1160J-1105D01*
G03X390044I275J291D01*
G02X392244I1100J-1164D01*
G03X392794I275J291D01*
G02X395094Y325234I1100J-1164D01*
G03X395694I300J265D01*
G02X398094I1200J-1061D01*
G03X398694I300J265D01*
G02X401094I1200J-1061D01*
G03X401694I300J265D01*
G02X404094I1200J-1061D01*
G03X404694I300J265D01*
G02X407094I1200J-1061D01*
G03X407694I300J265D01*
G02X410094I1200J-1061D01*
G03X410694I300J265D01*
G02X413094I1200J-1061D01*
G03X413694I300J265D01*
G02X416334Y324874I1200J-1061D01*
G03X417054I360J175D01*
G02X419694Y325234I1440J-701D01*
G03X420294I300J265D01*
G02Y323112I1200J-1061D01*
G03X419694I-300J-265D01*
G02X417054Y323472I-1200J1061D01*
G03X416334I-360J-175D01*
G02X413694Y323112I-1440J701D01*
G03X413094I-300J-265D01*
G02X410694I-1200J1061D01*
G03X410094I-300J-265D01*
G02X407694I-1200J1061D01*
G03X407094I-300J-265D01*
G02X404694I-1200J1061D01*
G03X404094I-300J-265D01*
G02X401694I-1200J1061D01*
G03X401094I-300J-265D01*
G02X398694I-1200J1061D01*
G03X398094I-300J-265D01*
G02X395694I-1200J1061D01*
G03X395094I-300J-265D01*
G02X392794Y323009I-1200J1061D01*
G03X392244I-275J-291D01*
G02X390044I-1100J1164D01*
G03X389494I-275J-291D01*
G02X387234Y323068I-1100J1164D01*
G03X386654I-290J-275D01*
G37*
G36*
G01X384661Y279438D02*
G02X384467Y277861I1284J-958D01*
G03X383778Y277946I-369J-154D01*
G02X383972Y279523I-1284J958D01*
G03X384661Y279438I369J154D01*
G37*
G36*
G01X196210Y379327D02*
G03Y378773I288J-277D01*
G02X194190I-1010J-973D01*
G03Y379327I-288J277D01*
G02X196210I1010J973D01*
G37*
G36*
G01X175831Y403321D02*
G02X175784Y404774I-1222J688D01*
G03X176467Y404797I335J219D01*
G02X178913Y404794I1222J-688D01*
G03X179603Y404780I349J195D01*
G02X179575Y403364I1196J-732D01*
G03X178885Y403378I-349J-195D01*
G02X176514Y403344I-1196J731D01*
G03X175831Y403321I-335J-219D01*
G37*
G36*
G01X412516Y364647D02*
G03X412494Y364092I277J-289D01*
G02X410478Y364173I-1047J-932D01*
G03X410500Y364728I-277J289D01*
G02X410576Y366671I1047J932D01*
G03Y367249I-277J289D01*
G02X412518I971J1011D01*
G03Y366671I277J-289D01*
G02X412516Y364647I-971J-1011D01*
G37*
G36*
G01X434694Y294843D02*
G03X434094I-300J-265D01*
G02Y296965I-1200J1061D01*
G03X434694I300J265D01*
G02Y294843I1200J-1061D01*
G37*
G36*
G01X427494D02*
G03X426894I-300J-265D01*
G02Y296965I-1200J1061D01*
G03X427494I300J265D01*
G02Y294843I1200J-1061D01*
G37*
G36*
G01X420294D02*
G03X419694I-300J-265D01*
G02Y296965I-1200J1061D01*
G03X420294I300J265D01*
G02Y294843I1200J-1061D01*
G37*
G36*
G01X465497Y294379D02*
G03X465932Y293948I399J-33D01*
G02X464569Y292573I134J-1496D01*
G03X464134Y293004I-399J33D01*
G02X465497Y294379I-134J1496D01*
G37*
G36*
G01X557887Y284909D02*
G03X557651Y285415I-377J132D01*
G02X559319Y287494I494J1312D01*
G03X559927Y287420I335J218D01*
G02X560979Y284997I957J-1024D01*
G03X560608Y284565I28J-399D01*
G02X557887Y284909I-1397J-118D01*
G37*
G36*
G01X434704Y277866D02*
G03X434104Y277860I-297J-268D01*
G02X434084Y279982I-1210J1050D01*
G03X434684Y279988I297J268D01*
G02X434704Y277866I1210J-1050D01*
G37*
G36*
G01X427494Y277849D02*
G03X426894I-300J-265D01*
G02Y279971I-1200J1061D01*
G03X427494I300J265D01*
G02Y277849I1200J-1061D01*
G37*
G36*
G01X420335Y277870D02*
G03X419735Y277863I-297J-268D01*
G02X419711Y279984I-1212J1047D01*
G03X420311Y279991I297J268D01*
G02X420335Y277870I1212J-1047D01*
G37*
G36*
G01X441894Y277843D02*
G03X441294I-300J-265D01*
G02Y279965I-1200J1061D01*
G03X441894I300J265D01*
G02Y277843I1200J-1061D01*
G37*
G36*
G01X459399Y277949D02*
G03X459398Y277385I283J-283D01*
G02X457409Y277391I-997J-985D01*
G03X457410Y277955I-283J283D01*
G02X459399Y277949I997J985D01*
G37*
G36*
G01X566278Y264312D02*
G03X565739Y264144I-185J-355D01*
G02X565148Y266043I-1239J656D01*
G03X565687Y266211I185J355D01*
G02X565916Y266528I1240J-655D01*
G03Y267082I-288J277D01*
G02X565690Y267393I1011J972D01*
G03X565152Y267559I-353J-189D01*
G02X565736Y269462I-652J1241D01*
G03X566274Y269296I353J189D01*
G02X567936Y267082I652J-1241D01*
G03Y266528I288J-277D01*
G02X566278Y264312I-1010J-973D01*
G37*
G36*
G01X430961Y265722D02*
G03X431548Y265678I314J248D01*
G02X431339Y263577I1095J-1170D01*
G03X430755Y263649I-325J-233D01*
G02X430961Y265722I-974J1144D01*
G37*
G36*
G01X441151Y265147D02*
G03X440996Y264558I174J-361D01*
G02X439113Y265052I-1232J-859D01*
G03X439268Y265641I-174J361D01*
G02X441151Y265147I1232J859D01*
G37*
G36*
G01X437620Y263877D02*
G03X437658Y263359I322J-237D01*
G02X435228Y263181I-1139J-1127D01*
G03X435190Y263699I-322J237D01*
G02X437620Y263877I1139J1127D01*
G37*
G36*
G01X574890Y258091D02*
G03X574335Y257936I-203J-345D01*
G02X573810Y259809I-1235J664D01*
G03X574365Y259964I203J345D01*
G02X574590Y260273I1235J-663D01*
G03Y260827I-288J277D01*
G02X574351Y261164I1012J971D01*
G03X573818Y261341I-356J-182D01*
G02X574449Y263236I-618J1258D01*
G03X574982Y263059I356J182D01*
G02X576610Y260827I619J-1258D01*
G03Y260273I288J-277D01*
G02X574890Y258091I-1009J-973D01*
G37*
G36*
G01X510564Y259018D02*
G03X510207Y258602I43J-398D01*
G02X508544Y260025I-1500J-70D01*
G03X508901Y260441I-43J398D01*
G02X510564Y259018I1500J70D01*
G37*
G36*
G01X568789Y244539D02*
G03X569335Y244559I262J302D01*
G02X569350Y242426I1065J-1059D01*
G03X568804Y242438I-279J-286D01*
G02X566796Y242579I-936J1044D01*
G03X566187Y242582I-306J-258D01*
G02X564139Y242499I-1063J914D01*
G03X563576I-282J-285D01*
G02Y244493I-985J997D01*
G03X564139I282J285D01*
G02X566196Y244399I985J-997D01*
G03X566805Y244396I306J258D01*
G02X568789Y244539I1063J-914D01*
G37*
G36*
G01X579182Y231552D02*
G03X579740Y231317I381J124D01*
G02X579027Y229627I620J-1257D01*
G03X578469Y229862I-381J-124D01*
G02X576876Y232128I-619J1257D01*
G03X576872Y232707I-278J288D01*
G02X578512Y234955I960J1022D01*
G03X579073Y235146I194J350D01*
G02X579680Y233364I1287J-556D01*
G03X579119Y233173I-194J-350D01*
G02X578805Y232720I-1287J557D01*
G03X578809Y232141I278J-288D01*
G02X579182Y231552I-961J-1021D01*
G37*
G36*
G01X571697Y229557D02*
G03X572258Y229360I369J154D01*
G02X571637Y227588I672J-1230D01*
G03X571076Y227785I-369J-154D01*
G02X569455Y230047I-672J1230D01*
G03X569483Y230608I-270J295D01*
G02X571043Y232847I1045J935D01*
G03X571576Y233115I147J372D01*
G02X572415Y231446I1354J-365D01*
G03X571882Y231178I-147J-372D01*
G02X571477Y230511I-1354J365D01*
G03X571449Y229950I270J-295D01*
G02X571697Y229557I-1045J-934D01*
G37*
G36*
G01X580917Y218515D02*
G03X580471Y218069I-49J-397D01*
G02X579165Y219375I-1491J-185D01*
G03X579611Y219821I49J397D01*
G02X580917Y218515I1491J185D01*
G37*
G36*
G01X565401Y213453D02*
G03X565854Y213044I400J-12D01*
G02X564550Y211602I197J-1489D01*
G03X564097Y212011I-400J12D01*
G02X565401Y213453I-197J1489D01*
G37*
G36*
G01X562230Y207440D02*
G03X562676Y206994I397J-49D01*
G02X561370Y205688I185J-1491D01*
G03X560924Y206134I-397J49D01*
G02X562230Y207440I-185J1491D01*
G37*
G36*
G01X578866Y203940D02*
G03X579312Y203494I397J-49D01*
G02X578006Y202188I185J-1491D01*
G03X577560Y202634I-397J49D01*
G02X578866Y203940I-185J1491D01*
G37*
G36*
G01X688060Y199114D02*
G03X687506I-277J-288D01*
G02Y201134I-973J1010D01*
G03X688060I277J288D01*
G02X690025Y201115I973J-1010D01*
G03X690591I283J282D01*
G02Y199133I992J-991D01*
G03X690025I-283J-282D01*
G02X688060Y199114I-992J991D01*
G37*
G36*
G01Y195614D02*
G03X687506I-277J-288D01*
G02Y197634I-973J1010D01*
G03X688060I277J288D01*
G02X690025Y197615I973J-1010D01*
G03X690591I283J282D01*
G02Y195633I992J-991D01*
G03X690025I-283J-282D01*
G02X688060Y195614I-992J991D01*
G37*
G36*
G01X725999Y189785D02*
G03X726623Y189773I317J244D01*
G02X726547Y187947I1153J-963D01*
G03X725925Y187986I-327J-230D01*
G02X725999Y189785I-1037J944D01*
G37*
G36*
G01X455287Y293287D02*
G02X453794Y290967I-61J-1601D01*
G03X453085Y290978I-357J-179D01*
G02X450200Y291115I-1410J761D01*
G03X449695Y291335I-368J-156D01*
G02X447972Y291753I-547J1506D01*
G03X447385Y291754I-294J-271D01*
G02X445221Y294103I-1176J1088D01*
G03X445256Y294702I-246J315D01*
G02X445050Y294953I1129J1137D01*
G03X444392Y294966I-334J-221D01*
G02X441894Y294843I-1298J938D01*
G03X441294I-300J-265D01*
G02Y296965I-1200J1061D01*
G03X441894I300J265D01*
G02X444427Y296792I1200J-1061D01*
G03X445085Y296779I334J221D01*
G02X447371Y294580I1299J-938D01*
G03X447336Y293981I246J-315D01*
G02X447385Y293930I-1131J-1135D01*
G03X447972Y293929I294J271D01*
G02X450623Y293465I1176J-1088D01*
G03X451128Y293245I368J156D01*
G02X451534Y293335I547J-1506D01*
G03X451898Y293723I-36J398D01*
G02X451910Y293875I1502J-42D01*
G03X451574Y294320I-397J50D01*
G02X453079Y296889I242J1584D01*
G03X453700Y296877I315J246D01*
G02X455219Y294267I1222J-1036D01*
G03X454895Y293834I74J-393D01*
G02X454902Y293686I-1495J-145D01*
G03X455287Y293287I400J1D01*
G37*
G36*
G01X468864Y287326D02*
G02X468576Y285975I1049J-930D01*
G03X467887Y286111I-382J-120D01*
G02X468179Y287482I-1153J962D01*
G03X468864Y287326I385J109D01*
G37*
G36*
G01X451827Y274504D02*
G02X449761Y276685I-1027J1096D01*
G03X449561Y277367I-276J289D01*
G02X448782Y277783I287J1474D01*
G03X448214I-284J-282D01*
G02Y279899I-1066J1058D01*
G03X448782I284J282D01*
G02X450887Y277756I1066J-1058D01*
G03X451087Y277074I276J-289D01*
G02X451827Y276696I-287J-1474D01*
G03X452373I273J292D01*
G02Y274504I1027J-1096D01*
G03X451827I-273J-292D01*
G37*
G36*
G01X449580Y264344D02*
G02X448046Y264728I-1077J-1047D01*
G03X448211Y265388I-121J381D01*
G02X448391Y267640I1077J1047D01*
G03X448318Y268324I-239J320D01*
G02X449773Y268503I582J1276D01*
G03X449867Y267821I249J-313D01*
G02X450726Y266868I-579J-1386D01*
G03X451272Y266618I383J115D01*
G02X450445Y264813I611J-1372D01*
G03X449899Y265063I-383J-115D01*
G02X449745Y265004I-614J1371D01*
G03X449580Y264344I121J-381D01*
G37*
G36*
G01X445956Y262596D02*
G02X443997Y262340I-833J-1250D01*
G03X443919Y262938I-300J265D01*
G02X443771Y265325I833J1250D01*
G03X443699Y265981I-261J303D01*
G02X445389Y266168I709J1324D01*
G03X445461Y265512I261J-303D01*
G02X445878Y263194I-709J-1324D01*
G03X445956Y262596I300J-265D01*
G37*
G36*
G01X463914Y314235D02*
G03X463891Y313677I275J-291D01*
G02X461882Y313757I-1043J-936D01*
G03X461905Y314315I-275J291D01*
G02X463914Y314235I1043J936D01*
G37*
G36*
G01X637881Y287185D02*
G03X637839Y286610I255J-308D01*
G02X636064Y286864I-1040J-940D01*
G03X636087Y287187I-105J170D01*
G02X635967Y287300I900J1076D01*
G03X635645Y287257I-146J-137D01*
G02X635280Y289012I-1238J658D01*
G03X635852Y289090I249J313D01*
G02X637881Y287185I1133J-827D01*
G37*
G36*
G01X621974Y254930D02*
G03X621904Y254340I231J-327D01*
G02X620041Y254561I-1054J-924D01*
G03X620111Y255151I-231J327D01*
G02X621974Y254930I1054J924D01*
G37*
G36*
G01X631752Y247132D02*
G03X631199Y247116I-268J-297D01*
G02X631140Y249140I-999J984D01*
G03X631693Y249156I268J297D01*
G02X631752Y247132I999J-984D01*
G37*
G36*
G01X629922Y287956D02*
G02X629175Y289074I-1397J-125D01*
G03X629758Y289475I186J354D01*
G02X630516Y288340I1492J176D01*
G03X629922Y287956I-196J-349D01*
G37*
G36*
G01X643772Y262245D02*
G02X641828I-972J-1145D01*
G03Y262855I-259J305D01*
G02X642264Y265403I972J1145D01*
G03X642430Y266030I-143J373D01*
G02X642310Y267768I1161J953D01*
G03X642156Y268331I-341J209D01*
G02X642144Y270983I699J1329D01*
G03X642298Y271541I-189J352D01*
G02X642477Y273220I1202J721D01*
G03X642461Y273783I-292J273D01*
G02X644539I1039J1085D01*
G03X644523Y273220I276J-290D01*
G02X644226Y271063I-1023J-958D01*
G03X644102Y270498I208J-342D01*
G02X644136Y268875I-1247J-838D01*
G03X644290Y268312I341J-209D01*
G02X644127Y265580I-699J-1329D01*
G03X643961Y264953I143J-373D01*
G02X643772Y262855I-1161J-953D01*
G03Y262245I259J-305D01*
G37*
G36*
G01X700168Y337953D02*
G03X699613Y337931I-266J-299D01*
G02X699532Y339947I-1013J969D01*
G03X700087Y339969I266J299D01*
G02X700168Y337953I1013J-969D01*
G37*
G36*
G01X645706Y326977D02*
G03X645589Y327576I-312J250D01*
G02X647366Y327923I683J1224D01*
G03X647483Y327324I312J-250D01*
G02X645706Y326977I-683J-1224D01*
G37*
G36*
G01X688320Y318775D02*
G03X688262Y318235I263J-301D01*
G02X686218Y318455I-1124J-838D01*
G03X686276Y318995I-263J301D01*
G02X688320Y318775I1124J838D01*
G37*
G36*
G01X647783Y319011D02*
G03Y318389I252J-311D01*
G02X646017I-883J-1089D01*
G03Y319011I-252J311D01*
G02X647783I883J1089D01*
G37*
G36*
G01X714980Y309887D02*
G03Y309333I288J-277D01*
G02X712960I-1010J-973D01*
G03Y309887I-288J277D01*
G02X714980I1010J973D01*
G37*
G36*
G01X657627Y294985D02*
G03X657426Y295549I-350J193D01*
G02X659176Y296170I524J1301D01*
G03X659377Y295606I350J-193D01*
G02X657627Y294985I-524J-1301D01*
G37*
G36*
G01X663911Y283917D02*
G03X663289I-311J-252D01*
G02X660957Y285448I-1089J883D01*
G03X660742Y286007I-355J184D01*
G02X662475Y286673I490J1314D01*
G03X662690Y286114I355J-184D01*
G02X663289Y285683I-491J-1314D01*
G03X663911I311J252D01*
G02Y283917I1089J-883D01*
G37*
G36*
G01X662303Y279878D02*
G03X662721Y279485I400J6D01*
G02X661384Y278062I65J-1401D01*
G03X660966Y278455I-400J-6D01*
G02X662303Y279878I-65J1401D01*
G37*
G36*
G01X679038Y364209D02*
G02X677514Y363539I-308J-1368D01*
G03X677255Y364128I-347J199D01*
G02X678779Y364798I308J1368D01*
G03X679038Y364209I347J-199D01*
G37*
G36*
G01X696449Y352760D02*
G02X695006Y352697I-659J-1460D01*
G03X694996Y353401I-195J349D01*
G02X694719Y355697I648J1243D01*
G03X694731Y356287I-264J300D01*
G02X696625Y356247I969J1013D01*
G03X696613Y355657I264J-300D01*
G02X696398Y353462I-969J-1013D01*
G03X696449Y352760I215J-337D01*
G37*
G36*
G01X637524Y328453D02*
G02X635905Y327850I-381J-1453D01*
G03X635691Y328459I-330J226D01*
G02X636069Y331202I409J1341D01*
G03X636420Y331777I-8J400D01*
G02X637712Y330988I1261J613D01*
G03X637361Y330413I8J-400D01*
G02X637286Y329053I-1261J-613D01*
G03X637524Y328453I339J-213D01*
G37*
G36*
G01X688114Y326341D02*
G02X686563Y326393I-815J-1141D01*
G03X686586Y327059I-210J341D01*
G02X688137Y327007I815J1141D01*
G03X688114Y326341I210J-341D01*
G37*
G36*
G01X672778Y298889D02*
G02X672637Y297518I1144J-810D01*
G03X671944Y297589I-367J-160D01*
G02X669711Y297517I-1144J811D01*
G03X669089I-311J-252D01*
G02Y299283I-1089J883D01*
G03X669711I311J252D01*
G02X672085Y298960I1089J-883D01*
G03X672778Y298889I367J160D01*
G37*
G36*
G01X656121Y285442D02*
G02X654689Y285967I-1121J-842D01*
G03X654921Y286597I-88J390D01*
G02X656353Y286072I1121J842D01*
G03X656121Y285442I88J-390D01*
G37*
G36*
G01X684678Y281366D02*
G02X684620Y282940I-1188J744D01*
G03X685282Y282964I323J236D01*
G02X685340Y281390I1188J-744D01*
G03X684678Y281366I-323J-236D01*
G37*
G36*
G01X690825Y282220D02*
G02X689271I-777J-1167D01*
G03Y282886I-222J333D01*
G02X690825I777J1167D01*
G03Y282220I222J-333D01*
G37*
G36*
G01X710700Y273831D02*
G02X709004Y273683I-751J-1184D01*
G03X708949Y274316I-269J295D01*
G02X708692Y276474I751J1184D01*
G03X708670Y277051I-288J278D01*
G02X708511Y277217I930J1049D01*
G03X707889I-311J-252D01*
G02Y278983I-1089J883D01*
G03X708511I311J252D01*
G02X710608Y277126I1090J-882D01*
G03X710630Y276549I288J-278D01*
G02X710645Y274464I-930J-1049D01*
G03X710700Y273831I269J-295D01*
G37*
G36*
G01X718606Y249173D02*
G02X718591Y250691I-1186J747D01*
G03X719264Y250697I335J219D01*
G02X721584Y250774I1186J-747D01*
G03X722239Y250786I323J236D01*
G02X724545Y250809I1161J-786D01*
G03X725195Y250805I326J231D01*
G02X725183Y249170I1133J-826D01*
G03X724533Y249174I-326J-231D01*
G02X722266Y249176I-1133J826D01*
G03X721611Y249164I-323J-236D01*
G02X719279Y249179I-1161J786D01*
G03X718606Y249173I-335J-219D01*
G37*
G36*
G01X1755384Y34253D02*
G02X1756601Y35735I1511J-1D01*
G03X1756873Y36321I-78J392D01*
G02X1756865Y36336I1233J667D01*
G03X1756299Y36484I-352J-190D01*
G02X1754912Y36269I-899J1216D01*
G01X1754909Y36259D01*
X1754718Y36324D01*
X1754704Y36283D01*
G03X1754385Y35757I59J-396D01*
G02X1751822Y34641I-1325J-457D01*
G03X1751214Y34761I-353J-188D01*
G02X1750251Y34414I-964J1164D01*
G01X1746550D01*
G02X1745673Y37156I0J1511D01*
G03X1745687Y37796I-233J325D01*
G02X1745270Y38333I866J1103D01*
G03X1744593Y38421I-365J-162D01*
G02X1742368Y38473I-1093J879D01*
G03X1741742Y38498I-323J-236D01*
G02X1740556Y37975I-1144J988D01*
G01Y37965D01*
X1736654Y38080D01*
X1736483Y38104D01*
G02X1735904Y38315I217J1496D01*
G03X1735298Y38033I-210J-340D01*
G02X1732545Y37911I-1388J199D01*
G03X1731952Y38164I-389J-91D01*
G02X1731184Y37954I-769J1301D01*
G01X1727382D01*
G02X1726597Y38174I0J1511D01*
G03X1726027Y38003I-208J-341D01*
G02X1723365Y38444I-1269J597D01*
G03X1722714Y38709I-398J-44D01*
G02X1721758Y38368I-956J1171D01*
G01X1717958D01*
G02Y41392I0J1512D01*
G01X1721759D01*
G02X1723270Y39890I-1J-1512D01*
G01Y39795D01*
X1723260Y39711D01*
G02X1723229Y39532I-1502J168D01*
G03X1723590Y39376I195J-45D01*
G02X1725423Y39834I1168J-776D01*
G03X1725984Y40035I190J352D01*
G02X1727383Y40976I1400J-570D01*
G01X1731183D01*
G02X1732694Y39475I0J-1511D01*
G01Y39272D01*
X1732966D01*
X1733021Y39317D01*
G02X1734602Y39452I889J-1084D01*
G03X1735197Y39758I197J348D01*
G02X1736742Y41111I1503J-158D01*
G01Y41121D01*
X1740642Y41006D01*
X1740650Y40998D01*
X1740723Y40992D01*
G02X1741859Y40319I-125J-1506D01*
G03X1742483Y40265I333J221D01*
G02X1744782Y39867I1017J-965D01*
G03X1745459Y39779I365J162D01*
G02X1747624Y39804I1093J-879D01*
G03X1748248Y39820I306J258D01*
G02X1750371Y39947I1116J-849D01*
G03X1750917Y39920I287J278D01*
G02X1752488Y40296I1083J-1056D01*
G01X1752491Y40306D01*
X1755896Y39140D01*
Y39138D01*
X1756013Y39082D01*
G02X1756350Y38877I-611J-1383D01*
G01Y38875D01*
X1756360Y38868D01*
X1756362D01*
G02X1756780Y38318I-963J-1166D01*
G03X1757344Y38181I347J199D01*
G02X1758431Y35638I756J-1181D01*
G03X1758185Y35040I95J-389D01*
G02X1758406Y34262I-1290J-787D01*
G01Y30367D01*
X1758397Y30283D01*
G02X1755384Y30452I-1502J169D01*
G01Y34253D01*
G37*
G36*
G01X1833443Y127860D02*
X1839943D01*
G02Y112456I0J-7702D01*
G01X1833443D01*
G02Y127860I0J7702D01*
G37*
G36*
G01X1970288Y483021D02*
G03X1970070Y482434I125J-380D01*
G02X1967831Y482651I-1200J-724D01*
G03X1967729Y483269I-297J268D01*
G02X1970288Y483021I1562J2795D01*
G37*
G36*
G01X1939943Y478362D02*
G03X1939957Y477758I269J-296D01*
G02X1938043I-957J-1158D01*
G03X1938057Y478362I-255J308D01*
G02X1939943I943J1038D01*
G37*
G36*
G01X1685535Y458399D02*
G03Y457854I293J-272D01*
G02X1683335I-1100J-1022D01*
G03Y458399I-293J272D01*
G02X1685535I1100J1022D01*
G37*
G36*
G01X1676975Y457708D02*
G03X1676913Y457143I249J-313D01*
G02X1674810Y457376I-1169J-943D01*
G03X1674872Y457941I-249J313D01*
G02X1676975Y457708I1169J943D01*
G37*
G36*
G01X1840514Y453316D02*
G03X1839895Y453286I-297J-268D01*
G02X1839767Y455103I-1127J834D01*
G03X1840384Y455160I285J281D01*
G02X1842815Y455244I1246J-839D01*
G03X1843445I315J246D01*
G02X1845677Y455398I1185J-923D01*
G03X1846228Y455393I278J287D01*
G02X1846267Y453309I957J-1024D01*
G03X1845716Y453283I-262J-302D01*
G02X1843445Y453398I-1086J1038D01*
G03X1842815I-315J-246D01*
G02X1840514Y453316I-1185J923D01*
G37*
G36*
G01X1682201Y450789D02*
G03X1682187Y450234I281J-285D01*
G02X1680168Y450283I-1033J-948D01*
G03X1680182Y450838I-281J285D01*
G02X1680196Y452749I1033J948D01*
G03X1680191Y453304I-290J275D01*
G02X1682211Y453323I1001J982D01*
G03X1682216Y452768I290J-275D01*
G02X1682201Y450789I-1001J-982D01*
G37*
G36*
G01X1934174Y449606D02*
G03X1933519Y449525I-300J-265D01*
G02X1933813Y452055I-3200J1654D01*
G03X1934432Y451826I388J97D01*
G02X1934174Y449606I868J-1226D01*
G37*
G36*
G01X1677412Y448780D02*
G03X1677408Y448243I295J-271D01*
G02X1675179Y448258I-1121J-999D01*
G03X1675183Y448795I-295J271D01*
G02X1677412Y448780I1121J999D01*
G37*
G36*
G01X1719804Y443854D02*
G03X1719976Y443297I348J-198D01*
G02X1718052Y442757I-659J-1350D01*
G03X1717909Y443323I-337J216D01*
G02X1717595Y443559I677J1228D01*
G03X1717029I-283J-282D01*
G02Y445541I-992J991D01*
G03X1717595I283J282D01*
G02X1719804Y443854I992J-991D01*
G37*
G36*
G01X1662244Y389244D02*
G03X1662179Y388723I267J-298D01*
G02X1659933Y389003I-1245J-840D01*
G03X1659998Y389524I-267J298D01*
G02X1660139Y391382I1245J840D01*
G03Y391925I-294J271D01*
G02X1662347I1104J1018D01*
G03Y391382I294J-271D01*
G02X1662244Y389244I-1104J-1018D01*
G37*
G36*
G01X1665990Y378242D02*
G03X1666006Y377716I310J-254D01*
G02X1663744Y377647I-1101J-1021D01*
G03X1663728Y378173I-310J254D01*
G02X1665990Y378242I1101J1021D01*
G37*
G36*
G01X1669624Y255597D02*
G03X1669481Y256198I-319J242D01*
G02X1668945Y256637I658J1350D01*
G03X1668414Y256733I-318J-242D01*
G02X1666532Y258743I-747J1187D01*
G03X1666377Y259340I-324J234D01*
G02X1668103Y259788I591J1271D01*
G03X1668258Y259191I324J-234D01*
G02X1668730Y258834I-591J-1271D01*
G03X1669266Y258769I304J260D01*
G02X1671338Y256641I874J-1222D01*
G03X1671481Y256040I319J-242D01*
G02X1669624Y255597I-659J-1349D01*
G37*
G36*
G01X1845386Y252511D02*
G03X1844778Y252504I-301J-263D01*
G02X1844712Y254371I-1078J897D01*
G03X1845319Y254406I289J277D01*
G02X1845386Y252511I1198J-906D01*
G37*
G36*
G01X1726471Y249314D02*
G03X1725917I-277J-288D01*
G02X1723874Y249418I-973J1010D01*
G03X1723291Y249449I-306J-258D01*
G02X1723445Y251443I-1040J1083D01*
G03X1724025Y251383I318J242D01*
G02X1725917Y251334I919J-1059D01*
G03X1726471I277J288D01*
G02X1728417I973J-1010D01*
G03X1728971I277J288D01*
G02Y249314I973J-1010D01*
G03X1728417I-277J-288D01*
G02X1726471I-973J1010D01*
G37*
G36*
G01X1818590Y249557D02*
G02X1817282Y248886I-1309J941D01*
G01X1812281D01*
G02X1810973Y249558I1J1612D01*
G03X1810345Y249585I-325J-234D01*
G02Y251411I-1064J913D01*
G03X1810973Y251438I303J261D01*
G02X1812282Y252110I1309J-939D01*
G01X1817282D01*
G02X1818590Y251439I-1J-1612D01*
G03X1819218Y251412I325J234D01*
G02Y249584I1063J-914D01*
G03X1818590Y249557I-303J-261D01*
G37*
G36*
G01X1770221Y249140D02*
G03X1769616Y249114I-291J-274D01*
G02X1769538Y250943I-1100J869D01*
G03X1770143Y250969I291J274D01*
G02X1770221Y249140I1100J-869D01*
G37*
G36*
G01X1827922Y248932D02*
G03X1827350Y248938I-289J-276D01*
G02X1824787Y249921I-1063J1062D01*
G03X1824369Y250300I-400J-21D01*
G02X1825800Y251879I-69J1500D01*
G03X1826218Y251500I400J21D01*
G02X1827427Y250978I69J-1500D01*
G03X1827998Y250942I303J261D01*
G02X1827922Y248932I938J-1042D01*
G37*
G36*
G01X1736800Y248939D02*
G03X1736200I-300J-265D01*
G02Y251061I-1200J1061D01*
G03X1736800I300J265D01*
G02X1739200I1200J-1061D01*
G03X1739800I300J265D01*
G02Y248939I1200J-1061D01*
G03X1739200I-300J-265D01*
G02X1736800I-1200J1061D01*
G37*
G36*
G01X1690282Y249679D02*
G03X1689813Y249382I-80J-392D01*
G02X1687218Y249048I-1362J334D01*
G03X1686708Y249225I-352J-190D01*
G02X1685177Y249429I-595J1379D01*
G03X1684652Y249406I-249J-313D01*
G02X1684551Y251668I-1037J1087D01*
G03X1685076Y251691I249J313D01*
G02X1687474Y251240I1037J-1087D01*
G03X1687972Y251034I362J170D01*
G02X1688734Y251089I478J-1318D01*
G03X1689203Y251386I80J392D01*
G02X1690282Y249679I1362J-334D01*
G37*
G36*
G01X1662685Y245453D02*
G03X1663057Y245081I399J27D01*
G02X1661457Y243481I-101J-1499D01*
G03X1661085Y243853I-399J-27D01*
G02X1662685Y245453I101J1499D01*
G37*
G36*
G01X1780760Y236772D02*
G02X1779451Y236100I-1309J939D01*
G01X1774450D01*
G02X1773143Y236771I2J1612D01*
G03X1772514Y236798I-325J-233D01*
G02Y238626I-1063J914D01*
G03X1773143Y238653I304J260D01*
G02X1774451Y239324I1309J-941D01*
G01X1779451D01*
G02X1780760Y238652I0J-1611D01*
G03X1781388Y238625I325J234D01*
G02Y236799I1064J-913D01*
G03X1780760Y236772I-303J-261D01*
G37*
G36*
G01X1844351Y237699D02*
G03X1844229Y237117I201J-346D01*
G02X1839789Y237315I-2300J-1687D01*
G03X1839659Y237941I-300J264D01*
G02X1841670Y239916I641J1359D01*
G03X1842364Y239853I365J164D01*
G02X1844351Y237699I1236J-853D01*
G37*
G36*
G01X1682720Y234701D02*
G03X1683281Y234682I290J275D01*
G02X1683212Y232543I1019J-1103D01*
G03X1682651Y232562I-290J-275D01*
G02X1682720Y234701I-1019J1103D01*
G37*
G36*
G01X1768016Y232307D02*
G03X1767464Y232105I-183J-356D01*
G02X1766761Y234018I-1387J576D01*
G03X1767313Y234220I183J356D01*
G02X1768016Y232307I1387J-576D01*
G37*
G36*
G01X1802348Y231433D02*
G03X1801764Y231339I-249J-313D01*
G02X1801406Y233247I-1173J767D01*
G03X1801984Y233370I233J325D01*
G02X1804397Y233616I1296J-759D01*
G03X1804986Y233610I297J267D01*
G02X1804966Y231579I1097J-1026D01*
G03X1804377Y231585I-297J-267D01*
G02X1802348Y231433I-1097J1026D01*
G37*
G36*
G01X1792793Y231303D02*
G03X1792238Y231233I-242J-319D01*
G02X1791925Y233268I-1097J873D01*
G03X1792475Y233369I223J332D01*
G02X1792566Y233485I1226J-868D01*
G03X1792545Y234031I-302J262D01*
G02X1794734Y234115I1055J1069D01*
G03X1794755Y233569I302J-262D01*
G02X1792793Y231303I-1055J-1069D01*
G37*
G36*
G01X1783574Y231711D02*
G03X1782977Y231544I-230J-327D01*
G02X1782450Y233286I-1284J562D01*
G03X1783039Y233479I216J337D01*
G02X1783574Y231711I1401J-541D01*
G37*
G36*
G01X1883413Y222968D02*
G03X1882887I-263J-302D01*
G02Y225232I-987J1132D01*
G03X1883413I263J302D01*
G02Y222968I987J-1132D01*
G37*
G36*
G01X1898546Y215524D02*
G03Y214978I292J-273D01*
G02X1896354I-1096J-1027D01*
G03Y215524I-292J273D01*
G02X1898546I1096J1027D01*
G37*
G36*
G01X1873391Y212681D02*
G03X1872830Y212602I-241J-319D01*
G02X1872553Y214561I-1122J840D01*
G03X1873114Y214640I241J319D01*
G02X1873391Y212681I1122J-840D01*
G37*
G36*
G01X1927510Y211417D02*
G03X1926977Y211395I-254J-309D01*
G02X1926890Y213483I-977J1005D01*
G03X1927423Y213505I254J309D01*
G02X1927510Y211417I977J-1005D01*
G37*
G36*
G01X1863324Y210751D02*
G03X1862750Y210652I-240J-319D01*
G02X1860002Y211341I-1253J829D01*
G03X1859604Y211704I-398J-37D01*
G01X1859602D01*
G02X1861099Y213346I2J1502D01*
G03X1861497Y212983I398J37D01*
G01X1861499D01*
G02X1862462Y212632I-2J-1502D01*
G03X1863041Y212701I257J306D01*
G02X1863324Y210751I1129J-832D01*
G37*
G36*
G01X1826685Y210650D02*
X1822024D01*
G03X1821652Y210102I0J-400D01*
G02X1820044Y210954I-1303J-516D01*
G03X1820318Y211516I-87J390D01*
G02X1821685Y213672I1367J645D01*
G01X1826686D01*
G02X1828196Y212171I-1J-1511D01*
G01Y212076D01*
X1828187Y211992D01*
G02X1826685Y210650I-1502J169D01*
G37*
G36*
G01X1856810Y207408D02*
G03X1857399Y207388I304J260D01*
G02X1857330Y205357I1071J-1053D01*
G03X1856741Y205377I-304J-260D01*
G02X1856810Y207408I-1071J1053D01*
G37*
G36*
G01X1910152Y203101D02*
G03X1910048Y202502I204J-344D01*
G02X1908253Y202815I-1081J-893D01*
G03X1908357Y203414I-204J344D01*
G02X1910152Y203101I1081J893D01*
G37*
G36*
G01X1884398Y201334D02*
G03X1884420Y201029I140J-143D01*
G02X1882372Y200759I-881J-1216D01*
G03X1882333Y201305I-310J252D01*
G02X1884518Y203354I1016J1106D01*
G03X1885095Y203307I311J252D01*
G02X1884810Y201403I998J-1123D01*
G03X1884488Y201429I-170J-104D01*
G02X1884398Y201334I-1135J985D01*
G37*
G36*
G01X1835113Y178705D02*
G03X1834511Y178660I-281J-284D01*
G02X1834375Y180495I-1123J839D01*
G03X1834977Y180540I281J284D01*
G02X1835113Y178705I1123J-839D01*
G37*
G36*
G01X1884594Y177825D02*
G03X1884609Y177477I106J-170D01*
G02X1882939Y177266I-679J-1340D01*
G03X1882912Y177889I-264J301D01*
G02X1884992Y180014I888J1211D01*
G03X1885538Y179930I317J244D01*
G02X1885208Y177786I862J-1230D01*
G03X1884662Y177870I-317J-244D01*
G02X1884594Y177825I-863J1230D01*
G37*
G36*
G01X1856413Y174768D02*
G03X1855887I-263J-302D01*
G02Y177032I-987J1132D01*
G03X1856413I263J302D01*
G02Y174768I987J-1132D01*
G37*
G36*
G01X1876568Y175809D02*
G03X1876939Y175417I400J7D01*
G02X1875330Y173892I-107J-1498D01*
G03X1874959Y174284I-400J-7D01*
G02X1876568Y175809I107J1498D01*
G37*
G36*
G01X1794374Y171029D02*
G03X1793797Y171007I-278J-288D01*
G02X1793722Y172945I-1049J930D01*
G03X1794299Y172967I278J288D01*
G02X1796321Y173047I1049J-930D01*
G03X1796875I277J288D01*
G02Y171027I973J-1010D01*
G03X1796321I-277J-288D01*
G02X1794374Y171029I-972J1010D01*
G37*
G36*
G01X1887496Y171573D02*
G03Y171027I292J-273D01*
G02X1885304I-1096J-1027D01*
G03Y171573I-292J273D01*
G02X1887496I1096J1027D01*
G37*
G36*
G01X1794264Y164466D02*
G03X1794277Y163886I282J-284D01*
G02X1792209Y163839I-1009J-1112D01*
G03X1792196Y164419I-282J284D01*
G02X1794264Y164466I1009J1112D01*
G37*
G36*
G01X1840979Y158342D02*
G03X1840978Y157802I295J-271D01*
G02X1838855Y157744I-1037J-944D01*
G03X1838824Y158283I-310J253D01*
G02X1840979Y158342I1049J1075D01*
G37*
G36*
G01X1870051Y154828D02*
G03X1870597Y154777I300J264D01*
G02X1870340Y152665I924J-1184D01*
G03X1869798Y152747I-315J-247D01*
G02X1870051Y154828I-798J1153D01*
G37*
G36*
G01X1887324Y152830D02*
G03X1887272Y152305I273J-292D01*
G02X1885025Y152529I-1222J-874D01*
G03X1885077Y153054I-273J292D01*
G02X1885165Y154913I1222J874D01*
G03X1885102Y155496I-302J262D01*
G02X1887134Y155715I898J1204D01*
G03X1887197Y155132I302J-262D01*
G02X1887324Y152830I-898J-1204D01*
G37*
G36*
G01X1873380Y146296D02*
G03X1873409Y145732I297J-267D01*
G02X1871484Y145809I-1009J-1113D01*
G03Y146126I-122J159D01*
G02X1871370Y146223I850J1115D01*
G03X1871048Y146158I-138J-144D01*
G02X1870598Y147929I-1380J592D01*
G03X1871178Y148020I248J314D01*
G02X1873380Y146296I1163J-783D01*
G37*
G36*
G01X1833115Y144479D02*
G03X1832599Y144204I-130J-379D01*
G02X1831633Y146013I-1451J388D01*
G03X1832149Y146288I130J379D01*
G02X1833115Y144479I1451J-388D01*
G37*
G36*
G01X1801318Y144713D02*
G03X1801922Y144715I301J264D01*
G02X1801883Y142797I1136J-982D01*
G03X1801280Y142823I-313J-249D01*
G02X1801318Y144713I-1016J966D01*
G37*
G36*
G01X1910547Y143703D02*
G03X1911150Y143631I332J223D01*
G02X1911010Y141718I950J-1031D01*
G03X1910403Y141736I-311J-251D01*
G02X1910547Y143703I-1187J1076D01*
G37*
G36*
G01X1849616Y143180D02*
G03X1849627Y142581I270J-295D01*
G02X1847506Y142540I-1037J-1221D01*
G03X1847495Y143139I-270J295D01*
G02X1849616Y143180I1037J1221D01*
G37*
G36*
G01X1905267Y141604D02*
G03X1905220Y141049I263J-302D01*
G02X1903106Y141112I-1084J-889D01*
G03X1903093Y141669I-293J272D01*
G02X1905267Y141604I1122J1143D01*
G37*
G36*
G01X1856050Y137539D02*
G03X1855450I-300J-265D01*
G02Y139661I-1200J1061D01*
G03X1856050I300J265D01*
G02Y137539I1200J-1061D01*
G37*
G36*
G01X1879910Y138935D02*
G03X1879937Y138396I308J-255D01*
G02X1877819Y138229I-987J-996D01*
G03X1877761Y138765I-323J236D01*
G02X1879910Y138935I992J1128D01*
G37*
G36*
G01X1846794Y136207D02*
G03X1847347Y136050I352J189D01*
G02X1846775Y134043I753J-1300D01*
G03X1846222Y134200I-352J-189D01*
G02X1846794Y136207I-753J1300D01*
G37*
G36*
G01X1817468Y132215D02*
G03X1816929Y132199I-261J-303D01*
G02Y134355I-1046J1078D01*
G03X1817468Y134339I278J287D01*
G02Y132215I915J-1062D01*
G37*
G36*
G01X1861933Y132617D02*
G03X1861943Y131996I257J-306D01*
G02X1860051Y131967I-928J-1181D01*
G03X1860041Y132588I-257J306D01*
G02X1859873Y134796I928J1181D01*
G03Y135342I-292J273D01*
G02X1862065I1096J1027D01*
G03Y134796I292J-273D01*
G02X1861933Y132617I-1096J-1027D01*
G37*
G36*
G01X1248363Y123745D02*
G03X1248983Y123780I296J270D01*
G02X1249046Y121939I1217J-880D01*
G03X1248425Y121931I-307J-256D01*
G02X1248363Y123745I-1099J870D01*
G37*
G36*
G01X1287039Y117747D02*
G03Y117117I246J-315D01*
G02X1285193I-923J-1185D01*
G03Y117747I-246J315D01*
G02X1287039I923J1185D01*
G37*
G36*
G01X1278135Y116500D02*
G03X1278122Y115901I259J-305D01*
G02X1276186Y115992I-1022J-1101D01*
G03X1276228Y116589I-244J317D01*
G02X1278135Y116500I1001J981D01*
G37*
G36*
G01X1303600Y113273D02*
G03Y112727I292J-273D01*
G02X1301408I-1096J-1027D01*
G03Y113273I-292J273D01*
G02X1301439Y115359I1096J1027D01*
G03Y115641I-142J141D01*
G02X1301450Y117770I1065J1059D01*
G03X1301452Y118052I-141J142D01*
G02X1303580Y118032I1074J1050D01*
G03X1303578Y117750I141J-142D01*
G02X1303569Y115641I-1074J-1050D01*
G03Y115359I142J-141D01*
G02X1303600Y113273I-1065J-1059D01*
G37*
G36*
G01X951622Y111340D02*
G03X951635Y110779I291J-274D01*
G02X949553Y110787I-1045J-1079D01*
G03X949571Y111348I-276J290D01*
G02X951622Y111340I1029J952D01*
G37*
G36*
G01X1209253Y109017D02*
G03X1209267Y108434I281J-285D01*
G02X1207267I-1000J-1120D01*
G03X1207281Y109017I-267J298D01*
G02X1209253I986J997D01*
G37*
G36*
G01X1202560D02*
G03X1202574Y108434I281J-285D01*
G02X1200574I-1000J-1120D01*
G03X1200588Y109017I-267J298D01*
G02X1202560I986J997D01*
G37*
G36*
G01X1178842Y108978D02*
G03X1178869Y108417I298J-267D01*
G02X1176788Y108377I-1020J-1103D01*
G03X1176792Y108938I-283J283D01*
G02X1178842Y108978I1006J976D01*
G37*
G36*
G01X924511Y108948D02*
G03X924538Y108387I298J-267D01*
G02X922457Y108347I-1020J-1103D01*
G03X922461Y108908I-283J283D01*
G02X924511Y108948I1006J976D01*
G37*
G36*
G01X918111Y108987D02*
G03X918125Y108404I281J-285D01*
G02X916125I-1000J-1120D01*
G03X916139Y108987I-267J298D01*
G02X918111I986J997D01*
G37*
G36*
G01X911418D02*
G03X911432Y108404I281J-285D01*
G02X909432I-1000J-1120D01*
G03X909446Y108987I-267J298D01*
G02X911418I986J997D01*
G37*
G36*
G01X887700Y108948D02*
G03X887727Y108387I298J-267D01*
G02X885646Y108347I-1020J-1103D01*
G03X885650Y108908I-283J283D01*
G02X887700Y108948I1006J976D01*
G37*
G36*
G01X1185167Y108608D02*
G03X1185183Y108047I293J-272D01*
G02X1183101I-1041J-1083D01*
G03X1183117Y108608I-277J289D01*
G02X1185167I1025J956D01*
G37*
G36*
G01X1171746D02*
G03X1171762Y108047I293J-272D01*
G02X1169680I-1041J-1083D01*
G03X1169696Y108608I-277J289D01*
G02X1171746I1025J956D01*
G37*
G36*
G01X1165453D02*
G03X1165469Y108047I293J-272D01*
G02X1163387I-1041J-1083D01*
G03X1163403Y108608I-277J289D01*
G02X1165453I1025J956D01*
G37*
G36*
G01X1148356D02*
G03X1148372Y108047I293J-272D01*
G02X1146290I-1041J-1083D01*
G03X1146306Y108608I-277J289D01*
G02X1148356I1025J956D01*
G37*
G36*
G01X1142063D02*
G03X1142079Y108047I293J-272D01*
G02X1139997I-1041J-1083D01*
G03X1140013Y108608I-277J289D01*
G02X1142063I1025J956D01*
G37*
G36*
G01X930836Y108578D02*
G03X930852Y108017I293J-272D01*
G02X928770I-1041J-1083D01*
G03X928786Y108578I-277J289D01*
G02X930836I1025J956D01*
G37*
G36*
G01X894025D02*
G03X894041Y108017I293J-272D01*
G02X891959I-1041J-1083D01*
G03X891975Y108578I-277J289D01*
G02X894025I1025J956D01*
G37*
G36*
G01X1853259Y106796D02*
G03X1852843Y106388I-16J-399D01*
G02X1851479Y107854I-1502J-30D01*
G03X1851916Y108240I37J398D01*
G02X1853259Y106796I1401J-43D01*
G37*
G36*
G01X1189030Y106782D02*
G03X1189014Y106221I277J-289D01*
G02X1186964I-1025J-956D01*
G03X1186948Y106782I-293J272D01*
G02X1186901Y108900I1041J1083D01*
G03X1186895Y109457I-290J275D01*
G02X1186922Y111597I1068J1057D01*
G03X1186938Y112158I-277J289D01*
G02X1188988I1025J956D01*
G03X1189004Y111597I293J-272D01*
G02X1189051Y109479I-1041J-1083D01*
G03X1189057Y108922I290J-275D01*
G02X1189030Y106782I-1068J-1057D01*
G37*
G36*
G01X1152219D02*
G03X1152203Y106221I277J-289D01*
G02X1150153I-1025J-956D01*
G03X1150137Y106782I-293J272D01*
G02X1150090Y108900I1041J1083D01*
G03X1150084Y109457I-290J275D01*
G02X1150111Y111597I1068J1057D01*
G03X1150127Y112158I-277J289D01*
G02X1152177I1025J956D01*
G03X1152193Y111597I293J-272D01*
G02X1152240Y109479I-1041J-1083D01*
G03X1152246Y108922I290J-275D01*
G02X1152219Y106782I-1068J-1057D01*
G37*
G36*
G01X934699D02*
G03X934683Y106221I277J-289D01*
G02X932633I-1025J-956D01*
G03X932617Y106782I-293J272D01*
G02X932570Y108900I1041J1083D01*
G03X932564Y109457I-290J275D01*
G02X932591Y111597I1068J1057D01*
G03X932607Y112158I-277J289D01*
G02X934657I1025J956D01*
G03X934673Y111597I293J-272D01*
G02X934720Y109479I-1041J-1083D01*
G03X934726Y108922I290J-275D01*
G02X934699Y106782I-1068J-1057D01*
G37*
G36*
G01X1194108Y106576D02*
G03X1194095Y106014I278J-288D01*
G02X1192047Y106004I-1019J-963D01*
G03X1192029Y106565I-293J271D01*
G02X1191980Y108696I1034J1090D01*
G03X1191986Y109245I-288J278D01*
G02X1192049Y111347I1103J1019D01*
G03X1192064Y111909I-277J289D01*
G02X1194114I1025J956D01*
G03X1194129Y111347I292J-273D01*
G02X1194172Y109223I-1040J-1083D01*
G03X1194166Y108674I288J-278D01*
G02X1194108Y106576I-1103J-1019D01*
G37*
G36*
G01X1157297D02*
G03X1157284Y106014I278J-288D01*
G02X1155236Y106004I-1019J-963D01*
G03X1155218Y106565I-293J271D01*
G02X1155169Y108696I1034J1090D01*
G03X1155175Y109245I-288J278D01*
G02X1155238Y111347I1103J1019D01*
G03X1155253Y111909I-277J289D01*
G02X1157303I1025J956D01*
G03X1157318Y111347I292J-273D01*
G02X1157361Y109223I-1040J-1083D01*
G03X1157355Y108674I288J-278D01*
G02X1157297Y106576I-1103J-1019D01*
G37*
G36*
G01X939777D02*
G03X939764Y106014I278J-288D01*
G02X937716Y106004I-1019J-963D01*
G03X937698Y106565I-293J271D01*
G02X937649Y108696I1034J1090D01*
G03X937655Y109245I-288J278D01*
G02X937718Y111347I1103J1019D01*
G03X937733Y111909I-277J289D01*
G02X939783I1025J956D01*
G03X939798Y111347I292J-273D01*
G02X939841Y109223I-1040J-1083D01*
G03X939835Y108674I288J-278D01*
G02X939777Y106576I-1103J-1019D01*
G37*
G36*
G01X954799Y106575D02*
G03X954787Y105996I270J-295D01*
G02X952803Y105985I-987J-996D01*
G03X952785Y106564I-285J281D01*
G02X954799Y106575I1001J1120D01*
G37*
G36*
G01X948267Y106735D02*
G03X948281Y106170I290J-275D01*
G02X946211Y106176I-1038J-1086D01*
G03X946228Y106740I-275J291D01*
G02X948267Y106735I1022J960D01*
G37*
G36*
G01X1811279Y105590D02*
G03X1811804Y105567I276J290D01*
G02X1811709Y103305I939J-1172D01*
G03X1811184Y103328I-276J-290D01*
G02X1809199Y103422I-939J1172D01*
G03X1808660Y103438I-278J-287D01*
G02Y105562I-915J1062D01*
G03X1809199Y105578I261J303D01*
G02X1811279Y105590I1046J-1078D01*
G37*
G36*
G01X1072122Y104689D02*
G03X1072109Y104110I269J-296D01*
G02X1070124Y104103I-989J-994D01*
G03X1070108Y104682I-284J282D01*
G02X1072122Y104689I1003J1118D01*
G37*
G36*
G01X1065435Y104685D02*
G03X1065420Y104106I268J-297D01*
G02X1063435Y104107I-993J-990D01*
G03X1063420Y104686I-283J282D01*
G02X1065435Y104685I1008J1114D01*
G37*
G36*
G01X1058761Y104654D02*
G03X1058746Y104086I274J-291D01*
G02X1056722I-1012J-970D01*
G03X1056707Y104654I-289J277D01*
G02X1058761I1027J1096D01*
G37*
G36*
G01X1051990Y104686D02*
G03X1051975Y104106I268J-297D01*
G02X1049991I-992J-990D01*
G03X1049976Y104686I-283J283D01*
G02X1051990I1007J1114D01*
G37*
G36*
G01X1078304Y104680D02*
G03X1078290Y104097I267J-298D01*
G02X1076318I-986J-997D01*
G03X1076304Y104680I-281J285D01*
G02X1078304I1000J1120D01*
G37*
G36*
G01X1876102Y103939D02*
G03X1875735Y103468I26J-399D01*
G02X1872860Y102647I-1477J-272D01*
G03X1872347Y102875I-372J-146D01*
G02X1873130Y104771I-492J1313D01*
G03X1873654Y104571I364J167D01*
G02X1874157Y104695I606J-1375D01*
G03X1874524Y105166I-26J399D01*
G02X1876102Y103939I1477J272D01*
G37*
G36*
G01X977419Y104723D02*
G03X977512Y104164I325J-233D01*
G02X975516Y102270I-812J-1143D01*
G03X974939Y102377I-338J-214D01*
G02X974274Y104891I-839J1123D01*
G03X974718Y105354I50J397D01*
G02X977419Y104723I1482J246D01*
G37*
G36*
G01X1270315Y101177D02*
G03X1269685I-315J-246D01*
G02X1267445Y103169I-1185J923D01*
G03X1267466Y103715I-281J284D01*
G02X1269741Y105677I1134J985D01*
G03X1270349I304J260D01*
G02X1272590Y103678I1141J-977D01*
G03X1272592Y103131I293J-272D01*
G02X1270315Y101177I-1092J-1031D01*
G37*
G36*
G01X1323598Y101146D02*
G03X1324138Y101133I277J289D01*
G02X1324023Y98980I987J-1132D01*
G03X1323485Y99025I-294J-272D01*
G02X1323598Y101146I-857J1109D01*
G37*
G36*
G01X757896Y100973D02*
G03Y100427I292J-273D01*
G02X755704I-1096J-1027D01*
G03Y100973I-292J273D01*
G02X757896I1096J1027D01*
G37*
G36*
G01X1789506Y100381D02*
G03X1789462Y99789I245J-316D01*
G02X1787590Y99929I-1014J-969D01*
G03X1787634Y100521I-245J316D01*
G02X1789506Y100381I1014J969D01*
G37*
G36*
G01X1312679Y92960D02*
G03X1312681Y92430I300J-264D01*
G02X1310546Y92540I-1122J-999D01*
G03X1310545Y92836I-135J148D01*
G02X1310471Y92908I1010J1112D01*
G03X1310169Y92892I-144J-139D01*
G02X1308020Y94967I-1185J923D01*
G03X1308018Y95582I-257J307D01*
G02X1309935Y95589I954J1160D01*
G03X1309937Y94974I257J-307D01*
G01X1309938D01*
G03X1310478Y95003I254J309D01*
G02X1312679Y92960I1074J-1050D01*
G37*
G36*
G01X1676462Y91763D02*
G03X1677015Y91552I372J146D01*
G02X1676369Y89729I634J-1251D01*
G03X1675806Y89914I-365J-163D01*
G02X1676462Y91763I-744J1305D01*
G37*
G36*
G01X1851554Y93382D02*
G03Y92818I283J-282D01*
G02X1847298I-2128J-2118D01*
G03Y93382I-283J282D01*
G02X1846827Y93998I2129J2116D01*
G02X1846720Y96800I-27J1402D01*
G02X1850888Y98122I2706J-1300D01*
G03X1851419Y98256I194J350D01*
G02X1852772Y96109I1181J-756D01*
G03X1852422Y95687I49J-397D01*
G02X1851554Y93382I-2996J-188D01*
G37*
G36*
G01X1675907Y88007D02*
G03X1676501Y87982I308J255D01*
G02X1676415Y85973I1072J-1052D01*
G03X1675821Y85998I-308J-255D01*
G02X1675907Y88007I-1072J1052D01*
G37*
G36*
G01X1810887Y85685D02*
G03X1810347I-270J-295D01*
G02X1808049Y87908I-1080J1183D01*
G03Y88428I-304J260D01*
G02X1808084Y90548I1218J1040D01*
G03Y91088I-295J270D01*
G02Y93248I1183J1080D01*
G03Y93788I-295J270D01*
G02X1810347Y96051I1183J1080D01*
G03X1810887I270J295D01*
G02X1813047I1080J-1183D01*
G03X1813587I270J295D01*
G02X1815850Y93788I1080J-1183D01*
G03Y93248I295J-270D01*
G02Y91088I-1183J-1080D01*
G03Y90548I295J-270D01*
G02X1815885Y88428I-1183J-1080D01*
G03Y87908I304J-260D01*
G02X1813587Y85685I-1218J-1040D01*
G03X1813047I-270J-295D01*
G02X1810887I-1080J1183D01*
G37*
G36*
G01X1660143Y86878D02*
G03X1660112Y86354I286J-280D01*
G02X1657888I-1112J-854D01*
G03X1657857Y86878I-317J244D01*
G02X1660143I1143J1122D01*
G37*
G36*
G01X1319249Y84199D02*
G03X1318681Y84010I-200J-346D01*
G02X1316128Y85539I-1381J589D01*
G03X1316105Y86064I-313J249D01*
G02X1316107Y88133I1090J1033D01*
G03X1316129Y88659I-290J276D01*
G02X1318388Y88565I1171J941D01*
G03X1318366Y88039I290J-276D01*
G02X1318696Y87157I-1171J-941D01*
G03X1319286Y86821I400J16D01*
G02X1319249Y84199I714J-1321D01*
G37*
G36*
G01X1756536Y83562D02*
G03X1755952Y83415I-228J-329D01*
G02X1755449Y85240I-1249J638D01*
G03X1756027Y85413I214J338D01*
G02X1758461Y85852I1368J-619D01*
G03X1759085Y85924I284J282D01*
G02X1759298Y84078I1279J-788D01*
G03X1758674Y84006I-284J-282D01*
G02X1756536Y83562I-1279J788D01*
G37*
G36*
G01X1664513Y80468D02*
G03X1663987I-263J-302D01*
G02Y82732I-987J1132D01*
G03X1664513I263J302D01*
G02X1666487I987J-1132D01*
G03X1667013I263J302D01*
G02X1669046Y82678I987J-1132D01*
G03X1669585Y82662I278J287D01*
G02X1671415I915J-1062D01*
G03X1671954Y82678I261J303D01*
G02X1673987Y82732I1046J-1078D01*
G03X1674513I263J302D01*
G02X1676487I987J-1132D01*
G03X1677013I263J302D01*
G02Y80468I987J-1132D01*
G03X1676487I-263J-302D01*
G02X1674513I-987J1132D01*
G03X1673987I-263J-302D01*
G02X1671954Y80522I-987J1132D01*
G03X1671415Y80538I-278J-287D01*
G02X1669585I-915J1062D01*
G03X1669046Y80522I-261J-303D01*
G02X1667013Y80468I-1046J1078D01*
G03X1666487I-263J-302D01*
G02X1664513I-987J1132D01*
G37*
G36*
G01X1799809Y81895D02*
G03X1800152Y81394I386J-104D01*
G02X1798645Y80361I-152J-1394D01*
G03X1798302Y80862I-386J104D01*
G02X1799809Y81895I152J1394D01*
G37*
G36*
G01X1695196Y79073D02*
G03X1695481Y79081I139J144D01*
G02Y76901I1174J-1090D01*
G03X1695196Y76909I-146J-136D01*
G02X1693168Y76859I-1041J1082D01*
G03X1692642I-263J-302D01*
G02X1690668I-987J1132D01*
G03X1690142I-263J-302D01*
G02Y79123I-987J1132D01*
G03X1690668I263J302D01*
G02X1692642I987J-1132D01*
G03X1693168I263J302D01*
G02X1695196Y79073I987J-1132D01*
G37*
G36*
G01X1822075Y76146D02*
G03X1821535I-270J-295D01*
G02X1819255Y78390I-1079J1184D01*
G03X1819261Y78912I-300J264D01*
G02X1821568Y81126I1226J1032D01*
G03X1822108I270J295D01*
G02X1824388Y78882I1079J-1184D01*
G03X1824382Y78360I300J-264D01*
G02X1822075Y76146I-1226J-1032D01*
G37*
G36*
G01X1675057Y76022D02*
G03X1675610Y75906I335J219D01*
G02X1675171Y73824I818J-1260D01*
G03X1674618Y73940I-335J-219D01*
G02X1675057Y76022I-818J1260D01*
G37*
G36*
G01X1680956Y75568D02*
G03X1681481Y75535I281J284D01*
G02X1681340Y73276I915J-1191D01*
G03X1680815Y73309I-281J-284D01*
G02X1680956Y75568I-915J1191D01*
G37*
G36*
G01X1563773Y75324D02*
G03X1563830Y74780I319J-242D01*
G02X1561652Y74549I-981J-1138D01*
G03X1561595Y75093I-319J242D01*
G02X1563773Y75324I981J1138D01*
G37*
G36*
G01X1832657Y71664D02*
G03X1832946Y71653I150J133D01*
G02X1832973Y69324I1113J-1152D01*
G03X1832454Y69343I-271J-295D01*
G02X1830277Y71680I-994J1256D01*
G03Y72220I-295J270D01*
G02X1832643I1183J1080D01*
G03Y71680I295J-270D01*
G02X1832657Y71664I-1198J-1063D01*
G37*
G36*
G01X1767426Y71421D02*
G03X1768043Y71404I316J246D01*
G02X1767945Y69421I1207J-1054D01*
G03X1767329Y69465I-326J-231D01*
G02X1767426Y71421I-1089J1034D01*
G37*
G36*
G01X1825167Y71302D02*
G03X1825191Y70703I276J-289D01*
G02X1823012Y68364I-1011J-1243D01*
G03X1822431Y68366I-291J-274D01*
G02X1820139Y70604I-1161J1104D01*
G03X1820099Y71206I-282J284D01*
G02X1822273Y73537I970J1275D01*
G03X1822871Y73533I301J264D01*
G02X1825167Y71302I1189J-1073D01*
G37*
G36*
G01X1795700Y70821D02*
G03X1796100Y70402I400J-19D01*
G01X1796101D01*
G02X1794500Y68877I-1J-1602D01*
G03X1794100Y69296I-400J19D01*
G01X1794099D01*
G02X1795700Y70821I1J1602D01*
G37*
G36*
G01X1328558Y66934D02*
G03Y66366I282J-284D01*
G02X1326442I-1058J-1066D01*
G03Y66934I-282J284D01*
G02X1326464Y69088I1058J1066D01*
G03X1326458Y69674I-275J290D01*
G02X1328503Y69698I1010J1112D01*
G03X1328509Y69112I275J-290D01*
G02X1328558Y66934I-1009J-1112D01*
G37*
G36*
G01X1785925Y65083D02*
G03X1786325Y64743I395J60D01*
G02X1784991Y62964I16J-1402D01*
G03X1784553Y63253I-385J-108D01*
G02X1785925Y65083I-212J1588D01*
G37*
G36*
G01X1798661Y63047D02*
G03X1798665Y62454I270J-295D01*
G02X1796606Y60268I-1001J-1120D01*
G03X1796044Y60270I-282J-284D01*
G02X1793953Y60258I-1052J1072D01*
G03X1793404Y60262I-277J-289D01*
G02X1791366Y62469I-1022J1101D01*
G03X1791362Y63062I-270J295D01*
G02X1793402Y65266I1001J1120D01*
G03X1793951Y65262I277J289D01*
G02X1796031Y65227I1022J-1101D01*
G03X1796593Y65225I282J284D01*
G02X1798661Y63047I1052J-1072D01*
G37*
G36*
G01X1747577Y59845D02*
G03X1748119Y59727I332J223D01*
G02X1747734Y57690I735J-1194D01*
G03X1747186Y57778I-320J-240D01*
G02X1747577Y59845I-858J1233D01*
G37*
G36*
G01X1734177Y57140D02*
G03X1733623I-277J-288D01*
G02X1731640Y59123I-973J1010D01*
G03Y59677I-288J277D01*
G02X1733623Y61660I1010J973D01*
G03X1734177I277J288D01*
G02X1736160Y59677I973J-1010D01*
G03Y59123I288J-277D01*
G02X1734177Y57140I-1010J-973D01*
G37*
G36*
G01X1712801Y54815D02*
G03X1712253Y54697I-214J-338D01*
G02X1711871Y56748I-1253J828D01*
G03X1712424Y56836I232J326D01*
G02X1712801Y54815I1126J-836D01*
G37*
G36*
G01X1825893Y54749D02*
G03X1826068Y54496I193J-54D01*
G02X1824348Y53154I-138J-1596D01*
G03X1824033Y53610I-395J64D01*
G02X1823249Y56344I317J1570D01*
G03X1823261Y56913I-275J290D01*
G02X1823034Y58850I1149J1116D01*
G03X1822918Y59383I-344J204D01*
G02X1825206Y59880I912J1317D01*
G03X1825322Y59347I344J-204D01*
G02X1825980Y58351I-912J-1318D01*
G03X1826477Y58045I392J80D01*
G02X1826212Y55053I423J-1545D01*
G03X1825929Y54907I-86J-180D01*
G02X1825893Y54749I-1578J276D01*
G37*
G36*
G01X1668585Y50438D02*
G03X1668046Y50422I-261J-303D01*
G02Y52578I-1046J1078D01*
G03X1668585Y52562I278J287D01*
G02X1670473Y52510I915J-1062D01*
G03X1671027I277J288D01*
G02Y50490I973J-1010D01*
G03X1670473I-277J-288D01*
G02X1668585Y50438I-973J1010D01*
G37*
G36*
G01X1744121Y46096D02*
G03X1743567I-277J-288D01*
G02Y48116I-973J1010D01*
G03X1744121I277J288D01*
G02Y46096I973J-1010D01*
G37*
G36*
G01X1809314Y38871D02*
G03X1809318Y38248I253J-310D01*
G02X1807510Y38197I-874J-1096D01*
G03X1807479Y38819I-267J298D01*
G02X1809314Y38871I884J1214D01*
G37*
G36*
G01X1792542Y35377D02*
G03X1792101Y34962I-42J-398D01*
G02X1790782Y36300I-1401J-62D01*
G03X1791204Y36735I24J399D01*
G02X1792542Y35377I1496J136D01*
G37*
G36*
G01X1799199Y36709D02*
G03X1799637Y36285I399J-26D01*
G02X1798372Y34915I137J-1395D01*
G03X1797915Y35317I-400J6D01*
G02X1799199Y36709I-215J1487D01*
G37*
G36*
G01X683076Y27208D02*
G03X682476I-300J-265D01*
G02Y29066I-1050J929D01*
G03X683076I300J265D01*
G02Y27208I1050J-929D01*
G37*
G36*
G01X1523758Y27469D02*
G03X1523264Y27176I-105J-386D01*
G02X1522198Y28870I-1364J324D01*
G03X1522677Y29189I85J391D01*
G02X1523758Y27469I1477J-271D01*
G37*
G36*
G01X1808320Y27830D02*
G03X1808887Y27760I318J243D01*
G02X1808629Y25673I935J-1175D01*
G03X1808062Y25743I-318J-243D01*
G02X1808320Y27830I-935J1175D01*
G37*
G36*
G01X1550847Y22724D02*
G03X1550321I-263J-302D01*
G02Y24988I-987J1132D01*
G03X1550847I263J302D01*
G02X1552861Y24952I987J-1132D01*
G03X1553407I273J292D01*
G02Y22760I1027J-1096D01*
G03X1552861I-273J-292D01*
G02X1550847Y22724I-1027J1096D01*
G37*
G36*
G01X1529230Y26922D02*
G03X1529190Y26318I241J-319D01*
G02X1526649Y27263I-2320J-2350D01*
G03X1527013Y27746I-27J399D01*
G02X1529230Y26922I1371J294D01*
G37*
G36*
G01X1532430Y23307D02*
G02Y24629I3693J661D01*
G02Y23307I3693J-661D01*
G37*
G36*
G01X1824363Y22761D02*
G03X1824904Y22737I284J282D01*
G02X1824807Y20526I966J-1150D01*
G03X1824266Y20550I-284J-282D01*
G02X1824363Y22761I-966J1150D01*
G37*
G36*
G01X690915Y16362D02*
G03X691454Y16378I261J303D01*
G02Y14222I1046J-1078D01*
G03X690915Y14238I-278J-287D01*
G02Y16362I-915J1062D01*
G37*
G36*
G01X1870141Y12086D02*
G03X1869536Y12015I-272J-293D01*
G02X1869308Y13948I-1250J833D01*
G03X1869913Y14019I272J293D01*
G02X1870141Y12086I1250J-833D01*
G37*
G36*
G01X1654869Y12118D02*
G03X1654492Y11670I20J-399D01*
G02X1653031Y12900I-1392J-170D01*
G03X1653408Y13348I-20J399D01*
G02X1654869Y12118I1392J170D01*
G37*
G36*
G01X1681428Y9870D02*
X1676428D01*
G02Y12892I0J1511D01*
G01X1681429D01*
G02X1682940Y11391I0J-1512D01*
G01Y11296D01*
X1682930Y11212D01*
G02X1681428Y9870I-1502J169D01*
G37*
G36*
G01X1643865Y9594D02*
X1638865D01*
G02Y12616I0J1511D01*
G01X1643866D01*
G02X1645376Y11115I-1J-1511D01*
G01Y11020D01*
X1645367Y10936D01*
G02X1643865Y9594I-1502J169D01*
G37*
G36*
G01X1663884Y10164D02*
Y10069D01*
X1663875Y9985D01*
G02X1662342Y8643I-1502J169D01*
G01X1657338Y8747D01*
G02X1657400Y11769I31J1511D01*
G01X1662403Y11665D01*
G02X1663884Y10164I-30J-1511D01*
G37*
G36*
G01X1401613Y8868D02*
G03X1401087I-263J-302D01*
G02Y11132I-987J1132D01*
G03X1401613I263J302D01*
G02X1403587I987J-1132D01*
G03X1404113I263J302D01*
G02Y8868I987J-1132D01*
G03X1403587I-263J-302D01*
G02X1401613I-987J1132D01*
G37*
G36*
G01X1809702Y10968D02*
G03X1809662Y10365I242J-319D01*
G02X1807696Y10497I-1059J-1065D01*
G03X1807736Y11100I-242J319D01*
G02X1809702Y10968I1059J1065D01*
G37*
G36*
G01X1754099Y10396D02*
G03X1754644Y10311I317J243D01*
G02X1754309Y8161I856J-1234D01*
G03X1753764Y8246I-317J-243D01*
G02X1754099Y10396I-856J1234D01*
G37*
G36*
G01X1666091Y5013D02*
G03X1665488Y4847I-235J-323D01*
G02X1664970Y6572I-1288J553D01*
G03X1665564Y6766I220J334D01*
G02X1666979Y7748I1416J-530D01*
G01X1671979D01*
G02X1673490Y6246I-1J-1512D01*
G01Y6151D01*
X1673481Y6067D01*
G02X1671979Y4724I-1502J168D01*
G01X1666979D01*
G02X1666091Y5013I1J1512D01*
G37*
G36*
G01X1653750Y4814D02*
X1648747D01*
G02X1648055Y4982I0J1511D01*
G03X1647500Y4776I-184J-355D01*
G02X1646775Y6579I-1300J524D01*
G03X1647318Y6814I165J364D01*
G02X1648748Y7836I1430J-489D01*
G01X1653749D01*
G02X1654940Y7254I-1J-1511D01*
G03X1655554Y7234I315J246D01*
G02X1655538Y5385I1046J-934D01*
G03X1654924Y5375I-303J-261D01*
G02X1653750Y4814I-1175J950D01*
G37*
G36*
G01X1431287Y6244D02*
X1431025D01*
G02Y9268I0J1512D01*
G01X1436026D01*
G02X1437536Y7766I-1J-1512D01*
G01Y7671D01*
X1437527Y7587D01*
G02X1437150Y6746I-1502J168D01*
G03X1437155Y6206I297J-267D01*
G02X1434808Y5712I-1024J-958D01*
G03X1434431Y6244I-377J132D01*
G01X1434351D01*
G03X1433976Y5706I0J-400D01*
G02X1431459Y5942I-1315J-486D01*
G03X1431287Y6244I-172J102D01*
G37*
G36*
G01X1625485Y3538D02*
G03X1624946Y3522I-261J-303D01*
G02Y5678I-1046J1078D01*
G03X1625485Y5662I278J287D01*
G02Y3538I915J-1062D01*
G37*
G36*
G01X1491399Y5398D02*
X1491101D01*
G03X1490768Y4776I0J-400D01*
G02X1488486Y4852I-1168J-776D01*
G03X1488294Y5474I-318J243D01*
G02X1488770Y8420I476J1435D01*
G01X1493771D01*
G02X1495282Y6919I0J-1512D01*
G01Y6824D01*
X1495272Y6740D01*
G02X1494220Y5466I-1502J169D01*
G03X1494020Y4844I119J-382D01*
G02X1491732Y4776I-1120J-844D01*
G03X1491399Y5398I-333J222D01*
G37*
G36*
G01X1837185Y2838D02*
G03X1836646Y2822I-261J-303D01*
G02Y4978I-1046J1078D01*
G03X1837185Y4962I278J287D01*
G02Y2838I915J-1062D01*
G37*
G36*
G01X1472024Y4078D02*
X1471463D01*
G03X1471095Y3520I0J-400D01*
G02X1468657Y3769I-1288J-553D01*
G03X1468551Y4331I-328J229D01*
G02X1469388Y7100I837J1258D01*
G01X1474389D01*
G02X1475900Y5599I0J-1512D01*
G01Y5504D01*
X1475890Y5420D01*
G02X1475050Y4230I-1502J169D01*
G03X1474881Y3667I175J-359D01*
G02X1472390Y3517I-1207J-714D01*
G03X1472024Y4078I-366J161D01*
G37*
G36*
G01X715347Y4379D02*
G03Y3825I288J-277D01*
G02X713327I-1010J-973D01*
G03Y4379I-288J277D01*
G02Y6325I1010J973D01*
G03Y6879I-288J277D01*
G02X715347I1010J973D01*
G03Y6325I288J-277D01*
G02Y4379I-1010J-973D01*
G37*
G36*
G01X1453150Y4078D02*
X1452056D01*
G03X1451713Y3473I1J-400D01*
G02X1449420Y3640I-1205J-717D01*
G03X1449294Y4248I-310J253D01*
G02X1449991Y7100I697J1341D01*
G01X1454992D01*
G02X1456502Y5599I-1J-1511D01*
G01Y5504D01*
X1456493Y5420D01*
G02X1455827Y4330I-1502J169D01*
G03X1455752Y3727I221J-334D01*
G02X1453498Y3479I-1037J-943D01*
G03X1453150Y4078I-348J199D01*
G37*
G36*
G01X1825926Y2808D02*
G03X1826086Y2294I363J-169D01*
G02X1823962Y1633I-762J-1294D01*
G03X1823802Y2147I-363J169D01*
G02X1825926Y2808I762J1294D01*
G37*
G36*
G01X1600115Y-1732D02*
G03X1599589I-263J-302D01*
G02Y532I-987J1132D01*
G03X1600115I263J302D01*
G02Y-1732I987J-1132D01*
G37*
G36*
G01X1837002D02*
G03X1837485Y-2131I400J-8D01*
G02X1836298Y-3568I315J-1469D01*
G03X1835815Y-3169I-400J8D01*
G02X1837002Y-1732I-315J1469D01*
G37*
G36*
G01X1607315Y-4523D02*
G03X1606685I-315J-246D01*
G02Y-2677I-1185J923D01*
G03X1607315I315J246D01*
G02Y-4523I1185J-923D01*
G37*
G36*
G01X1381506Y-3690D02*
G03X1381956Y-4056I399J31D01*
G02X1380653Y-5660I195J-1489D01*
G03X1380203Y-5294I-399J-31D01*
G02X1381506Y-3690I-195J1489D01*
G37*
G36*
G01X1372599Y-4397D02*
G03Y-4951I288J-277D01*
G02X1370579I-1010J-973D01*
G03Y-4397I-288J277D01*
G02X1370610Y-2421I1010J972D01*
G03X1370623Y-1862I-279J286D01*
G02X1372629Y-1910I1026J955D01*
G03X1372616Y-2469I279J-286D01*
G02X1372599Y-4397I-1027J-955D01*
G37*
G36*
G01X718758Y-5937D02*
G03X718305Y-6270I-58J-396D01*
G02X717047Y-4652I-1384J222D01*
G03X717481Y-4295I36J398D01*
G02X718758Y-5937I1494J-156D01*
G37*
G36*
G01X1583532Y-7764D02*
G03X1582993Y-7780I-261J-303D01*
G02X1580901I-1046J1078D01*
G03X1580362Y-7764I-278J-287D01*
G02Y-5640I-915J1062D01*
G03X1580901Y-5624I261J303D01*
G02X1582993I1046J-1078D01*
G03X1583532Y-5640I278J287D01*
G02Y-7764I915J-1062D01*
G37*
G36*
G01X1894156Y-11057D02*
G03X1894172Y-11596I303J-261D01*
G02X1892016I-1078J-1046D01*
G03X1892032Y-11057I-287J278D01*
G02X1894156I1062J915D01*
G37*
G36*
G01X718258Y-14370D02*
G03X718635Y-14747I399J22D01*
G02X717155Y-16225I-80J-1400D01*
G03X716778Y-15848I-399J-22D01*
G02X718258Y-14370I80J1400D01*
G37*
G36*
G01X1585513Y-17232D02*
G03X1584987I-263J-302D01*
G02Y-14968I-987J1132D01*
G03X1585513I263J302D01*
G02Y-17232I987J-1132D01*
G37*
G36*
G01X1375736Y-17802D02*
G03X1375155Y-17824I-280J-285D01*
G02X1373046I-1055J924D01*
G03X1372502Y-17769I-301J-263D01*
G02X1370658Y-15667I-849J1115D01*
G03X1370647Y-15093I-284J282D01*
G02X1370569Y-13124I958J1024D01*
G03X1370568Y-12584I-296J269D01*
G02X1370580Y-10669I1030J951D01*
G03X1370588Y-10127I-290J275D01*
G02X1372650Y-10155I1044J936D01*
G03X1372642Y-10697I290J-275D01*
G02X1372634Y-12578I-1044J-936D01*
G03X1372635Y-13118I296J-269D01*
G02X1372600Y-15056I-1030J-951D01*
G03X1372611Y-15630I284J-282D01*
G02X1372707Y-15730I-962J-1020D01*
G03X1373251Y-15785I301J263D01*
G02X1375083Y-15900I850J-1115D01*
G03X1375664Y-15878I280J285D01*
G02X1375736Y-17802I1055J-924D01*
G37*
G36*
G01X1596517Y-18478D02*
G03X1595991I-263J-302D01*
G02Y-16214I-987J1132D01*
G03X1596517I263J302D01*
G02X1598491I987J-1132D01*
G03X1599017I263J302D01*
G02X1601050Y-16268I987J-1132D01*
G03X1601589Y-16284I278J287D01*
G02X1603419I915J-1062D01*
G03X1603958Y-16268I261J303D01*
G02X1605991Y-16214I1046J-1078D01*
G03X1606517I263J302D01*
G02X1608491I987J-1132D01*
G03X1609017I263J302D01*
G02Y-18478I987J-1132D01*
G03X1608491I-263J-302D01*
G02X1606517I-987J1132D01*
G03X1605991I-263J-302D01*
G02X1603958Y-18424I-987J1132D01*
G03X1603419Y-18408I-278J-287D01*
G02X1601589I-915J1062D01*
G03X1601050Y-18424I-261J-303D01*
G02X1599017Y-18478I-1046J1078D01*
G03X1598491I-263J-302D01*
G02X1596517I-987J1132D01*
G37*
G36*
G01X714198Y-16550D02*
G03X714405Y-17057I373J-143D01*
G02X712489Y-17906I-581J-1276D01*
G03X712252Y-17411I-381J122D01*
G02X714198Y-16550I544J1400D01*
G37*
G36*
G01X1347152Y-19392D02*
G03X1346567Y-19406I-286J-280D01*
G02X1346520Y-17495I-1049J930D01*
G03X1347105Y-17481I286J280D01*
G02X1347144Y-17438I1058J-920D01*
G03Y-16884I-288J277D01*
G02X1349164I1010J973D01*
G03Y-17438I288J-277D01*
G02X1349248Y-17534I-1012J-970D01*
G03X1349560I156J125D01*
G02X1351627Y-17401I1094J-877D01*
G03X1352181I277J288D01*
G02Y-19421I973J-1010D01*
G03X1351627I-277J-288D01*
G02X1349681I-973J1010D01*
G03X1349127I-277J-288D01*
G02X1347152Y-19392I-973J1010D01*
G37*
G36*
G01X1901565Y-18175D02*
G03X1902176Y-18281I349J196D01*
G02X1901851Y-20152I984J-1135D01*
G03X1901240Y-20046I-349J-196D01*
G02X1901565Y-18175I-984J1135D01*
G37*
G36*
G01X1946339Y473319D02*
G02X1946189Y474918I-1339J681D01*
G03X1946861Y474981I316J245D01*
G02X1947011Y473382I1339J-681D01*
G03X1946339Y473319I-316J-245D01*
G37*
G36*
G01X1774643Y472912D02*
G02X1773009Y473413I-1143J-812D01*
G03X1773168Y474053I-140J375D01*
G02X1774300Y476566I1132J1002D01*
G01X1779300D01*
G02X1780812Y475065I0J-1512D01*
G01Y474970D01*
X1780802Y474886D01*
G02X1780332Y473951I-1502J169D01*
G03X1780404Y473312I273J-293D01*
G02X1778557Y472912I-704J-1212D01*
G03X1778231Y473544I-326J232D01*
G01X1774969D01*
G03X1774643Y472912I0J-400D01*
G37*
G36*
G01X1721077Y472614D02*
G02X1720955Y471248I1270J-802D01*
G03X1720252Y471321I-371J-150D01*
G02X1720373Y472667I-1163J783D01*
G03X1721077Y472614I366J161D01*
G37*
G36*
G01X1783132Y466324D02*
G02Y467686I-1225J681D01*
G03X1783832I350J194D01*
G02Y466324I1225J-681D01*
G03X1783132I-350J-194D01*
G37*
G36*
G01X1770534D02*
G02Y467686I-1225J681D01*
G03X1771234I350J194D01*
G02Y466324I1225J-681D01*
G03X1770534I-350J-194D01*
G37*
G36*
G01X1757935D02*
G02Y467686I-1225J681D01*
G03X1758635I350J194D01*
G02Y466324I1225J-681D01*
G03X1757935I-350J-194D01*
G37*
G36*
G01X1745337D02*
G02Y467686I-1225J681D01*
G03X1746037I350J194D01*
G02Y466324I1225J-681D01*
G03X1745337I-350J-194D01*
G37*
G36*
G01X1902864Y453653D02*
G02X1900284Y453652I-1290J769D01*
G03X1899604Y453664I-344J-205D01*
G02X1897200Y453741I-1179J758D01*
G03X1896500I-350J-194D01*
G02Y455103I-1225J681D01*
G03X1897200I350J194D01*
G02X1899604Y455180I1225J-681D01*
G03X1900284Y455192I336J217D01*
G02X1902864Y455191I1290J-770D01*
G03X1903544Y455180I343J205D01*
G02X1905949Y455103I1179J-758D01*
G03X1906649I350J194D01*
G02Y453741I1225J-681D01*
G03X1905949I-350J-194D01*
G02X1903544Y453664I-1226J681D01*
G03X1902864Y453653I-337J-216D01*
G37*
G36*
G01X1829823Y449415D02*
G02X1829523Y451155I-1223J685D01*
G03X1830144Y451277I263J301D01*
G02X1831495Y452112I1352J-677D01*
G01X1836495D01*
G02X1837749Y451444I0J-1512D01*
G03X1838374Y451395I332J223D01*
G02X1838275Y449604I1026J-955D01*
G03X1837649Y449623I-321J-239D01*
G02X1836495Y449088I-1154J977D01*
G01X1831494D01*
G02X1830449Y449509I2J1512D01*
G03X1829823Y449415I-277J-289D01*
G37*
G36*
G01X1768366Y451920D02*
X1773366D01*
G02X1774878Y450418I0J-1512D01*
G01Y450323D01*
X1774868Y450239D01*
G02X1774814Y449974I-1502J168D01*
G03X1775284Y449468I383J-116D01*
G02X1776815Y448781I306J-1368D01*
G03X1777515I350J194D01*
G02X1779046Y449468I1225J-681D01*
G03X1779516Y449974I87J390D01*
G02X1780964Y451920I1448J434D01*
G01X1785964D01*
G02X1787476Y450418I0J-1512D01*
G01Y450323D01*
X1787466Y450239D01*
G02X1787452Y450140I-1503J162D01*
G03X1787921Y449676I393J-71D01*
G02X1789392Y449019I268J-1376D01*
G03X1790091Y449042I343J206D01*
G02X1791593Y449779I1247J-642D01*
G03X1792063Y450221I73J393D01*
G02X1793563Y451920I1500J187D01*
G01X1798563D01*
G02X1800074Y450418I-1J-1512D01*
G01Y450323D01*
X1800065Y450239D01*
G02X1798563Y448896I-1502J169D01*
G01X1793562D01*
G02X1793224Y448935I3J1512D01*
G03X1792735Y448513I-90J-390D01*
G02X1790135Y447681I-1397J-112D01*
G03X1789436Y447658I-343J-206D01*
G02X1786800Y448493I-1247J641D01*
G03X1786312Y448937I-396J55D01*
G02X1785964Y448896I-350J1471D01*
G01X1780963D01*
G02X1780583Y448945I2J1512D01*
G03X1780096Y448456I-100J-387D01*
G02X1777515Y447419I-1356J-355D01*
G03X1776815I-350J-194D01*
G02X1774234Y448456I-1225J682D01*
G03X1773747Y448945I-387J102D01*
G02X1773366Y448896I-382J1463D01*
G01X1768366D01*
G02Y451920I0J1512D01*
G37*
G36*
G01X1860393Y448506D02*
G02X1858580Y449393I-1334J-430D01*
G03X1858824Y449892I-137J376D01*
G02X1858861Y450855I1334J431D01*
G03X1858523Y451405I-370J152D01*
G02X1859930Y452270I110J1398D01*
G03X1860268Y451720I370J-152D01*
G02X1860637Y449005I-110J-1398D01*
G03X1860393Y448506I137J-376D01*
G37*
G36*
G01X1751632Y447381D02*
G02X1749052Y448446I-1239J656D01*
G03X1748565Y448949I-382J117D01*
G02X1748169Y448896I-397J1459D01*
G01X1743169D01*
G02X1742849Y448931I3J1512D01*
G03X1742364Y448526I-85J-391D01*
G02X1739807Y447682I-1401J-50D01*
G03X1739104Y447599I-330J-226D01*
G02X1736649Y448907I-1310J500D01*
G03X1736496Y449498I-327J231D01*
G02X1738337Y449930I654J1352D01*
G03X1738463Y449333I316J-245D01*
G02X1738951Y448894I-668J-1233D01*
G03X1739654Y448977I330J226D01*
G02X1741197Y449858I1309J-501D01*
G03X1741663Y450285I67J394D01*
G02X1743169Y451920I1507J123D01*
G01X1748169D01*
G02X1749680Y450418I-1J-1512D01*
G01Y450323D01*
X1749671Y450239D01*
G02X1749599Y449920I-1501J171D01*
G03X1750070Y449401I379J-130D01*
G02X1751605Y448742I323J-1364D01*
G03X1752304Y448756I346J201D01*
G02X1753849Y449468I1239J-656D01*
G03X1754320Y449973I88J390D01*
G02X1755767Y451920I1448J435D01*
G01X1760767D01*
G02X1762278Y450418I-1J-1512D01*
G01Y450323D01*
X1762269Y450239D01*
G02X1760767Y448896I-1502J169D01*
G01X1755767D01*
G02X1755387Y448945I2J1512D01*
G03X1754899Y448457I-101J-387D01*
G02X1752331Y447395I-1356J-357D01*
G03X1751632Y447381I-346J-201D01*
G37*
G36*
G01X1818760Y451920D02*
X1823760D01*
G02X1825272Y450418I0J-1512D01*
G01Y450323D01*
X1825262Y450239D01*
G02X1825188Y449914I-1502J171D01*
G03X1825659Y449394I378J-131D01*
G02X1824645Y448445I325J-1364D01*
G03X1824158Y448950I-382J119D01*
G02X1823760Y448896I-400J1458D01*
G01X1818760D01*
G02X1818412Y448937I2J1512D01*
G03X1817924Y448493I-92J-389D01*
G02X1815384Y447499I-1389J-193D01*
G03X1814685Y447420I-328J-229D01*
G02X1814536Y448746I-1300J525D01*
G03X1815235Y448825I328J229D01*
G02X1816803Y449676I1300J-525D01*
G03X1817273Y450140I76J393D01*
G02X1818760Y451920I1488J268D01*
G37*
G36*
G01X1865545Y447255D02*
G02Y448545I-1245J645D01*
G03X1866255I355J184D01*
G02Y447255I1245J-645D01*
G03X1865545I-355J-184D01*
G37*
G36*
G01X1805305Y448413D02*
G02X1804314Y449266I-1305J-513D01*
G03X1804772Y449813I90J390D01*
G02X1806161Y451920I1389J595D01*
G01X1811161D01*
G02X1812672Y450418I-1J-1512D01*
G01Y450323D01*
X1812663Y450239D01*
G02X1811161Y448896I-1502J169D01*
G01X1806161D01*
G02X1805779Y448946I4J1512D01*
G03X1805305Y448413I-102J-387D01*
G37*
G36*
G01X1764900Y448624D02*
G02X1764882Y447205I1200J-725D01*
G03X1764192Y447214I-348J-198D01*
G02X1764210Y448633I-1200J725D01*
G03X1764900Y448624I348J198D01*
G37*
G36*
G01X1873956Y448977D02*
G02X1871764I-1096J-1027D01*
G03Y449523I-292J273D01*
G02X1871431Y451012I1096J1027D01*
G03X1871001Y451532I-381J123D01*
G02X1869722Y451992I-186J1490D01*
G03X1869133Y451984I-291J-275D01*
G02X1867965Y451486I-1118J1003D01*
G03X1867552Y451089I-13J-400D01*
G02X1866100Y452601I-1502J11D01*
G03X1866513Y452998I13J400D01*
G02X1869108Y454017I1502J-11D01*
G03X1869697Y454025I291J275D01*
G02X1872244Y452560I1118J-1003D01*
G03X1872674Y452040I381J-123D01*
G02X1873956Y449523I186J-1490D01*
G03Y448977I292J-273D01*
G37*
G36*
G01X1906123Y447384D02*
G02X1903434Y447161I-1399J546D01*
G03X1902754Y447172I-343J-205D01*
G02X1900349Y447248I-1180J758D01*
G03X1899650I-350J-194D01*
G02Y448612I-1225J682D01*
G03X1900349I349J194D01*
G02X1902754Y448688I1225J-682D01*
G03X1903434Y448699I337J216D01*
G02X1905903Y448860I1290J-769D01*
G03X1906585Y448951I314J248D01*
G02X1909099Y449082I1289J-551D01*
G03X1909798I350J194D01*
G02X1912251Y449077I1225J-682D01*
G03X1912931Y449045I350J194D01*
G02X1915488Y448926I1242J-845D01*
G03X1916150Y448869I350J193D01*
G02X1918566Y448772I1172J-939D01*
G03X1919228I331J224D01*
G02Y447088I1244J-842D01*
G03X1918566I-331J-224D01*
G02X1916007Y447204I-1244J842D01*
G03X1915345Y447261I-350J-193D01*
G02X1912834Y447519I-1172J939D01*
G03X1912155Y447573I-356J-182D01*
G02X1909798Y447718I-1132J827D01*
G03X1909099I-349J-194D01*
G02X1906802Y447497I-1225J682D01*
G03X1906123Y447384I-306J-258D01*
G37*
G36*
G01X1725352Y442736D02*
G02X1723568Y442871I-983J-1135D01*
G03X1723628Y443501I-214J338D01*
G02X1723579Y443550I967J1015D01*
G03X1723001I-289J-277D01*
G02Y445492I-1011J971D01*
G03X1723579I289J277D01*
G02X1725760Y445294I1011J-971D01*
G03X1726414Y445276I333J221D01*
G02X1726336Y443600I1206J-896D01*
G03X1725683Y443643I-342J-208D01*
G02X1725387Y443368I-1092J879D01*
G03X1725352Y442736I227J-330D01*
G37*
G36*
G01X1665820Y439101D02*
G02X1663704I-1058J-1066D01*
G03Y439669I-282J284D01*
G02X1663839Y441920I1058J1066D01*
G03Y442550I-246J315D01*
G02X1665685I923J1185D01*
G03Y441920I246J-315D01*
G02X1665828Y441793I-924J-1184D01*
G03X1666396I284J282D01*
G02X1668449Y441867I1066J-1058D01*
G03X1668975I263J302D01*
G02X1669106Y441969I987J-1132D01*
G03X1669076Y442646I-227J329D01*
G02X1668684Y444940I740J1307D01*
G03Y445466I-302J263D01*
G02Y447440I1132J987D01*
G03Y447966I-302J263D01*
G02X1671200Y449537I1132J987D01*
G03X1671884Y449446I369J155D01*
G02X1674198Y447533I1184J-924D01*
G03Y447007I301J-263D01*
G02X1673952Y444810I-1134J-985D01*
G03X1674054Y444111I236J-322D01*
G02X1674795Y441857I-504J-1415D01*
G03X1675126Y441233I332J-224D01*
G02X1673875Y440570I-5J-1502D01*
G03X1673544Y441194I-332J224D01*
G02X1672662Y443908I6J1502D01*
G03X1672560Y444607I-236J322D01*
G02X1671681Y445436I504J1415D01*
G03X1670998Y445526I-368J-156D01*
G02X1670948Y445466I-1178J931D01*
G03Y444940I302J-263D01*
G02X1670672Y442719I-1132J-987D01*
G03X1670702Y442042I227J-329D01*
G02X1670640Y439395I-740J-1307D01*
G03X1670454Y438879I181J-357D01*
G02X1667641Y438726I-1378J-598D01*
G03X1667302Y439242I-382J118D01*
G02X1666396Y439677I160J1493D01*
G03X1665828I-284J-282D01*
G02X1665820Y439669I-1066J1058D01*
G03Y439101I282J-284D01*
G37*
G36*
G01X1668579Y425859D02*
G02X1666942Y425900I-850J-1238D01*
G03X1666959Y426571I-209J341D01*
G02X1666846Y428962I850J1238D01*
G03X1666813Y429601I-256J307D01*
G02X1666878Y432138I836J1248D01*
G03X1666866Y432832I-205J344D01*
G02X1668359Y432860I722J1317D01*
G03X1668371Y432166I205J-344D01*
G02X1668612Y429696I-722J-1317D01*
G03X1668645Y429057I256J-307D01*
G02X1668596Y426530I-836J-1248D01*
G03X1668579Y425859I209J-341D01*
G37*
G36*
G01X1668695Y414289D02*
G02X1667241Y414313I-749J-1302D01*
G03X1667264Y415007I-187J354D01*
G02X1667031Y417213I736J1193D01*
G03X1667053Y417768I-277J289D01*
G02X1669069Y417687I1047J932D01*
G03X1669047Y417132I277J-289D01*
G02X1668696Y414983I-1047J-932D01*
G03X1668695Y414289I198J-347D01*
G37*
G36*
G01X1853700Y251924D02*
G02X1850929Y251708I-1400J76D01*
G03X1850471Y252019I-391J-83D01*
G02X1851704Y253730I-251J1481D01*
G03X1852144Y253393I396J61D01*
G02X1852703Y253343I157J-1393D01*
G03X1853218Y253720I115J383D01*
G02X1854230Y252280I1502J-20D01*
G03X1853700Y251924I-131J-378D01*
G37*
G36*
G01X1859470Y252106D02*
G02X1857345Y252123I-1070J-906D01*
G03X1857333Y252663I-301J263D01*
G02X1859671Y254531I1087J1037D01*
G03X1860360Y254569I333J221D01*
G02X1862690Y254813I1245J-644D01*
G03X1863289Y254791I309J254D01*
G02X1863220Y252937I1016J-966D01*
G03X1862621Y252959I-309J-254D01*
G02X1860462Y253113I-1016J966D01*
G03X1859776Y253053I-325J-232D01*
G02X1859490Y252646I-1355J648D01*
G03X1859470Y252106I285J-281D01*
G37*
G36*
G01X1803315Y250955D02*
G02X1802995Y249341I1073J-1051D01*
G03X1802349Y249481I-371J-150D01*
G02X1800321Y249584I-965J1017D01*
G03X1799692Y249557I-304J-260D01*
G02X1798384Y248886I-1309J941D01*
G01X1793384D01*
G02X1792075Y249558I0J1611D01*
G03X1791447Y249585I-325J-234D01*
G02Y251411I-1064J913D01*
G03X1792075Y251438I303J261D01*
G02X1793384Y252110I1309J-939D01*
G01X1798385D01*
G02X1799692Y251439I-2J-1612D01*
G03X1800321Y251412I325J233D01*
G02X1802664Y251071I1063J-914D01*
G03X1803315Y250955I365J163D01*
G37*
G36*
G01X1663986Y249465D02*
G02X1662827Y248123I338J-1463D01*
G03X1662338Y248545I-399J32D01*
G02X1663497Y249887I-338J1463D01*
G03X1663986Y249465I399J-32D01*
G37*
G36*
G01X1684710Y243483D02*
G02X1682478Y241514I-981J-1137D01*
G03X1681856Y241568I-333J-222D01*
G02X1680316Y244037I-1087J1037D01*
G03X1680524Y244646I-121J381D01*
G02X1682796Y246587I1236J854D01*
G03X1683374Y246615I276J290D01*
G02X1684874Y244174I1135J-984D01*
G03X1684710Y243483I97J-388D01*
G37*
G36*
G01X1667179Y243236D02*
G02X1665498Y243227I-834J-1249D01*
G03X1665495Y243890I-226J330D01*
G02X1667176Y243899I834J1249D01*
G03X1667179Y243236I226J-330D01*
G37*
G36*
G01X1824189Y235121D02*
G02X1824098Y236727I-1312J731D01*
G03X1824773Y236765I325J232D01*
G02X1824864Y235159I1312J-731D01*
G03X1824189Y235121I-325J-232D01*
G37*
G36*
G01X1837366Y234128D02*
G02X1835672Y233566I-466J-1428D01*
G03X1835470Y234176I-327J230D01*
G02X1837164Y234738I466J1428D01*
G03X1837366Y234128I327J-230D01*
G37*
G36*
G01X1821348Y232875D02*
G02Y231337I1290J-769D01*
G03X1820668Y231348I-343J-205D01*
G02Y232864I-1180J758D01*
G03X1821348Y232875I337J216D01*
G37*
G36*
G01X1910882Y218645D02*
G02X1909536Y218731I-759J-1296D01*
G03X1909581Y219445I-157J368D01*
G02X1909154Y221663I759J1296D01*
G03X1909114Y222198I-316J245D01*
G02X1909022Y224423I1105J1160D01*
G03X1909009Y224969I-299J266D01*
G02X1911350Y225025I1144J1121D01*
G03X1911363Y224479I299J-266D01*
G02X1911426Y222305I-1144J-1121D01*
G03X1911436Y221768I301J-263D01*
G02X1910927Y219359I-1096J-1027D01*
G03X1910882Y218645I157J-368D01*
G37*
G36*
G01X1848953Y212120D02*
G02Y213772I-1254J826D01*
G03X1849622I335J220D01*
G02Y212120I1254J-826D01*
G03X1848953I-334J-220D01*
G37*
G36*
G01X1884974Y209808D02*
G02X1882947Y211688I-1174J767D01*
G03Y212323I-243J317D01*
G02X1885054Y214063I853J1113D01*
G03X1885736Y214007I358J178D01*
G02X1887954Y212006I1216J-882D01*
G03X1887906Y211462I267J-298D01*
G02X1885639Y209813I-1106J-862D01*
G03X1884974Y209808I-331J-224D01*
G37*
G36*
G01X1801526Y210720D02*
X1796526D01*
G02Y213742I0J1511D01*
G01X1801527D01*
G02X1803038Y212241I0J-1512D01*
G01Y212146D01*
X1803028Y212062D01*
G02X1802928Y211665I-1502J167D01*
G03X1803248Y211119I371J-149D01*
G02X1801857Y210427I-176J-1391D01*
G03X1801665Y210726I-173J100D01*
G02X1801526Y210720I-135J1505D01*
G37*
G36*
G01X1809125Y213742D02*
X1814126D01*
G02X1815636Y212241I-1J-1511D01*
G01Y212146D01*
X1815627Y212062D01*
G02X1815527Y211665I-1502J167D01*
G03X1815847Y211119I371J-149D01*
G02X1814455Y210427I-177J-1391D01*
G03X1814263Y210726I-174J100D01*
G02X1814125Y210720I-135J1505D01*
G01X1809125D01*
G02X1809060Y210721I-9J1511D01*
G03X1808889Y210404I-9J-200D01*
G02X1807497Y210965I-1139J-818D01*
G03X1807780Y211541I-73J393D01*
G02X1809125Y213742I1345J690D01*
G37*
G36*
G01X1910116Y210136D02*
G02X1908533Y210016I-695J-1331D01*
G03X1908494Y210687I-236J323D01*
G02X1910054Y210805I692J1219D01*
G03X1910116Y210136I247J-314D01*
G37*
G36*
G01X1904485Y206330D02*
G02X1903176Y206122I-443J-1435D01*
G03X1903074Y206828I-230J327D01*
G02X1904363Y207033I450J1328D01*
G03X1904485Y206330I239J-321D01*
G37*
G36*
G01X1894288Y199946D02*
G02X1893117Y201535I-1497J123D01*
G03X1893603Y201893I87J390D01*
G02X1894423Y203111I1497J-123D01*
G03X1894531Y203745I-181J357D01*
G02X1896291Y203444I1084J1040D01*
G03X1896183Y202810I181J-357D01*
G02X1894774Y200304I-1083J-1040D01*
G03X1894288Y199946I-87J-390D01*
G37*
G36*
G01X1847808Y199983D02*
G02X1846358Y200068I-809J-1383D01*
G03X1846408Y200774I-161J366D01*
G02X1847839Y200691I792J1276D01*
G03X1847808Y199983I170J-362D01*
G37*
G36*
G01X1865205Y199772D02*
G02X1863859Y199841I-742J-1306D01*
G03X1863896Y200555I-161J366D01*
G02X1865242Y200486I742J1306D01*
G03X1865205Y199772I161J-366D01*
G37*
G36*
G01X1826682Y195330D02*
X1821681D01*
G02X1820184Y197046I1J1511D01*
G03X1819715Y197494I-396J55D01*
G02X1818236Y198183I-258J1378D01*
G03X1817528Y198161I-348J-197D01*
G02X1816017Y197392I-1262J611D01*
G03X1815547Y196966I-71J-394D01*
G02X1815552Y196851I-1506J-123D01*
G01Y196756D01*
X1815543Y196672D01*
G02X1814041Y195330I-1502J169D01*
G01X1809041D01*
G02X1807530Y196828I0J1511D01*
G03X1807061Y197219I-400J-3D01*
G02X1805834Y197605I-240J1381D01*
G03X1805244Y197576I-282J-284D01*
G02X1803533Y197221I-1078J896D01*
G03X1802952Y196859I-181J-357D01*
G01Y196756D01*
X1802943Y196672D01*
G02X1801441Y195330I-1502J169D01*
G01X1796440D01*
G02X1794943Y197046I1J1511D01*
G03X1794474Y197494I-396J55D01*
G02X1793012Y198153I-258J1378D01*
G03X1792313Y198131I-343J-205D01*
G02X1790817Y197392I-1247J641D01*
G03X1790347Y196966I-71J-394D01*
G02X1790352Y196851I-1506J-123D01*
G01Y196756D01*
X1790343Y196672D01*
G02X1788841Y195330I-1502J169D01*
G01X1783840D01*
G02X1782343Y197046I1J1511D01*
G03X1781874Y197494I-396J55D01*
G02X1780412Y198153I-258J1378D01*
G03X1779713Y198131I-343J-205D01*
G02X1778217Y197392I-1247J641D01*
G03X1777747Y196966I-71J-394D01*
G02X1777752Y196851I-1506J-123D01*
G01Y196756D01*
X1777743Y196672D01*
G02X1776241Y195330I-1502J169D01*
G01X1771240D01*
G02X1769743Y197046I1J1511D01*
G03X1769274Y197494I-396J55D01*
G02X1767812Y198153I-258J1378D01*
G03X1767113Y198131I-343J-205D01*
G02X1765638Y197389I-1247J641D01*
G03X1765175Y196962I-64J-395D01*
G02X1765180Y196853I-1507J-124D01*
G01Y196758D01*
X1765170Y196674D01*
G02X1763668Y195332I-1502J169D01*
G01X1758668D01*
G02X1757162Y196971I0J1511D01*
G03X1756727Y197404I-399J35D01*
G02X1758001Y198750I-127J1396D01*
G03X1758457Y198340I400J-14D01*
G02X1758668Y198354I205J-1497D01*
G01X1763669D01*
G02X1763982Y198322I4J-1511D01*
G03X1764465Y198726I83J391D01*
G02X1767070Y199491I1401J46D01*
G03X1767769Y199513I343J205D01*
G02X1770412Y198741I1247J-641D01*
G03X1770900Y198314I398J-37D01*
G02X1771241Y198352I337J-1473D01*
G01X1776242D01*
G02X1776577Y198315I3J-1511D01*
G03X1777065Y198720I88J390D01*
G02X1779670Y199491I1401J52D01*
G03X1780369Y199513I343J205D01*
G02X1783012Y198741I1247J-641D01*
G03X1783500Y198314I398J-37D01*
G02X1783841Y198352I337J-1473D01*
G01X1788842D01*
G02X1789177Y198315I3J-1511D01*
G03X1789665Y198720I88J390D01*
G02X1792270Y199491I1401J52D01*
G03X1792969Y199513I343J205D01*
G02X1795612Y198741I1247J-641D01*
G03X1796100Y198314I398J-37D01*
G02X1796441Y198352I337J-1473D01*
G01X1801442D01*
G02X1802171Y198164I-1J-1511D01*
G03X1802764Y198505I193J350D01*
G02X1805153Y199467I1402J-33D01*
G03X1805743Y199496I282J284D01*
G02X1808221Y198682I1078J-896D01*
G03X1808708Y198315I399J23D01*
G02X1809040Y198352I332J-1474D01*
G01X1814042D01*
G02X1814377Y198315I3J-1511D01*
G03X1814865Y198720I88J390D01*
G02X1817487Y199461I1401J52D01*
G03X1818195Y199483I348J197D01*
G02X1820853Y198741I1262J-611D01*
G03X1821341Y198314I398J-37D01*
G02X1821682Y198352I337J-1473D01*
G01X1826683D01*
G02X1826854Y198343I6J-1511D01*
G03X1827299Y198753I45J397D01*
G02X1830078Y198542I1401J47D01*
G03X1830459Y198068I393J-74D01*
G02X1828953Y196911I-44J-1501D01*
G03X1828594Y197402I-389J92D01*
G02X1828391Y197432I103J1398D01*
G03X1828152Y197191I-44J-195D01*
G02X1828194Y196851I-1469J-354D01*
G01Y196756D01*
X1828184Y196672D01*
G02X1826682Y195330I-1502J169D01*
G37*
G36*
G01X1746082Y198354D02*
X1751083D01*
G02X1751420Y198316I0J-1511D01*
G03X1751909Y198705I89J390D01*
G02X1753063Y197320I1402J-5D01*
G03X1752592Y196909I-71J-394D01*
G02X1752594Y196853I-1509J-82D01*
G01Y196758D01*
X1752584Y196674D01*
G02X1751082Y195332I-1502J169D01*
G01X1746082D01*
G02X1744576Y196973I0J1511D01*
G03X1744138Y197405I-399J34D01*
G02X1742794Y198085I-138J1395D01*
G03X1742106I-344J-204D01*
G02X1740553Y197442I-1206J715D01*
G03X1740058Y196996I-99J-388D01*
G02X1740074Y196786I-1495J-220D01*
G01Y196691D01*
X1740065Y196607D01*
G02X1738563Y195264I-1502J168D01*
G01X1733563D01*
G02X1732521Y195681I1J1512D01*
G03X1731858Y195487I-275J-290D01*
G02X1730322Y197350I-1458J363D01*
G03X1730425Y197715I-10J200D01*
G02X1730205Y197901I790J1158D01*
G03X1729627I-289J-277D01*
G02Y199843I-1011J971D01*
G03X1730205I289J277D01*
G02X1732602Y198662I1011J-971D01*
G03X1733116Y198220I395J-60D01*
G02X1733563Y198288I448J-1444D01*
G01X1738564D01*
G02X1738994Y198225I-2J-1512D01*
G03X1739506Y198651I114J383D01*
G02X1742106Y199515I1394J149D01*
G03X1742794I344J204D01*
G02X1745401Y198748I1206J-715D01*
G03X1745860Y198338I400J-14D01*
G02X1746082Y198354I219J-1495D01*
G37*
G36*
G01X1855752Y182799D02*
G02X1854077Y182758I-810J-1144D01*
G03X1854048Y183408I-247J315D01*
G02X1855176Y186137I820J1259D01*
G03X1855654Y186476I82J392D01*
G02X1856826Y184907I1390J-184D01*
G03X1856365Y184545I-62J-395D01*
G02X1855748Y183450I-1497J122D01*
G03X1855752Y182799I235J-324D01*
G37*
G36*
G01X1816582Y178036D02*
X1820383D01*
G02X1820478Y178033I0J-1511D01*
G03X1820600Y178400I12J200D01*
G02X1821693Y178211I766J1174D01*
G03X1821493Y177550I94J-389D01*
G02X1821894Y176535I-1111J-1026D01*
G01Y176440D01*
X1821884Y176356D01*
G02X1820382Y175014I-1502J169D01*
G01X1815382D01*
G02X1814269Y177548I0J1511D01*
G03X1814202Y178147I-295J270D01*
G02X1816231Y178628I798J1153D01*
G03X1816582Y178036I351J-192D01*
G37*
G36*
G01X1803907D02*
X1807785D01*
G02X1807880Y178033I0J-1511D01*
G03X1808002Y178400I12J200D01*
G02X1809095Y178211I766J1174D01*
G03X1808895Y177550I94J-389D01*
G02X1809296Y176535I-1111J-1026D01*
G01Y176440D01*
X1809286Y176356D01*
G02X1807784Y175014I-1502J169D01*
G01X1802784D01*
G02X1801695Y177573I0J1511D01*
G03X1801620Y178189I-288J277D01*
G02X1803566Y178645I749J1185D01*
G03X1803907Y178036I342J-209D01*
G37*
G36*
G01X1791408D02*
X1795187D01*
G02X1795281Y178033I-1J-1511D01*
G03X1795403Y178400I12J200D01*
G02X1796496Y178211I766J1174D01*
G03X1796296Y177550I93J-389D01*
G02X1796696Y176535I-1111J-1024D01*
G01Y176440D01*
X1796687Y176356D01*
G02X1795185Y175014I-1502J169D01*
G01X1790185D01*
G02X1789127Y177605I0J1512D01*
G03X1789074Y178220I-280J286D01*
G02X1791067Y178645I796J1154D01*
G03X1791408Y178036I342J-209D01*
G37*
G36*
G01X1778710D02*
X1782588D01*
G02X1782683Y178033I0J-1511D01*
G03X1782805Y178400I12J200D01*
G02X1783898Y178211I766J1174D01*
G03X1783698Y177550I94J-389D01*
G02X1784098Y176535I-1111J-1024D01*
G01Y176440D01*
X1784089Y176356D01*
G02X1782587Y175014I-1502J169D01*
G01X1777587D01*
G02X1776498Y177573I0J1511D01*
G03X1776423Y178189I-288J277D01*
G02X1778369Y178645I749J1185D01*
G03X1778710Y178036I342J-209D01*
G37*
G36*
G01X1929290Y171119D02*
G02X1929132Y169372I1010J-972D01*
G03X1928510Y169428I-333J-221D01*
G02X1928668Y171175I-1010J972D01*
G03X1929290Y171119I333J221D01*
G37*
G36*
G01X1808218Y163430D02*
G02X1806662I-778J-1400D01*
G03Y164130I-194J350D01*
G02Y166930I778J1400D01*
G03Y167630I-194J350D01*
G02X1808218I778J1400D01*
G03Y166930I194J-350D01*
G02Y164130I-778J-1400D01*
G03Y163430I194J-350D01*
G37*
G36*
G01X1930227Y157063D02*
G02X1928590Y154918I-516J-1304D01*
G03X1927993Y154966I-320J-240D01*
G02X1927254Y157520I-1041J1083D01*
G03X1927704Y158065I80J392D01*
G02X1930069Y157693I1296J535D01*
G03X1930227Y157063I305J-258D01*
G37*
G36*
G01X1834264Y152612D02*
G02Y154236I-1264J812D01*
G03X1834936I336J216D01*
G02Y152612I1264J-812D01*
G03X1834264I-336J-216D01*
G37*
G36*
G01X1879468Y152232D02*
G02X1877009Y151807I-1372J611D01*
G03X1876447Y151824I-290J-276D01*
G02X1874806Y154293I-1022J1101D01*
G03X1874842Y155003I-165J364D01*
G02X1876219Y154932I757J1297D01*
G03X1876183Y154222I165J-364D01*
G02X1876512Y153961I-760J-1296D01*
G03X1877074Y153944I290J276D01*
G02X1879273Y153776I1022J-1101D01*
G03X1879952Y153861I314J248D01*
G02X1880147Y152317I1372J-611D01*
G03X1879468Y152232I-314J-248D01*
G37*
G36*
G01X1923290Y152413D02*
G02X1922307Y151167I510J-1413D01*
G03X1921774Y151587I-397J44D01*
G02X1922757Y152833I-510J1413D01*
G03X1923290Y152413I397J-44D01*
G37*
G36*
G01X1829274Y151006D02*
G02X1827889Y151287I-933J-1046D01*
G03X1828026Y151964I-129J379D01*
G02X1829411Y151683I933J1046D01*
G03X1829274Y151006I129J-379D01*
G37*
G36*
G01X1838558Y150148D02*
G02X1837657Y151221I-1468J-318D01*
G03X1838199Y151676I151J370D01*
G02X1839100Y150603I1468J318D01*
G03X1838558Y150148I-151J-370D01*
G37*
G36*
G01X1907186Y150477D02*
G02X1906789Y148905I1141J-1124D01*
G03X1906129Y149083I-384J-111D01*
G02X1904293Y151442I-1036J1087D01*
G03X1904387Y152037I-213J339D01*
G02X1906339Y151728I1153J963D01*
G03X1906245Y151133I213J-339D01*
G02X1906520Y150634I-1154J-961D01*
G03X1907186Y150477I381J124D01*
G37*
G36*
G01X1916359Y147696D02*
G02X1913632Y147355I-1329J-446D01*
G03X1913265Y147784I-399J30D01*
G02X1913253Y150977I127J1597D01*
G03X1913528Y151629I-35J399D01*
G02X1913455Y151725I1158J956D01*
G03X1912881Y151813I-329J-228D01*
G02X1913196Y153855I-920J1187D01*
G03X1913770Y153767I329J228D01*
G02X1915967Y151789I920J-1187D01*
G03X1916307Y151178I340J-211D01*
G02X1917609Y150430I3J-1502D01*
G03X1918276Y150393I346J201D01*
G02X1918185Y148746I1208J-893D01*
G03X1917518Y148783I-346J-201D01*
G02X1916648Y148213I-1207J894D01*
G03X1916359Y147696I90J-390D01*
G37*
G36*
G01X1895112Y147343D02*
G02X1893942Y148513I-1471J-301D01*
G03X1894417Y148971I80J392D01*
G02X1894730Y150106I1383J229D01*
G03X1894687Y150667I-305J259D01*
G02X1896764Y150768I986J1133D01*
G03X1896776Y150206I291J-275D01*
G02X1895569Y147817I-976J-1006D01*
G03X1895112Y147343I-65J-394D01*
G37*
G36*
G01X1887306Y147734D02*
G02X1887324Y146316I1333J-692D01*
G03X1886625Y146317I-350J-194D01*
G02X1886606Y147714I-1225J682D01*
G03X1887306Y147734I344J204D01*
G37*
G36*
G01X1822653Y142693D02*
G02X1822539Y144352I-1305J744D01*
G03X1823204Y144397I318J243D01*
G02X1825459Y144816I1305J-744D01*
G03X1826109Y145076I253J310D01*
G02X1826646Y143788I1391J-176D01*
G03X1826004Y143509I-244J-317D01*
G02X1823318Y142738I-1495J144D01*
G03X1822653Y142693I-318J-243D01*
G37*
G36*
G01X1900817Y143276D02*
G02X1899095Y143417I-961J-1154D01*
G03X1899161Y144059I-202J345D01*
G02X1900857Y143920I939J1041D01*
G03X1900817Y143276I216J-337D01*
G37*
G36*
G01X1895705Y137455D02*
G02X1894230Y137351I-646J-1356D01*
G03X1894192Y138040I-221J333D01*
G02X1893916Y140345I642J1246D01*
G03X1893906Y140958I-262J302D01*
G02X1895786Y140944I949J1164D01*
G03X1895768Y140332I248J-314D01*
G02X1895645Y138143I-934J-1045D01*
G03X1895705Y137455I232J-326D01*
G37*
G36*
G01X1814421Y127229D02*
G02Y128723I-1303J747D01*
G03X1815115I347J199D01*
G02Y127229I1303J-747D01*
G03X1814421I-347J-199D01*
G37*
G36*
G01X1857943Y127804D02*
G02X1856097I-923J-1185D01*
G03Y128434I-246J315D01*
G02X1855521Y129531I923J1185D01*
G03X1854910Y129846I-399J-24D01*
G02X1853423Y132454I-795J1275D01*
G03X1853601Y132978I-185J355D01*
G02X1855654Y132280I1361J635D01*
G03X1855476Y131756I185J-355D01*
G02X1855614Y131209I-1361J-634D01*
G03X1856225Y130894I399J24D01*
G02X1857943Y128434I795J-1275D01*
G03Y127804I246J-315D01*
G37*
G36*
G01X1864336Y125295D02*
G02X1864310Y123644I1241J-845D01*
G03X1863641Y123655I-338J-214D01*
G02X1863667Y125306I-1241J845D01*
G03X1864336Y125295I338J214D01*
G37*
G36*
G01X1258689Y111984D02*
G02X1256948Y112014I-889J-1084D01*
G03X1256946Y112651I-243J318D01*
G02X1256980Y115074I904J1199D01*
G03Y115726I-232J326D01*
G02X1258747Y118155I870J1224D01*
G03X1259321Y118259I238J321D01*
G02X1259721Y116334I1179J-759D01*
G03X1259152Y116201I-222J-332D01*
G02X1258720Y115726I-1301J750D01*
G03Y115074I232J-326D01*
G02X1258713Y112621I-870J-1224D01*
G03X1258689Y111984I230J-328D01*
G37*
G36*
G01X1255492Y105937D02*
G02X1252899Y105146I-1192J-737D01*
G03X1252390Y105515I-400J-16D01*
G02X1253482Y106954I-410J1445D01*
G03X1253975Y106564I400J-1D01*
G02X1254208Y106599I324J-1364D01*
G03X1254336Y106940I-13J200D01*
G02X1255742Y106537I1065J1060D01*
G03X1255492Y105937I90J-390D01*
G37*
G36*
G01X1324967Y103473D02*
G02X1323023Y105417I-1167J777D01*
G03Y106083I-222J333D01*
G02X1324967Y108027I777J1167D01*
G03X1325633I333J222D01*
G02X1327577Y106083I1167J-777D01*
G03Y105417I222J-333D01*
G02X1325633Y103473I-777J-1167D01*
G03X1324967I-333J-222D01*
G37*
G36*
G01X1827759Y95846D02*
G02X1826363Y95910I-759J-1296D01*
G03X1826406Y96612I-169J363D01*
G02X1827781Y96548I744J1188D01*
G03X1827759Y95846I180J-357D01*
G37*
G36*
G01X1669057Y88609D02*
G02X1669003Y87232I1193J-736D01*
G03X1668301Y87249I-356J-183D01*
G02X1668356Y88647I-1301J751D01*
G03X1669057Y88609I361J172D01*
G37*
G36*
G01X1715133Y87043D02*
G02Y88757I-1233J857D01*
G03X1715781Y88745I328J229D01*
G02Y87055I1119J-845D01*
G03X1715133Y87043I-320J-241D01*
G37*
G36*
G01X754099Y83008D02*
G02X751591Y84535I-1419J492D01*
G03X751574Y85103I-290J276D01*
G02X753689Y85165I1026J1097D01*
G03X753706Y84597I290J-276D01*
G02X753780Y84523I-1024J-1098D01*
G03X754123Y84622I146J136D01*
G02X754704Y83207I1377J-261D01*
G03X754099Y83008I-227J-330D01*
G37*
G36*
G01X1665482Y70949D02*
G02X1663218I-1132J-987D01*
G03Y71475I-302J263D01*
G02X1663186Y71513I1133J986D01*
G03X1662848Y71467I-155J-126D01*
G02X1661123Y70697I-1285J561D01*
G03X1660598Y70311I-125J-380D01*
G02X1659636Y71622I-1402J-20D01*
G03X1660161Y72008I125J380D01*
G02X1660178Y72245I1402J19D01*
G03X1659870Y72443I-198J31D01*
G02X1658127Y72604I-771J1171D01*
G03X1657573I-277J-288D01*
G02Y74624I-973J1010D01*
G03X1658127I277J288D01*
G02X1660500Y73684I973J-1010D01*
G03X1661047Y73332I399J20D01*
G02X1662453Y73111I515J-1304D01*
G03X1663053Y73219I254J309D01*
G02X1665482Y71475I1297J-756D01*
G03Y70949I302J-263D01*
G37*
G36*
G01X1758881Y66758D02*
G02X1758714Y65025I1135J-984D01*
G03X1758076Y65099I-346J-200D01*
G02X1758240Y66806I-1022J960D01*
G03X1758881Y66758I338J214D01*
G37*
G36*
G01X1817315Y55795D02*
G02X1817298Y53727I1081J-1043D01*
G03X1816718Y53732I-292J-273D01*
G02X1814148Y54972I-1081J1043D01*
G03X1813652Y55411I-397J52D01*
G02X1812212Y55808I-374J1455D01*
G03X1811644I-284J-282D01*
G02X1809515Y55805I-1066J1058D01*
G03X1808955Y55811I-283J-283D01*
G02X1806882Y55805I-1040J1084D01*
G03X1806328Y55802I-275J-290D01*
G02X1804111Y55940I-1046J1078D01*
G03X1803446Y55877I-312J-251D01*
G02X1803290Y57521I-1327J703D01*
G03X1803955Y57584I312J251D01*
G02X1804255Y57976I1327J-704D01*
G03X1804282Y58531I-274J291D01*
G02X1804296Y60528I1129J991D01*
G03X1804269Y61092I-297J268D01*
G02X1806320Y63285I1012J1109D01*
G03X1806869Y63281I277J289D01*
G02X1808949Y63246I1022J-1101D01*
G03X1809511Y63244I282J284D01*
G02X1811669Y63189I1052J-1072D01*
G03X1812257I294J270D01*
G02X1814441Y61126I1106J-1017D01*
G03X1814447Y60563I287J-278D01*
G02X1814432Y58408I-1054J-1070D01*
G03X1814408Y57856I277J-289D01*
G02X1814767Y56669I-1130J-990D01*
G03X1815263Y56230I397J-52D01*
G02X1816735Y55800I374J-1455D01*
G03X1817315Y55795I292J273D01*
G37*
G36*
G01X1710803Y45080D02*
G02X1710636Y46744I-1203J720D01*
G03X1711283Y46822I296J270D01*
G02X1713646Y47178I1317J-722D01*
G03X1714185Y47162I278J287D01*
G02X1716073Y47110I915J-1062D01*
G03X1716627I277J288D01*
G02X1718573I973J-1010D01*
G03X1719127I277J288D01*
G02Y45090I973J-1010D01*
G03X1718573I-277J-288D01*
G02X1716627I-973J1010D01*
G03X1716073I-277J-288D01*
G02X1714185Y45038I-973J1010D01*
G03X1713646Y45022I-261J-303D01*
G02X1711452Y45132I-1046J1078D01*
G03X1710803Y45080I-306J-258D01*
G37*
G36*
G01X1828965Y39990D02*
G02X1828078Y38655I615J-1371D01*
G03X1827515Y39030I-400J10D01*
G02X1826048Y39163I-615J1370D01*
G03X1825466Y39016I-226J-330D01*
G02X1824982Y40940I-1336J687D01*
G03X1825564Y41087I226J330D01*
G02X1828402Y40365I1336J-687D01*
G03X1828965Y39990I400J-10D01*
G37*
G36*
G01X1707856Y37356D02*
G02X1706640Y38395I-1356J-356D01*
G03X1707062Y38910I40J398D01*
G02X1708508Y40862I1446J440D01*
G01X1712309D01*
G02X1713820Y39360I-1J-1512D01*
G01Y39265D01*
X1713810Y39181D01*
G02X1712308Y37838I-1502J168D01*
G01X1708508D01*
G02X1708298Y37853I2J1512D01*
G03X1707856Y37356I-55J-396D01*
G37*
G36*
G01X1699272Y41190D02*
X1703074D01*
G02X1704584Y39689I-1J-1511D01*
G01Y39594D01*
X1704575Y39510D01*
G02X1703073Y38168I-1502J169D01*
G01X1699273D01*
G02X1698710Y38276I-2J1511D01*
G03X1698169Y37984I-149J-371D01*
G02X1695438Y37906I-1374J276D01*
G03X1694852Y38152I-387J-101D01*
G02X1694098Y37950I-755J1310D01*
G01X1689098D01*
G02X1688932Y37960I8J1512D01*
G03X1688734Y37666I-22J-199D01*
G02X1687351Y38394I-1234J-666D01*
G03X1687683Y38932I-43J398D01*
G02X1689098Y40974I1416J530D01*
G01X1694098D01*
G02X1695576Y39777I0J-1511D01*
G03X1696151Y39505I391J84D01*
G02X1697252Y39585I644J-1245D01*
G03X1697778Y39904I130J378D01*
G02X1699272Y41190I1494J-225D01*
G37*
G36*
G01X1679231Y37672D02*
G02X1677888Y38398I-1231J-672D01*
G03X1678231Y38936I-32J399D01*
G02X1679648Y40974I1417J526D01*
G01X1684649D01*
G02X1686160Y39472I-1J-1512D01*
G01Y39377D01*
X1686150Y39293D01*
G02X1684648Y37950I-1502J169D01*
G01X1679648D01*
G02X1679434Y37966I5J1512D01*
G03X1679231Y37672I-28J-198D01*
G37*
G36*
G01X1669327Y37479D02*
G02X1668331Y38365I-1318J-479D01*
G03X1668794Y38902I92J389D01*
G02X1670198Y40974I1404J560D01*
G01X1675199D01*
G02X1676710Y39472I-1J-1512D01*
G01Y39377D01*
X1676700Y39293D01*
G02X1675198Y37950I-1502J169D01*
G01X1670198D01*
G02X1669806Y38002I1J1512D01*
G03X1669327Y37479I-103J-386D01*
G37*
G36*
G01X1819357Y36830D02*
G02X1818427Y35215I443J-1330D01*
G03X1817892Y35507I-391J-81D01*
G02X1816377Y38051I-540J1402D01*
G03X1816342Y38687I-260J305D01*
G02X1818644Y40291I844J1242D01*
G03X1819332Y40123I388J97D01*
G02X1818999Y38766I1125J-995D01*
G03X1818311Y38934I-388J-97D01*
G02X1818161Y38787I-1124J996D01*
G03X1818196Y38151I260J-305D01*
G02X1818835Y37146I-844J-1242D01*
G03X1819357Y36830I395J63D01*
G37*
G36*
G01X738666Y34207D02*
G02X738242Y32074I5627J-2227D01*
G03X737592Y32393I-400J7D01*
G02X735728Y32491I-877J1094D01*
G03X735170Y32497I-282J-284D01*
G02X733209Y34500I-969J1013D01*
G03X733193Y35080I-283J282D01*
G02X733098Y37070I938J1042D01*
G03X733103Y37604I-295J270D01*
G02X735128Y39541I1052J927D01*
G03X735682I277J288D01*
G02X737688Y37583I973J-1010D01*
G03X737683Y37049I295J-270D01*
G02X737619Y35127I-1052J-927D01*
G03X737638Y34543I282J-283D01*
G02X737944Y34162I-924J-1055D01*
G03X738666Y34207I350J192D01*
G37*
G36*
G01X728183Y24221D02*
G02X728161Y22820I1317J-721D01*
G03X727459Y22841I-357J-181D01*
G02X727481Y24222I-1209J710D01*
G03X728183Y24221I351J191D01*
G37*
G36*
G01X669873Y22090D02*
G02Y24110I-973J1010D01*
G03X670427I277J288D01*
G02X670749Y24341I970J-1012D01*
G03X670624Y24716I-93J177D01*
G02X669733Y27333I-224J1384D01*
G03X669739Y28033I-191J352D01*
G02X671097Y28020I691J1220D01*
G03X671091Y27320I191J-352D01*
G02X671427Y25146I-691J-1220D01*
G03X671649Y24480I293J-272D01*
G02X672373Y24110I-249J-1380D01*
G03X672927I277J288D01*
G02Y22090I973J-1010D01*
G03X672373I-277J-288D01*
G02X670427I-973J1010D01*
G03X669873I-277J-288D01*
G37*
G36*
G01X1743152Y24708D02*
X1748153D01*
G02X1749664Y23207I0J-1512D01*
G01Y23112D01*
X1749654Y23028D01*
G02X1749652Y23011I-1502J168D01*
G03X1750025Y22562I397J-50D01*
G02X1748570Y21458I-85J-1399D01*
G03X1748349Y21698I-195J42D01*
G02X1748152Y21686I-190J1499D01*
G01X1743150D01*
G02X1742872Y21712I1J1511D01*
G03X1742399Y21292I-74J-393D01*
G02X1739644Y20843I-1399J-92D01*
G03X1739029Y21070I-387J-102D01*
G02X1738168Y20800I-862J1242D01*
G01X1733168D01*
G02X1732458Y20978I2J1512D01*
G03X1731889Y20743I-187J-353D01*
G02X1731147Y22428I-1339J416D01*
G03X1731705Y22690I170J362D01*
G02X1733168Y23824I1464J-378D01*
G01X1738169D01*
G02X1739644Y22636I-2J-1512D01*
G03X1740249Y22384I391J86D01*
G02X1741196Y22588I751J-1184D01*
G03X1741650Y23029I56J396D01*
G02X1743152Y24708I1502J168D01*
G37*
G36*
G01X1756976Y21518D02*
X1760677Y21556D01*
G02X1761198Y21470I18J-1511D01*
G03X1761724Y21770I134J377D01*
G02X1762142Y22523I1375J-271D01*
G03X1762181Y23065I-274J292D01*
G02X1763360Y25522I1179J945D01*
G01X1767069D01*
G02X1768580Y24020I-1J-1512D01*
G01Y23925D01*
X1768571Y23841D01*
G02X1768477Y23459I-1502J167D01*
G03X1768840Y22914I372J-145D01*
G02X1767481Y21969I-33J-1402D01*
G03X1767096Y22499I-378J130D01*
G02X1767069Y22498I-69J1509D01*
G01X1764800D01*
G03X1764422Y21966I-1J-400D01*
G02X1762492Y20237I-1322J-466D01*
G03X1762205Y20055I-87J-180D01*
G02Y20019I-1512J-18D01*
G01X1762204Y20017D01*
Y20007D01*
G02X1760709Y18534I-1511J38D01*
G01X1757009Y18496D01*
G02X1756976Y21518I-16J1511D01*
G37*
G36*
G01X702373Y18791D02*
G02X700053Y18562I-1253J828D01*
G03X699496Y18572I-284J-282D01*
G02X699537Y20726I-1026J1097D01*
G03X700094Y20716I284J282D01*
G02X702356Y20472I1026J-1097D01*
G03X703010Y20467I329J228D01*
G02X703027Y18810I1140J-817D01*
G03X702373Y18791I-320J-239D01*
G37*
G36*
G01X1847302Y13825D02*
G02X1846954Y12104I1020J-1102D01*
G03X1846330Y12243I-364J-165D01*
G02X1846673Y13939I-910J1067D01*
G03X1847302Y13825I357J180D01*
G37*
G36*
G01X1815276Y11914D02*
G02X1814690Y13372I-1481J252D01*
G03X1815320Y13613I238J321D01*
G02X1815897Y12177I1373J-282D01*
G03X1815276Y11914I-227J-330D01*
G37*
G36*
G01X1484135Y10052D02*
X1479135D01*
G02X1477630Y11703I0J1511D01*
G03X1477116Y12124I-398J38D01*
G02X1478112Y13391I-404J1342D01*
G03X1478642Y12992I399J-21D01*
G02X1479135Y13074I491J-1429D01*
G01X1484136D01*
G02X1484313Y13064I3J-1511D01*
G03X1484760Y13470I47J397D01*
G02X1486068Y12101I1402J30D01*
G03X1485643Y11673I-26J-399D01*
G02X1485646Y11573I-1508J-95D01*
G01Y11478D01*
X1485637Y11394D01*
G02X1484135Y10052I-1502J169D01*
G37*
G36*
G01X1465237D02*
X1460237D01*
G02X1458732Y11703I0J1511D01*
G03X1458218Y12124I-398J38D01*
G02X1459214Y13391I-404J1342D01*
G03X1459744Y12992I399J-21D01*
G02X1460237Y13074I491J-1429D01*
G01X1465238D01*
G02X1465416Y13064I4J-1511D01*
G03X1465863Y13477I47J397D01*
G02X1467168Y12134I1401J56D01*
G03X1466742Y11699I-28J-399D01*
G02X1466748Y11573I-1505J-135D01*
G01Y11478D01*
X1466739Y11394D01*
G02X1465237Y10052I-1502J169D01*
G37*
G36*
G01X1446340D02*
X1441340D01*
G02X1439842Y11758I1J1511D01*
G03X1439328Y12192I-397J52D01*
G02X1440314Y13405I-410J1341D01*
G03X1440844Y12991I398J-36D01*
G02X1441340Y13074I494J-1428D01*
G01X1446340D01*
G02X1446519Y13064I5J-1511D01*
G03X1446966Y13477I47J397D01*
G02X1448271Y12134I1401J56D01*
G03X1447845Y11699I-28J-399D01*
G02X1447852Y11573I-1504J-147D01*
G01Y11478D01*
X1447842Y11394D01*
G02X1446340Y10052I-1502J169D01*
G37*
G36*
G01X1427442D02*
X1422442D01*
G02X1420937Y11703I0J1511D01*
G03X1420423Y12124I-398J38D01*
G02X1418917Y12599I-405J1342D01*
G03X1418238Y12518I-315J-247D01*
G02X1415627Y12297I-1367J621D01*
G03X1414965I-331J-224D01*
G02X1412423Y12383I-1244J842D01*
G03X1411743Y12401I-346J-201D01*
G02X1409399Y12400I-1172J769D01*
G03X1408719Y12382I-334J-219D01*
G02X1408704Y13921I-1297J757D01*
G03X1409384Y13917I341J209D01*
G02X1411758Y13916I1187J-747D01*
G03X1412438Y13921I338J213D01*
G02X1414965Y13981I1283J-782D01*
G03X1415627I331J224D01*
G02X1418082Y14028I1244J-842D01*
G03X1418762Y14088I322J237D01*
G02X1421419Y13391I1257J-622D01*
G03X1421949Y12992I399J-21D01*
G02X1422442Y13074I491J-1429D01*
G01X1427443D01*
G02X1427620Y13064I3J-1511D01*
G03X1428067Y13462I47J397D01*
G02X1429377Y12067I1402J4D01*
G03X1428951Y11646I-27J-399D01*
G02X1428954Y11573I-1508J-99D01*
G01Y11478D01*
X1428944Y11394D01*
G02X1427442Y10052I-1502J169D01*
G37*
G36*
G01X1605898Y9844D02*
X1600898D01*
G02Y12866I0J1511D01*
G01X1605899D01*
G02X1606234Y12829I3J-1511D01*
G03X1606723Y13237I89J390D01*
G02X1607873Y11922I1401J64D01*
G03X1607403Y11493I-72J-393D01*
G02X1607410Y11365I-1504J-146D01*
G01Y11270D01*
X1607400Y11186D01*
G02X1605898Y9844I-1502J169D01*
G37*
G36*
G01X1719297Y9668D02*
X1714297D01*
G02X1712816Y11483I0J1512D01*
G03X1712300Y11944I-392J81D01*
G02X1711712Y11882I-438J1332D01*
G03X1711272Y11438I-43J-398D01*
G02X1711282Y11271I-1501J-174D01*
G01Y11176D01*
X1711273Y11092D01*
G02X1709771Y9750I-1502J169D01*
G01X1704771D01*
G02X1703270Y11439I0J1511D01*
G03X1702773Y11874I-397J48D01*
G02X1702176Y11851I-351J1357D01*
G03X1701707Y11427I-70J-394D01*
G02X1701712Y11327I-1506J-125D01*
G01Y11232D01*
X1701702Y11148D01*
G02X1700200Y9806I-1502J170D01*
G01X1695200D01*
G02Y12828I0J1511D01*
G01X1700201D01*
G02X1700532Y12792I3J-1511D01*
G03X1701020Y13193I88J390D01*
G02X1703819Y13122I1401J39D01*
G03X1704333Y12708I399J-31D01*
G02X1704771Y12772I435J-1447D01*
G01X1709772D01*
G02X1710004Y12754I-1J-1511D01*
G03X1710464Y13178I61J395D01*
G02X1713245Y13042I1399J98D01*
G03X1713777Y12599I394J-67D01*
G02X1714297Y12692I522J-1419D01*
G01X1719298D01*
G02X1719713Y12633I-3J-1512D01*
G03X1720208Y13125I110J385D01*
G02X1722949Y13316I1351J375D01*
G03X1723415Y12869I397J-53D01*
G02X1723677Y12892I263J-1488D01*
G01X1728681D01*
G02X1728906Y12875I-1J-1511D01*
G03X1729366Y13280I60J395D01*
G02X1730625Y11918I1402J33D01*
G03X1730186Y11491I-40J-398D01*
G02X1730190Y11391I-1508J-110D01*
G01Y11296D01*
X1730180Y11212D01*
G02X1728678Y9870I-1502J169D01*
G01X1723678D01*
G02X1722190Y11644I0J1511D01*
G03X1721743Y12110I-394J69D01*
G02X1721218Y12140I-184J1390D01*
G03X1720739Y11632I-97J-388D01*
G02X1720808Y11190I-1442J-452D01*
G01Y11095D01*
X1720799Y11011D01*
G02X1719297Y9668I-1502J169D01*
G37*
G36*
G01X1690948Y9214D02*
X1685948D01*
G02X1684677Y11543I0J1511D01*
G03X1684465Y12140I-336J217D01*
G02X1686144Y12822I437J1332D01*
G03X1686499Y12236I354J-186D01*
G01X1689838D01*
G03X1690216Y12767I0J400D01*
G02X1692338Y12073I1325J459D01*
G03X1692227Y11530I227J-329D01*
G02X1692460Y10735I-1279J-806D01*
G01Y10640D01*
X1692450Y10556D01*
G02X1690948Y9214I-1502J169D01*
G37*
G36*
G01X1666414Y12000D02*
G02X1665215Y11278I86J-1500D01*
G03X1664862Y11886I-342J208D01*
G02X1666043Y12596I-39J1401D01*
G03X1666414Y12000I348J-197D01*
G37*
G36*
G01X1833689Y11578D02*
G02X1831582Y9580I-789J-1278D01*
G03X1830948Y9671I-351J-192D01*
G02X1829091Y12008I-1060J1064D01*
G03X1829204Y12580I-212J339D01*
G02X1831214Y14496I1140J817D01*
G03X1831753Y14534I249J313D01*
G02X1833677Y12251I1089J-1034D01*
G03X1833689Y11578I222J-333D01*
G37*
G36*
G01X1842283Y10502D02*
G02X1842180Y8690I1143J-974D01*
G03X1841543Y8726I-332J-223D01*
G02X1839413Y8568I-1143J974D01*
G03X1838887I-263J-302D01*
G02Y10832I-987J1132D01*
G03X1839413I263J302D01*
G02X1841646Y10538I987J-1132D01*
G03X1842283Y10502I332J223D01*
G37*
G36*
G01X1619798Y12266D02*
X1624799D01*
G02X1625611Y12029I-1J-1511D01*
G03X1626197Y12219I214J338D01*
G02X1626805Y10483I1303J-518D01*
G03X1626228Y10265I-198J-347D01*
G02X1624799Y9244I-1430J490D01*
G01X1619795D01*
G02X1619054Y9439I2J1511D01*
G03X1618467Y9177I-197J-348D01*
G02X1615608Y10064I-1467J323D01*
G03X1615184Y10610I-371J150D01*
G02X1616315Y11515I-184J1390D01*
G03X1616756Y10982I375J-138D01*
G02X1617734Y10810I243J-1482D01*
G03X1618321Y11075I196J349D01*
G02X1619798Y12266I1477J-320D01*
G37*
G36*
G01X1743586Y9827D02*
G02X1743564Y8413I1314J-728D01*
G03X1742858Y8424I-356J-182D01*
G02X1742880Y9838I-1314J728D01*
G03X1743586Y9827I356J182D01*
G37*
G36*
G01X1805322Y10061D02*
G02X1803639Y10087I-861J-1231D01*
G03X1803662Y10740I-219J335D01*
G02X1805320Y10715I846J1118D01*
G03X1805322Y10061I231J-326D01*
G37*
G36*
G01X1799966Y10245D02*
G02X1798312Y9796I-504J-1415D01*
G03X1798154Y10425I-306J257D01*
G02X1799784Y10867I522J1301D01*
G03X1799966Y10245I316J-245D01*
G37*
G36*
G01X1586998Y9844D02*
X1581998D01*
G02X1580490Y11456I0J1511D01*
G03X1580020Y11877I-399J27D01*
G02X1579016Y12077I-247J1380D01*
G03X1578433Y11901I-217J-336D01*
G02X1577048Y10994I-1385J605D01*
G01X1573048D01*
G02X1571739Y11750I0J1512D01*
G03X1571128Y11849I-346J-200D01*
G02X1569347Y11787I-928J1051D01*
G03X1568768Y11686I-243J-318D01*
G02X1567498Y10994I-1270J820D01*
G01X1563498D01*
G02X1562172Y11781I1J1512D01*
G03X1561572Y11902I-351J-192D01*
G02X1560031Y11768I-872J1098D01*
G03X1559486Y11603I-191J-351D01*
G02X1558148Y10794I-1338J703D01*
G01X1554148D01*
G02X1552815Y11595I1J1512D01*
G03X1552206Y11714I-353J-188D01*
G02X1550464Y11673I-897J1078D01*
G03X1549904Y11595I-241J-319D01*
G02X1548698Y10994I-1207J911D01*
G01X1544698D01*
G02X1543347Y11829I1J1512D01*
G03X1542636Y11839I-358J-179D01*
G02X1540503Y11422I-1236J661D01*
G03X1539884Y11282I-256J-307D01*
G02X1539528Y13025I-1364J629D01*
G03X1540152Y13139I268J296D01*
G02X1542634Y13166I1248J-639D01*
G03X1543344Y13178I352J190D01*
G02X1544698Y14018I1354J-672D01*
G01X1548699D01*
G02X1549678Y13657I-1J-1512D01*
G03X1550242Y13702I260J304D01*
G02X1552513Y13510I1067J-910D01*
G03X1553127Y13420I344J205D01*
G02X1554148Y13818I1022J-1114D01*
G01X1558148D01*
G02X1558945Y13590I-1J-1512D01*
G03X1559499Y13723I211J340D01*
G02X1561895Y13733I1201J-723D01*
G03X1562500Y13641I341J209D01*
G02X1563498Y14018I999J-1135D01*
G01X1567499D01*
G02X1568481Y13654I-2J-1512D01*
G03X1569065Y13723I260J304D01*
G02X1571379Y13659I1135J-823D01*
G03X1571994Y13589I336J217D01*
G02X1573048Y14018I1055J-1083D01*
G01X1577049D01*
G02X1577927Y13735I-3J-1511D01*
G03X1578518Y13882I233J325D01*
G02X1581175Y13227I1255J-625D01*
G03X1581663Y12829I400J-8D01*
G02X1581998Y12866I332J-1474D01*
G01X1586999D01*
G02X1588425Y11853I-1J-1511D01*
G03X1588904Y11597I378J131D01*
G02X1589834Y11520I356J-1356D01*
G03X1590385Y11785I164J365D01*
G02X1591848Y12918I1463J-379D01*
G01X1595849D01*
G02X1597360Y11416I-1J-1512D01*
G01Y11321D01*
X1597350Y11237D01*
G02X1597282Y10928I-1502J169D01*
G03X1597670Y10402I379J-126D01*
G02X1596353Y9388I30J-1402D01*
G03X1595943Y9897I-384J110D01*
G02X1595848Y9894I-95J1509D01*
G01X1594075D01*
G03X1593734Y9286I0J-400D01*
G02X1591289Y9451I-1281J-784D01*
G03X1591161Y10060I-310J253D01*
G02X1590963Y10181I687J1346D01*
G03X1590647Y10047I-118J-162D01*
G02X1587967Y9696I-1388J194D01*
G03X1587473Y9920I-368J-156D01*
G02X1586998Y9844I-473J1435D01*
G37*
G36*
G01X1786579Y7214D02*
G02X1784448Y9289I-1213J886D01*
G03X1784516Y9855I-245J316D01*
G02X1786527Y9667I1096J874D01*
G03X1786489Y9098I261J-303D01*
G02X1786566Y9004I-1123J-998D01*
G03X1787208Y9008I320J240D01*
G02X1787221Y7218I1213J-886D01*
G03X1786579Y7214I-320J-240D01*
G37*
G36*
G01X1629148Y8336D02*
X1632677D01*
G03X1633015Y8950I0J400D01*
G02X1635094Y8620I1185J750D01*
G03X1635098Y8001I255J-308D01*
G02X1635660Y6835I-950J-1176D01*
G01Y6740D01*
X1635650Y6656D01*
G02X1635608Y6433I-1502J167D01*
G03X1636106Y5946I386J-103D01*
G02X1635135Y4918I395J-1345D01*
G03X1634620Y5389I-390J91D01*
G02X1634148Y5314I-470J1436D01*
G01X1629148D01*
G02Y8336I0J1511D01*
G37*
G36*
G01X1609833Y6936D02*
X1614834D01*
G02X1616344Y5435I-1J-1511D01*
G01Y5340D01*
X1616335Y5256D01*
G02X1614833Y3914I-1502J169D01*
G01X1609833D01*
G02X1608729Y4393I0J1511D01*
G03X1608051Y4226I-292J-273D01*
G02X1607692Y5591I-1351J374D01*
G03X1608364Y5780I283J282D01*
G02X1609833Y6936I1469J-355D01*
G37*
G36*
G01X1525906Y2483D02*
G02Y4517I-1106J1017D01*
G03X1526494I294J270D01*
G02X1528864Y4312I1106J-1017D01*
G03X1529536I336J216D01*
G02X1532064I1264J-812D01*
G03X1532736I336J216D01*
G02Y2688I1264J-812D01*
G03X1532064I-336J-216D01*
G02X1529536I-1264J812D01*
G03X1528864I-336J-216D01*
G02X1526494Y2483I-1264J812D01*
G03X1525906I-294J-270D01*
G37*
G36*
G01X1510387Y2368D02*
G02X1508354Y2422I-987J1132D01*
G03X1507815Y2438I-278J-287D01*
G02Y4562I-915J1062D01*
G03X1508354Y4578I261J303D01*
G02X1510387Y4632I1046J-1078D01*
G03X1510913I263J302D01*
G02X1512887I987J-1132D01*
G03X1513413I263J302D01*
G02X1515387I987J-1132D01*
G03X1515913I263J302D01*
G02X1518164Y4312I987J-1132D01*
G03X1518836I336J216D01*
G02Y2688I1264J-812D01*
G03X1518164I-336J-216D01*
G02X1515913Y2368I-1264J812D01*
G03X1515387I-263J-302D01*
G02X1513413I-987J1132D01*
G03X1512887I-263J-302D01*
G02X1510913I-987J1132D01*
G03X1510387I-263J-302D01*
G37*
G36*
G01X1544803Y2653D02*
G02Y4147I-1303J747D01*
G03X1545497I347J199D01*
G02X1547985Y4323I1303J-747D01*
G03X1548615I315J246D01*
G02X1550787Y4532I1185J-923D01*
G03X1551313I263J302D01*
G02X1553287I987J-1132D01*
G03X1553813I263J302D01*
G02X1556064Y4212I987J-1132D01*
G03X1556736I336J216D01*
G02X1558987Y4532I1264J-812D01*
G03X1559513I263J302D01*
G02X1561566Y4458I987J-1132D01*
G03X1562134I284J282D01*
G02X1564306Y4417I1066J-1058D01*
G03X1564894I294J270D01*
G02X1567185Y4323I1106J-1017D01*
G03X1567815I315J246D01*
G02Y2477I1185J-923D01*
G03X1567185I-315J-246D01*
G02X1564894Y2383I-1185J923D01*
G03X1564306I-294J-270D01*
G02X1562134Y2342I-1106J1017D01*
G03X1561566I-284J-282D01*
G02X1559513Y2268I-1066J1058D01*
G03X1558987I-263J-302D01*
G02X1556736Y2588I-987J1132D01*
G03X1556064I-336J-216D01*
G02X1553813Y2268I-1264J812D01*
G03X1553287I-263J-302D01*
G02X1551313I-987J1132D01*
G03X1550787I-263J-302D01*
G02X1548615Y2477I-987J1132D01*
G03X1547985I-315J-246D01*
G02X1545497Y2653I-1185J923D01*
G03X1544803I-347J-199D01*
G37*
G36*
G01X1681260Y1995D02*
G02X1681237Y3762I-1226J868D01*
G03X1681875Y3757I321J239D01*
G02X1683924Y3942I1110J-856D01*
G03X1684482Y3964I268J297D01*
G02X1686415Y4062I1018J-964D01*
G03X1686954Y4078I261J303D01*
G02X1689133Y3986I1046J-1078D01*
G03X1689748Y3999I302J262D01*
G02Y2001I1252J-999D01*
G03X1689133Y2014I-313J-249D01*
G02X1686954Y1922I-1133J986D01*
G03X1686415Y1938I-278J-287D01*
G02X1684561Y1959I-915J1062D01*
G03X1684003Y1937I-268J-297D01*
G02X1681897Y2017I-1018J964D01*
G03X1681260Y1995I-310J-253D01*
G37*
G36*
G01X1498634Y-11183D02*
G02X1497339Y-12326I166J-1493D01*
G03X1496892Y-11837I-389J93D01*
G02X1498204Y-10679I-232J1585D01*
G03X1498634Y-11183I385J-107D01*
G37*
G36*
G01X1674935Y-17561D02*
G02X1674904Y-16078I-1435J712D01*
G03X1675602Y-16084I351J193D01*
G02X1675632Y-17526I1217J-696D01*
G03X1674935Y-17561I-339J-213D01*
G37*
G36*
G01X689350Y410810D02*
G03X688784Y410617I-197J-348D01*
G02X688201Y412470I-1384J583D01*
G03X688776Y412636I214J338D01*
G02X689350Y410810I1264J-606D01*
G37*
G36*
G01X705251Y415224D02*
G02X704037Y416342I-1375J-275D01*
G03X704475Y416818I46J397D01*
G02X706140Y418465I1375J275D01*
G03X706620Y418905I83J391D01*
G02X708660Y420321I1391J173D01*
G03X709234Y420585I185J355D01*
G02X711673Y421169I1366J-318D01*
G03X712315Y421210I306J258D01*
G02X714245Y419266I1178J-761D01*
G03X714131Y418700I215J-338D01*
G02X712163Y416760I-1151J-800D01*
G03X711596Y416655I-233J-325D01*
G02X710199Y416039I-1173J768D01*
G03X709738Y415692I-64J-395D01*
G02X706981Y415541I-1392J167D01*
G03X706426Y415815I-390J-91D01*
G02X705689Y415700I-577J1278D01*
G03X705251Y415224I-46J-397D01*
G37*
G36*
G01X776892Y377686D02*
G03X776286Y377668I-295J-270D01*
G02X774019Y379637I-1164J949D01*
G03X774032Y380166I-293J272D01*
G02X774050Y382120I1150J966D01*
G03Y382646I-302J263D01*
G02X776314I1132J987D01*
G03Y382120I302J-263D01*
G02X776284Y380112I-1132J-987D01*
G03X776271Y379583I293J-272D01*
G02X776368Y379453I-1154J-962D01*
G03X776706Y379463I166J112D01*
G02X776892Y377686I1294J-763D01*
G37*
G36*
G01X778810Y371129D02*
G03X778193Y371122I-306J-258D01*
G02X778172Y372904I-1093J878D01*
G03X778789Y372911I306J258D01*
G02X778810Y371129I1093J-878D01*
G37*
G36*
G01X771160Y372542D02*
G03X770929Y373080I-366J161D01*
G02X772683Y373834I472J1320D01*
G03X772914Y373296I366J-161D01*
G02X771160Y372542I-472J-1320D01*
G37*
G36*
G01X767955Y352504D02*
G03X768121Y351953I349J-195D01*
G02X766254Y351393I-644J-1245D01*
G03X766088Y351944I-349J195D01*
G02X767955Y352504I644J1245D01*
G37*
G36*
G01X776250Y347661D02*
G03X776535Y347659I143J139D01*
G02X776633Y345450I1065J-1059D01*
G03X776122Y345454I-258J-306D01*
G02X774069Y347637I-951J1163D01*
G03X774082Y348166I-293J272D01*
G02X774100Y350120I1150J966D01*
G03Y350646I-302J263D01*
G02X776364I1132J987D01*
G03Y350120I302J-263D01*
G02X776216Y347998I-1132J-987D01*
G03X776208Y347702I131J-152D01*
G02X776250Y347661I-1028J-1095D01*
G37*
G36*
G01X776797Y313582D02*
G03X776244Y313565I-268J-297D01*
G02X774069Y315637I-1073J1051D01*
G03X774082Y316166I-293J272D01*
G02X774100Y318120I1150J966D01*
G03Y318646I-302J263D01*
G02X776364I1132J987D01*
G03Y318120I302J-263D01*
G02X776216Y315998I-1132J-987D01*
G03X776208Y315702I131J-152D01*
G02X776301Y315606I-1031J-1092D01*
G03X776610Y315616I150J132D01*
G02X776797Y313582I1190J-916D01*
G37*
G36*
G01X772396Y309446D02*
G03X772325Y308851I227J-329D01*
G02X770482Y309072I-1047J-933D01*
G03X770553Y309667I-227J329D01*
G02X772396Y309446I1047J933D01*
G37*
G36*
G01X776293Y283614D02*
G03X776590Y283612I149J133D01*
G02X776694Y281484I1110J-1012D01*
G03X776162Y281488I-268J-297D01*
G02X774069Y283637I-991J1129D01*
G03X774082Y284166I-293J272D01*
G02X774100Y286120I1150J966D01*
G03Y286646I-302J263D01*
G02X776364I1132J987D01*
G03Y286120I302J-263D01*
G02X776216Y283998I-1132J-987D01*
G03X776208Y283702I131J-152D01*
G02X776293Y283614I-1037J-1086D01*
G37*
G36*
G01X746896Y281538D02*
G02X752004Y280262I2904J762D01*
G02X746896Y281538I-2904J-762D01*
G37*
G36*
G01X778572Y275068D02*
G03X777973Y274913I-236J-323D01*
G02X777528Y276632I-1273J588D01*
G03X778127Y276787I236J323D01*
G02X778572Y275068I1273J-588D01*
G37*
G36*
G01X752199Y274925D02*
G02X757405Y274771I2647J1415D01*
G02X752199Y274925I-2647J-1415D01*
G37*
G36*
G01X746387Y268945D02*
G02X751693Y268755I2703J1305D01*
G02X746387Y268945I-2703J-1305D01*
G37*
G36*
G01X752813Y251578D02*
G02X750240Y251423I-1450J2629D01*
G02X746261Y255750I-1540J2577D01*
G02X751686Y257192I2439J1750D01*
G02X752813Y256836I-323J-2985D01*
G02Y251578I1450J-2629D01*
G37*
G36*
G01X766693Y253259D02*
G03X766354Y252751I45J-397D01*
G02X764846Y253756I-1347J-388D01*
G03X765185Y254264I-45J397D01*
G02X765602Y255701I1347J388D01*
G03X765624Y256278I-266J299D01*
G02X767562Y256203I1008J974D01*
G03X767540Y255626I266J-299D01*
G02X766693Y253259I-1008J-974D01*
G37*
G36*
G01X776293Y251614D02*
G03X776590Y251612I149J133D01*
G02X776694Y249484I1110J-1012D01*
G03X776162Y249488I-268J-297D01*
G02X774069Y251637I-991J1129D01*
G03X774082Y252166I-293J272D01*
G02X774100Y254120I1150J966D01*
G03Y254646I-302J263D01*
G02X776364I1132J987D01*
G03Y254120I302J-263D01*
G02X776216Y251998I-1132J-987D01*
G03X776208Y251702I131J-152D01*
G02X776293Y251614I-1037J-1086D01*
G37*
G36*
G01X747300Y242136D02*
G03X747304Y241569I284J-282D01*
G02X745324Y241555I-983J-1000D01*
G03X745320Y242122I-284J282D01*
G02X747300Y242136I983J1000D01*
G37*
G36*
G01X767662Y224140D02*
G03X767640Y223563I266J-299D01*
G02X765702Y223638I-1008J-974D01*
G03X765724Y224215I-266J299D01*
G02X767662Y224140I1008J974D01*
G37*
G36*
G01X776293Y219614D02*
G03X776590Y219612I149J133D01*
G02X776694Y217484I1110J-1012D01*
G03X776162Y217488I-268J-297D01*
G02X774069Y219637I-991J1129D01*
G03X774082Y220166I-293J272D01*
G02X774100Y222120I1150J966D01*
G03Y222646I-302J263D01*
G02X776364I1132J987D01*
G03Y222120I302J-263D01*
G02X776216Y219998I-1132J-987D01*
G03X776208Y219702I131J-152D01*
G02X776293Y219614I-1037J-1086D01*
G37*
G36*
G01X707632Y216413D02*
G03Y215887I302J-263D01*
G02X705368I-1132J-987D01*
G03Y216413I-302J263D01*
G02X705398Y218421I1132J987D01*
G03X705411Y218950I-293J272D01*
G02X707663Y218896I1150J967D01*
G03X707650Y218367I293J-272D01*
G02X707632Y216413I-1150J-966D01*
G37*
G36*
G01X766290Y380798D02*
G02X764936Y381765I-1333J-435D01*
G03X765310Y382289I-6J400D01*
G02X766009Y383974I1333J435D01*
G03X766122Y384602I-181J357D01*
G02X767789Y384300I1033J948D01*
G03X767676Y383672I181J-357D01*
G02X766664Y381322I-1033J-948D01*
G03X766290Y380798I6J-400D01*
G37*
G36*
G01X764923Y374919D02*
G02X763374Y374904I-763J-1176D01*
G03X763367Y375571I-224J331D01*
G02X764916Y375586I763J1176D01*
G03X764923Y374919I224J-331D01*
G37*
G36*
G01X761107Y361064D02*
G02X759612Y360885I-607J-1264D01*
G03X759533Y361555I-253J310D01*
G02X761028Y361734I607J1264D01*
G03X761107Y361064I253J-310D01*
G37*
G36*
G01X775465Y339137D02*
G02X775435Y340868I-1118J846D01*
G03X776064Y340879I310J252D01*
G02X778252Y340939I1118J-846D01*
G03X778862I305J259D01*
G02Y339127I1070J-906D01*
G03X778252I-305J-259D01*
G02X776094Y339148I-1070J906D01*
G03X775465Y339137I-310J-252D01*
G37*
G36*
G01X764141Y339743D02*
G02X763234Y340819I-1381J-244D01*
G03X763763Y341265I135J377D01*
G02X764359Y342669I1381J242D01*
G03X764352Y343336I-224J331D01*
G02X765901Y343351I763J1176D01*
G03X765908Y342684I224J-331D01*
G02X764670Y340189I-764J-1176D01*
G03X764141Y339743I-135J-377D01*
G37*
G36*
G01X766382Y316635D02*
G02X765182Y317754I-1375J-272D01*
G03X765625Y318228I50J397D01*
G02X765973Y319454I1375J272D01*
G03X765913Y320051I-293J272D01*
G02X767759Y320235I819J1138D01*
G03X767819Y319638I293J-272D01*
G02X766825Y317109I-819J-1138D01*
G03X766382Y316635I-50J-397D01*
G37*
G36*
G01X765908Y310684D02*
G02X764359Y310669I-763J-1176D01*
G03X764352Y311336I-224J331D01*
G02X765901Y311351I763J1176D01*
G03X765908Y310684I224J-331D01*
G37*
G36*
G01X777591Y306631D02*
G02X777150Y308191I-1321J469D01*
G03X777779Y308369I252J311D01*
G02X778220Y306809I1321J-469D01*
G03X777591Y306631I-252J-311D01*
G37*
G36*
G01X766364Y284716D02*
G02X765442Y285696I-1357J-353D01*
G03X765953Y286177I124J380D01*
G02X765923Y286323I1357J355D01*
G03X765406Y286644I-395J-60D01*
G02X766367Y288187I-426J1336D01*
G03X766884Y287866I395J60D01*
G02X766875Y285197I426J-1336D01*
G03X766364Y284716I-124J-380D01*
G37*
G36*
G01X765908Y278684D02*
G02X764359Y278669I-763J-1176D01*
G03X764352Y279336I-224J331D01*
G02X765901Y279351I763J1176D01*
G03X765908Y278684I224J-331D01*
G37*
G36*
G01Y246684D02*
G02X764359Y246669I-763J-1176D01*
G03X764352Y247336I-224J331D01*
G02X765901Y247351I763J1176D01*
G03X765908Y246684I224J-331D01*
G37*
G36*
G01X778282Y242932D02*
G02X778000Y244483I-1282J568D01*
G03X778650Y244601I285J281D01*
G02X778932Y243050I1282J-568D01*
G03X778282Y242932I-285J-281D01*
G37*
G36*
G01X765908Y214684D02*
G02X764359Y214669I-763J-1176D01*
G03X764352Y215336I-224J331D01*
G02X765901Y215351I763J1176D01*
G03X765908Y214684I224J-331D01*
G37*
G36*
G01X1313449Y618405D02*
G03X1312903I-273J-292D01*
G02Y620597I-1027J1096D01*
G03X1313449I273J292D01*
G02Y618405I1027J-1096D01*
G37*
G36*
G01X713416Y616500D02*
G03X712996Y616137I-22J-399D01*
G02X711584Y617774I-1496J137D01*
G03X712004Y618137I22J399D01*
G02X713416Y616500I1496J-137D01*
G37*
G36*
G01X1225841Y606267D02*
G03X1225825Y605706I277J-289D01*
G02X1223775I-1025J-956D01*
G03X1223759Y606267I-293J272D01*
G02X1223712Y608385I1041J1083D01*
G03X1223706Y608942I-290J275D01*
G02X1223733Y611082I1068J1057D01*
G03X1223749Y611643I-277J289D01*
G02X1225799I1025J956D01*
G03X1225815Y611082I293J-272D01*
G02X1225862Y608964I-1041J-1083D01*
G03X1225868Y608407I290J-275D01*
G02X1225841Y606267I-1068J-1057D01*
G37*
G36*
G01X1189030D02*
G03X1189014Y605706I277J-289D01*
G02X1186964I-1025J-956D01*
G03X1186948Y606267I-293J272D01*
G02X1186901Y608385I1041J1083D01*
G03X1186895Y608942I-290J275D01*
G02X1186922Y611082I1068J1057D01*
G03X1186938Y611643I-277J289D01*
G02X1188988I1025J956D01*
G03X1189004Y611082I293J-272D01*
G02X1189051Y608964I-1041J-1083D01*
G03X1189057Y608407I290J-275D01*
G02X1189030Y606267I-1068J-1057D01*
G37*
G36*
G01X1152219D02*
G03X1152203Y605706I277J-289D01*
G02X1150153I-1025J-956D01*
G03X1150137Y606267I-293J272D01*
G02X1150090Y608385I1041J1083D01*
G03X1150084Y608942I-290J275D01*
G02X1150111Y611082I1068J1057D01*
G03X1150127Y611643I-277J289D01*
G02X1152177I1025J956D01*
G03X1152193Y611082I293J-272D01*
G02X1152240Y608964I-1041J-1083D01*
G03X1152246Y608407I290J-275D01*
G02X1152219Y606267I-1068J-1057D01*
G37*
G36*
G01X1115407D02*
G03X1115391Y605706I277J-289D01*
G02X1113341I-1025J-956D01*
G03X1113325Y606267I-293J272D01*
G02X1113278Y608385I1041J1083D01*
G03X1113272Y608942I-290J275D01*
G02X1113299Y611082I1068J1057D01*
G03X1113315Y611643I-277J289D01*
G02X1115365I1025J956D01*
G03X1115381Y611082I293J-272D01*
G02X1115428Y608964I-1041J-1083D01*
G03X1115434Y608407I290J-275D01*
G02X1115407Y606267I-1068J-1057D01*
G37*
G36*
G01X934699D02*
G03X934683Y605706I277J-289D01*
G02X932633I-1025J-956D01*
G03X932617Y606267I-293J272D01*
G02X932570Y608385I1041J1083D01*
G03X932564Y608942I-290J275D01*
G02X932591Y611082I1068J1057D01*
G03X932607Y611643I-277J289D01*
G02X934657I1025J956D01*
G03X934673Y611082I293J-272D01*
G02X934720Y608964I-1041J-1083D01*
G03X934726Y608407I290J-275D01*
G02X934699Y606267I-1068J-1057D01*
G37*
G36*
G01X897888D02*
G03X897872Y605706I277J-289D01*
G02X895822I-1025J-956D01*
G03X895806Y606267I-293J272D01*
G02X895759Y608385I1041J1083D01*
G03X895753Y608942I-290J275D01*
G02X895780Y611082I1068J1057D01*
G03X895796Y611643I-277J289D01*
G02X897846I1025J956D01*
G03X897862Y611082I293J-272D01*
G02X897909Y608964I-1041J-1083D01*
G03X897915Y608407I290J-275D01*
G02X897888Y606267I-1068J-1057D01*
G37*
G36*
G01X861077D02*
G03X861061Y605706I277J-289D01*
G02X859011I-1025J-956D01*
G03X858995Y606267I-293J272D01*
G02X858948Y608385I1041J1083D01*
G03X858942Y608942I-290J275D01*
G02X858969Y611082I1068J1057D01*
G03X858985Y611643I-277J289D01*
G02X861035I1025J956D01*
G03X861051Y611082I293J-272D01*
G02X861098Y608964I-1041J-1083D01*
G03X861104Y608407I290J-275D01*
G02X861077Y606267I-1068J-1057D01*
G37*
G36*
G01X824266D02*
G03X824250Y605706I277J-289D01*
G02X822200I-1025J-956D01*
G03X822184Y606267I-293J272D01*
G02X822137Y608385I1041J1083D01*
G03X822131Y608942I-290J275D01*
G02X822158Y611082I1068J1057D01*
G03X822174Y611643I-277J289D01*
G02X824224I1025J956D01*
G03X824240Y611082I293J-272D01*
G02X824287Y608964I-1041J-1083D01*
G03X824293Y608407I290J-275D01*
G02X824266Y606267I-1068J-1057D01*
G37*
G36*
G01X787455D02*
G03X787439Y605706I277J-289D01*
G02X785389I-1025J-956D01*
G03X785373Y606267I-293J272D01*
G02X785326Y608385I1041J1083D01*
G03X785320Y608942I-290J275D01*
G02X785347Y611082I1068J1057D01*
G03X785363Y611643I-277J289D01*
G02X787413I1025J956D01*
G03X787429Y611082I293J-272D01*
G02X787476Y608964I-1041J-1083D01*
G03X787482Y608407I290J-275D01*
G02X787455Y606267I-1068J-1057D01*
G37*
G36*
G01X1230919Y606061D02*
G03X1230906Y605499I278J-288D01*
G02X1228858Y605489I-1019J-963D01*
G03X1228840Y606050I-293J271D01*
G02X1228781Y608170I1034J1090D01*
G03Y608719I-291J274D01*
G02X1228844Y610843I1093J1031D01*
G03X1228865Y611404I-274J291D01*
G02X1230915Y611383I1035J946D01*
G03X1230925Y610822I290J-275D01*
G02X1230967Y608719I-1051J-1073D01*
G03Y608170I291J-274D01*
G02X1230919Y606061I-1093J-1030D01*
G37*
G36*
G01X1194108D02*
G03X1194095Y605499I278J-288D01*
G02X1192047Y605489I-1019J-963D01*
G03X1192029Y606050I-293J271D01*
G02X1191970Y608170I1034J1090D01*
G03Y608719I-291J274D01*
G02X1192033Y610843I1093J1031D01*
G03X1192054Y611404I-274J291D01*
G02X1194104Y611383I1035J946D01*
G03X1194114Y610822I290J-275D01*
G02X1194156Y608719I-1051J-1073D01*
G03Y608170I291J-274D01*
G02X1194108Y606061I-1093J-1030D01*
G37*
G36*
G01X1157297D02*
G03X1157284Y605499I278J-288D01*
G02X1155236Y605489I-1019J-963D01*
G03X1155218Y606050I-293J271D01*
G02X1155159Y608170I1034J1090D01*
G03Y608719I-291J274D01*
G02X1155222Y610843I1093J1031D01*
G03X1155243Y611404I-274J291D01*
G02X1157293Y611383I1035J946D01*
G03X1157303Y610822I290J-275D01*
G02X1157345Y608719I-1051J-1073D01*
G03Y608170I291J-274D01*
G02X1157297Y606061I-1093J-1030D01*
G37*
G36*
G01X1120485D02*
G03X1120472Y605499I278J-288D01*
G02X1118424Y605489I-1019J-963D01*
G03X1118406Y606050I-293J271D01*
G02X1118347Y608170I1034J1090D01*
G03Y608719I-291J274D01*
G02X1118410Y610843I1093J1031D01*
G03X1118431Y611404I-274J291D01*
G02X1120481Y611383I1035J946D01*
G03X1120491Y610822I290J-275D01*
G02X1120533Y608719I-1051J-1073D01*
G03Y608170I291J-274D01*
G02X1120485Y606061I-1093J-1030D01*
G37*
G36*
G01X939777D02*
G03X939764Y605499I278J-288D01*
G02X937716Y605489I-1019J-963D01*
G03X937698Y606050I-293J271D01*
G02X937639Y608170I1034J1090D01*
G03Y608719I-291J274D01*
G02X937702Y610843I1093J1031D01*
G03X937723Y611404I-274J291D01*
G02X939773Y611383I1035J946D01*
G03X939783Y610822I290J-275D01*
G02X939825Y608719I-1051J-1073D01*
G03Y608170I291J-274D01*
G02X939777Y606061I-1093J-1030D01*
G37*
G36*
G01X902966D02*
G03X902953Y605499I278J-288D01*
G02X900905Y605489I-1019J-963D01*
G03X900887Y606050I-293J271D01*
G02X900828Y608170I1034J1090D01*
G03Y608719I-291J274D01*
G02X900891Y610843I1093J1031D01*
G03X900912Y611404I-274J291D01*
G02X902962Y611383I1035J946D01*
G03X902972Y610822I290J-275D01*
G02X903014Y608719I-1051J-1073D01*
G03Y608170I291J-274D01*
G02X902966Y606061I-1093J-1030D01*
G37*
G36*
G01X866155D02*
G03X866142Y605499I278J-288D01*
G02X864094Y605489I-1019J-963D01*
G03X864076Y606050I-293J271D01*
G02X864017Y608170I1034J1090D01*
G03Y608719I-291J274D01*
G02X864080Y610843I1093J1031D01*
G03X864101Y611404I-274J291D01*
G02X866151Y611383I1035J946D01*
G03X866161Y610822I290J-275D01*
G02X866203Y608719I-1051J-1073D01*
G03Y608170I291J-274D01*
G02X866155Y606061I-1093J-1030D01*
G37*
G36*
G01X829344D02*
G03X829331Y605499I278J-288D01*
G02X827283Y605489I-1019J-963D01*
G03X827265Y606050I-293J271D01*
G02X827206Y608170I1034J1090D01*
G03Y608719I-291J274D01*
G02X827269Y610843I1093J1031D01*
G03X827290Y611404I-274J291D01*
G02X829340Y611383I1035J946D01*
G03X829350Y610822I290J-275D01*
G02X829392Y608719I-1051J-1073D01*
G03Y608170I291J-274D01*
G02X829344Y606061I-1093J-1030D01*
G37*
G36*
G01X792533D02*
G03X792520Y605499I278J-288D01*
G02X790472Y605489I-1019J-963D01*
G03X790454Y606050I-293J271D01*
G02X790395Y608170I1034J1090D01*
G03Y608719I-291J274D01*
G02X790458Y610843I1093J1031D01*
G03X790479Y611404I-274J291D01*
G02X792529Y611383I1035J946D01*
G03X792539Y610822I290J-275D01*
G02X792581Y608719I-1051J-1073D01*
G03Y608170I291J-274D01*
G02X792533Y606061I-1093J-1030D01*
G37*
G36*
G01X711010Y605077D02*
G03Y605623I-292J273D01*
G02X711582Y608058I1096J1027D01*
G03X711798Y608616I-139J375D01*
G02X714386Y610133I1334J690D01*
G03X715012Y610079I334J220D01*
G02X714852Y608223I1094J-1029D01*
G03X714226Y608277I-334J-220D01*
G02X713656Y607898I-1095J1028D01*
G03X713440Y607340I139J-375D01*
G02X713202Y605623I-1334J-690D01*
G03Y605077I292J-273D01*
G02X711010I-1096J-1027D01*
G37*
G36*
G01X1299110Y597327D02*
G03Y596773I288J-277D01*
G02X1297090I-1010J-973D01*
G03Y597327I-288J277D01*
G02X1299110I1010J973D01*
G37*
G36*
G01X1021954Y592663D02*
G03X1021382Y592659I-284J-282D01*
G02X1021421Y594700I-1082J1042D01*
G03X1021992Y594674I298J266D01*
G02X1023923Y594660I958J-1024D01*
G03X1024477I277J288D01*
G02Y592640I973J-1010D01*
G03X1023923I-277J-288D01*
G02X1021954Y592663I-973J1010D01*
G37*
G36*
G01X754907Y592660D02*
G03X754330Y592649I-283J-282D01*
G02X754293Y594590I-1030J951D01*
G03X754870Y594601I283J282D01*
G02X754907Y592660I1030J-951D01*
G37*
G36*
G01X765634Y591716D02*
G03X765606Y592320I-276J290D01*
G02X767518Y592364I929J1180D01*
G03Y591760I262J-302D01*
G02X765634Y591716I-918J-1060D01*
G37*
G36*
G01X1299110Y591527D02*
G03Y590973I288J-277D01*
G02X1297090I-1010J-973D01*
G03Y591527I-288J277D01*
G02X1299110I1010J973D01*
G37*
G36*
G01X1246064Y590417D02*
G03X1246078Y589834I281J-285D01*
G02X1244078I-1000J-1120D01*
G03X1244092Y590417I-267J298D01*
G02X1246064I986J997D01*
G37*
G36*
G01X1239371D02*
G03X1239385Y589834I281J-285D01*
G02X1237385I-1000J-1120D01*
G03X1237399Y590417I-267J298D01*
G02X1239371I986J997D01*
G37*
G36*
G01X1221939D02*
G03X1221953Y589834I281J-285D01*
G02X1219953I-1000J-1120D01*
G03X1219967Y590417I-267J298D01*
G02X1221939I986J997D01*
G37*
G36*
G01X1209253D02*
G03X1209267Y589834I281J-285D01*
G02X1207267I-1000J-1120D01*
G03X1207281Y590417I-267J298D01*
G02X1209253I986J997D01*
G37*
G36*
G01X1202560D02*
G03X1202574Y589834I281J-285D01*
G02X1200574I-1000J-1120D01*
G03X1200588Y590417I-267J298D01*
G02X1202560I986J997D01*
G37*
G36*
G01X1185128D02*
G03X1185142Y589834I281J-285D01*
G02X1183142I-1000J-1120D01*
G03X1183156Y590417I-267J298D01*
G02X1185128I986J997D01*
G37*
G36*
G01X1178842Y590378D02*
G03X1178869Y589817I298J-267D01*
G02X1176788Y589777I-1020J-1103D01*
G03X1176792Y590338I-283J283D01*
G02X1178842Y590378I1006J976D01*
G37*
G36*
G01X1172442Y590417D02*
G03X1172456Y589834I281J-285D01*
G02X1170456I-1000J-1120D01*
G03X1170470Y590417I-267J298D01*
G02X1172442I986J997D01*
G37*
G36*
G01X1165749D02*
G03X1165763Y589834I281J-285D01*
G02X1163763I-1000J-1120D01*
G03X1163777Y590417I-267J298D01*
G02X1165749I986J997D01*
G37*
G36*
G01X1148317D02*
G03X1148331Y589834I281J-285D01*
G02X1146331I-1000J-1120D01*
G03X1146345Y590417I-267J298D01*
G02X1148317I986J997D01*
G37*
G36*
G01X1142031Y590378D02*
G03X1142058Y589817I298J-267D01*
G02X1139977Y589777I-1020J-1103D01*
G03X1139981Y590338I-283J283D01*
G02X1142031Y590378I1006J976D01*
G37*
G36*
G01X1135631Y590417D02*
G03X1135645Y589834I281J-285D01*
G02X1133645I-1000J-1120D01*
G03X1133659Y590417I-267J298D01*
G02X1135631I986J997D01*
G37*
G36*
G01X1128938D02*
G03X1128952Y589834I281J-285D01*
G02X1126952I-1000J-1120D01*
G03X1126966Y590417I-267J298D01*
G02X1128938I986J997D01*
G37*
G36*
G01X1111545Y590358D02*
G03X1111561Y589797I293J-272D01*
G02X1109479I-1041J-1083D01*
G03X1109495Y590358I-277J289D01*
G02X1111545I1025J956D01*
G37*
G36*
G01X1105220Y590378D02*
G03X1105247Y589817I298J-267D01*
G02X1103166Y589777I-1020J-1103D01*
G03X1103170Y590338I-283J283D01*
G02X1105220Y590378I1006J976D01*
G37*
G36*
G01X954890Y590435D02*
G03X954915Y589853I286J-279D01*
G02X952915Y589816I-979J-1139D01*
G03X952919Y590399I-272J293D01*
G02X954890Y590435I967J1015D01*
G37*
G36*
G01X948229Y590417D02*
G03X948243Y589834I281J-285D01*
G02X946243I-1000J-1120D01*
G03X946257Y590417I-267J298D01*
G02X948229I986J997D01*
G37*
G36*
G01X930797D02*
G03X930811Y589834I281J-285D01*
G02X928811I-1000J-1120D01*
G03X928825Y590417I-267J298D01*
G02X930797I986J997D01*
G37*
G36*
G01X924511Y590378D02*
G03X924538Y589817I298J-267D01*
G02X922457Y589777I-1020J-1103D01*
G03X922461Y590338I-283J283D01*
G02X924511Y590378I1006J976D01*
G37*
G36*
G01X918111Y590417D02*
G03X918125Y589834I281J-285D01*
G02X916125I-1000J-1120D01*
G03X916139Y590417I-267J298D01*
G02X918111I986J997D01*
G37*
G36*
G01X911418D02*
G03X911432Y589834I281J-285D01*
G02X909432I-1000J-1120D01*
G03X909446Y590417I-267J298D01*
G02X911418I986J997D01*
G37*
G36*
G01X893986D02*
G03X894000Y589834I281J-285D01*
G02X892000I-1000J-1120D01*
G03X892014Y590417I-267J298D01*
G02X893986I986J997D01*
G37*
G36*
G01X887700Y590378D02*
G03X887727Y589817I298J-267D01*
G02X885646Y589777I-1020J-1103D01*
G03X885650Y590338I-283J283D01*
G02X887700Y590378I1006J976D01*
G37*
G36*
G01X881300Y590417D02*
G03X881314Y589834I281J-285D01*
G02X879314I-1000J-1120D01*
G03X879328Y590417I-267J298D01*
G02X881300I986J997D01*
G37*
G36*
G01X874607D02*
G03X874621Y589834I281J-285D01*
G02X872621I-1000J-1120D01*
G03X872635Y590417I-267J298D01*
G02X874607I986J997D01*
G37*
G36*
G01X857175D02*
G03X857189Y589834I281J-285D01*
G02X855189I-1000J-1120D01*
G03X855203Y590417I-267J298D01*
G02X857175I986J997D01*
G37*
G36*
G01X850889Y590378D02*
G03X850916Y589817I298J-267D01*
G02X848835Y589777I-1020J-1103D01*
G03X848839Y590338I-283J283D01*
G02X850889Y590378I1006J976D01*
G37*
G36*
G01X844489Y590417D02*
G03X844503Y589834I281J-285D01*
G02X842503I-1000J-1120D01*
G03X842517Y590417I-267J298D01*
G02X844489I986J997D01*
G37*
G36*
G01X837796D02*
G03X837810Y589834I281J-285D01*
G02X835810I-1000J-1120D01*
G03X835824Y590417I-267J298D01*
G02X837796I986J997D01*
G37*
G36*
G01X820384Y590387D02*
G03X820399Y589816I287J-278D01*
G02X818357I-1021J-1102D01*
G03X818372Y590387I-272J293D01*
G02X820384I1006J977D01*
G37*
G36*
G01X814078Y590378D02*
G03X814105Y589817I298J-267D01*
G02X812024Y589777I-1020J-1103D01*
G03X812028Y590338I-283J283D01*
G02X814078Y590378I1006J976D01*
G37*
G36*
G01X807678Y590417D02*
G03X807692Y589834I281J-285D01*
G02X805692I-1000J-1120D01*
G03X805706Y590417I-267J298D01*
G02X807678I986J997D01*
G37*
G36*
G01X800985D02*
G03X800999Y589834I281J-285D01*
G02X798999I-1000J-1120D01*
G03X799013Y590417I-267J298D01*
G02X800985I986J997D01*
G37*
G36*
G01X783553D02*
G03X783567Y589834I281J-285D01*
G02X781567I-1000J-1120D01*
G03X781581Y590417I-267J298D01*
G02X783553I986J997D01*
G37*
G36*
G01X777267Y590378D02*
G03X777294Y589817I298J-267D01*
G02X775213Y589777I-1020J-1103D01*
G03X775217Y590338I-283J283D01*
G02X777267Y590378I1006J976D01*
G37*
G36*
G01X1007377Y589955D02*
G03Y589377I277J-289D01*
G02X1005435I-971J-1011D01*
G03Y589955I-277J289D01*
G02X1007377I971J1011D01*
G37*
G36*
G01X958426Y589947D02*
G03X958416Y589356I264J-300D01*
G02X956530Y589387I-960J-1022D01*
G03X956540Y589978I-264J300D01*
G02X956475Y591957I960J1022D01*
G03X956427Y592547I-292J273D01*
G02X958308Y592700I856J1110D01*
G03X958356Y592110I292J-273D01*
G02X958426Y589947I-856J-1110D01*
G37*
G36*
G01X1096799Y589794D02*
G03X1097019Y590330I-145J373D01*
G02X1098874Y589621I1281J570D01*
G03X1098682Y589075I164J-365D01*
G02X1096799Y589794I-1339J-681D01*
G37*
G36*
G01X709195Y588479D02*
G03X708884Y588024I84J-391D01*
G02X706116I-1384J-224D01*
G03X705805Y588479I-395J64D01*
G02X707189Y590733I295J1371D01*
G03X707811I311J252D01*
G02X709195Y588479I1089J-883D01*
G37*
G36*
G01X1230814Y587343D02*
G03X1230795Y586736I251J-312D01*
G02X1228923Y586751I-944J-1036D01*
G03X1228914Y587359I-265J300D01*
G02X1228778Y589541I960J1155D01*
G03Y590087I-292J273D01*
G02X1228833Y592197I1096J1027D01*
G03X1228849Y592758I-277J289D01*
G02X1230899I1025J956D01*
G03X1230915Y592197I293J-272D01*
G02X1230970Y590087I-1041J-1083D01*
G03Y589541I292J-273D01*
G02X1230814Y587343I-1096J-1027D01*
G37*
G36*
G01X1194003D02*
G03X1193984Y586736I251J-312D01*
G02X1192112Y586751I-944J-1036D01*
G03X1192103Y587359I-265J300D01*
G02X1191967Y589541I960J1155D01*
G03Y590087I-292J273D01*
G02X1192022Y592197I1096J1027D01*
G03X1192038Y592758I-277J289D01*
G02X1194088I1025J956D01*
G03X1194104Y592197I293J-272D01*
G02X1194159Y590087I-1041J-1083D01*
G03Y589541I292J-273D01*
G02X1194003Y587343I-1096J-1027D01*
G37*
G36*
G01X1157192D02*
G03X1157173Y586736I251J-312D01*
G02X1155301Y586751I-944J-1036D01*
G03X1155292Y587359I-265J300D01*
G02X1155156Y589541I960J1155D01*
G03Y590087I-292J273D01*
G02X1155211Y592197I1096J1027D01*
G03X1155227Y592758I-277J289D01*
G02X1157277I1025J956D01*
G03X1157293Y592197I293J-272D01*
G02X1157348Y590087I-1041J-1083D01*
G03Y589541I292J-273D01*
G02X1157192Y587343I-1096J-1027D01*
G37*
G36*
G01X1120380D02*
G03X1120361Y586736I251J-312D01*
G02X1118489Y586751I-944J-1036D01*
G03X1118480Y587359I-265J300D01*
G02X1118344Y589541I960J1155D01*
G03Y590087I-292J273D01*
G02X1118399Y592197I1096J1027D01*
G03X1118415Y592758I-277J289D01*
G02X1120465I1025J956D01*
G03X1120481Y592197I293J-272D01*
G02X1120536Y590087I-1041J-1083D01*
G03Y589541I292J-273D01*
G02X1120380Y587343I-1096J-1027D01*
G37*
G36*
G01X939672D02*
G03X939653Y586736I251J-312D01*
G02X937781Y586751I-944J-1036D01*
G03X937772Y587359I-265J300D01*
G02X937636Y589541I960J1155D01*
G03Y590087I-292J273D01*
G02X937691Y592197I1096J1027D01*
G03X937707Y592758I-277J289D01*
G02X939757I1025J956D01*
G03X939773Y592197I293J-272D01*
G02X939828Y590087I-1041J-1083D01*
G03Y589541I292J-273D01*
G02X939672Y587343I-1096J-1027D01*
G37*
G36*
G01X902861D02*
G03X902842Y586736I251J-312D01*
G02X900970Y586751I-944J-1036D01*
G03X900961Y587359I-265J300D01*
G02X900825Y589541I960J1155D01*
G03Y590087I-292J273D01*
G02X900880Y592197I1096J1027D01*
G03X900896Y592758I-277J289D01*
G02X902946I1025J956D01*
G03X902962Y592197I293J-272D01*
G02X903017Y590087I-1041J-1083D01*
G03Y589541I292J-273D01*
G02X902861Y587343I-1096J-1027D01*
G37*
G36*
G01X866050D02*
G03X866031Y586736I251J-312D01*
G02X864159Y586751I-944J-1036D01*
G03X864150Y587359I-265J300D01*
G02X864014Y589541I960J1155D01*
G03Y590087I-292J273D01*
G02X864069Y592197I1096J1027D01*
G03X864085Y592758I-277J289D01*
G02X866135I1025J956D01*
G03X866151Y592197I293J-272D01*
G02X866206Y590087I-1041J-1083D01*
G03Y589541I292J-273D01*
G02X866050Y587343I-1096J-1027D01*
G37*
G36*
G01X829239D02*
G03X829220Y586736I251J-312D01*
G02X827348Y586751I-944J-1036D01*
G03X827339Y587359I-265J300D01*
G02X827203Y589541I960J1155D01*
G03Y590087I-292J273D01*
G02X827258Y592197I1096J1027D01*
G03X827274Y592758I-277J289D01*
G02X829324I1025J956D01*
G03X829340Y592197I293J-272D01*
G02X829395Y590087I-1041J-1083D01*
G03Y589541I292J-273D01*
G02X829239Y587343I-1096J-1027D01*
G37*
G36*
G01X792428D02*
G03X792409Y586736I251J-312D01*
G02X790537Y586751I-944J-1036D01*
G03X790528Y587359I-265J300D01*
G02X790392Y589541I960J1155D01*
G03Y590087I-292J273D01*
G02X790447Y592197I1096J1027D01*
G03X790463Y592758I-277J289D01*
G02X792513I1025J956D01*
G03X792529Y592197I293J-272D01*
G02X792584Y590087I-1041J-1083D01*
G03Y589541I292J-273D01*
G02X792428Y587343I-1096J-1027D01*
G37*
G36*
G01X1225814Y587216D02*
G03X1225799Y586655I277J-288D01*
G02X1223749I-1025J-957D01*
G03X1223734Y587216I-292J273D01*
G02X1223678Y589327I1040J1084D01*
G03Y589873I-292J273D01*
G02X1223723Y591973I1096J1027D01*
G03X1223733Y592535I-280J286D01*
G02X1225784Y592553I1017J965D01*
G03X1225805Y591992I295J-270D01*
G02X1225870Y589873I-1031J-1092D01*
G03Y589327I292J-273D01*
G02X1225814Y587216I-1096J-1027D01*
G37*
G36*
G01X1189003D02*
G03X1188988Y586655I277J-288D01*
G02X1186938I-1025J-957D01*
G03X1186923Y587216I-292J273D01*
G02X1186867Y589327I1040J1084D01*
G03Y589873I-292J273D01*
G02X1186912Y591973I1096J1027D01*
G03X1186922Y592535I-280J286D01*
G02X1188973Y592553I1017J965D01*
G03X1188994Y591992I295J-270D01*
G02X1189059Y589873I-1031J-1092D01*
G03Y589327I292J-273D01*
G02X1189003Y587216I-1096J-1027D01*
G37*
G36*
G01X1152192D02*
G03X1152177Y586655I277J-288D01*
G02X1150127I-1025J-957D01*
G03X1150112Y587216I-292J273D01*
G02X1150056Y589327I1040J1084D01*
G03Y589873I-292J273D01*
G02X1150101Y591973I1096J1027D01*
G03X1150111Y592535I-280J286D01*
G02X1152162Y592553I1017J965D01*
G03X1152183Y591992I295J-270D01*
G02X1152248Y589873I-1031J-1092D01*
G03Y589327I292J-273D01*
G02X1152192Y587216I-1096J-1027D01*
G37*
G36*
G01X1115380D02*
G03X1115365Y586655I277J-288D01*
G02X1113315I-1025J-957D01*
G03X1113300Y587216I-292J273D01*
G02X1113244Y589327I1040J1084D01*
G03Y589873I-292J273D01*
G02X1113289Y591973I1096J1027D01*
G03X1113299Y592535I-280J286D01*
G02X1115350Y592553I1017J965D01*
G03X1115371Y591992I295J-270D01*
G02X1115436Y589873I-1031J-1092D01*
G03Y589327I292J-273D01*
G02X1115380Y587216I-1096J-1027D01*
G37*
G36*
G01X934672D02*
G03X934657Y586655I277J-288D01*
G02X932607I-1025J-957D01*
G03X932592Y587216I-292J273D01*
G02X932536Y589327I1040J1084D01*
G03Y589873I-292J273D01*
G02X932581Y591973I1096J1027D01*
G03X932591Y592535I-280J286D01*
G02X934642Y592553I1017J965D01*
G03X934663Y591992I295J-270D01*
G02X934728Y589873I-1031J-1092D01*
G03Y589327I292J-273D01*
G02X934672Y587216I-1096J-1027D01*
G37*
G36*
G01X897861D02*
G03X897846Y586655I277J-288D01*
G02X895796I-1025J-957D01*
G03X895781Y587216I-292J273D01*
G02X895725Y589327I1040J1084D01*
G03Y589873I-292J273D01*
G02X895770Y591973I1096J1027D01*
G03X895780Y592535I-280J286D01*
G02X897831Y592553I1017J965D01*
G03X897852Y591992I295J-270D01*
G02X897917Y589873I-1031J-1092D01*
G03Y589327I292J-273D01*
G02X897861Y587216I-1096J-1027D01*
G37*
G36*
G01X861050D02*
G03X861035Y586655I277J-288D01*
G02X858985I-1025J-957D01*
G03X858970Y587216I-292J273D01*
G02X858914Y589327I1040J1084D01*
G03Y589873I-292J273D01*
G02X858959Y591973I1096J1027D01*
G03X858969Y592535I-280J286D01*
G02X861020Y592553I1017J965D01*
G03X861041Y591992I295J-270D01*
G02X861106Y589873I-1031J-1092D01*
G03Y589327I292J-273D01*
G02X861050Y587216I-1096J-1027D01*
G37*
G36*
G01X824239D02*
G03X824224Y586655I277J-288D01*
G02X822174I-1025J-957D01*
G03X822159Y587216I-292J273D01*
G02X822103Y589327I1040J1084D01*
G03Y589873I-292J273D01*
G02X822148Y591973I1096J1027D01*
G03X822158Y592535I-280J286D01*
G02X824209Y592553I1017J965D01*
G03X824230Y591992I295J-270D01*
G02X824295Y589873I-1031J-1092D01*
G03Y589327I292J-273D01*
G02X824239Y587216I-1096J-1027D01*
G37*
G36*
G01X785363Y586655D02*
G03X785348Y587216I-292J273D01*
G02X785292Y589327I1040J1084D01*
G03Y589873I-292J273D01*
G02X785337Y591973I1096J1027D01*
G03X785347Y592535I-280J286D01*
G02X787398Y592553I1017J965D01*
G03X787419Y591992I295J-270D01*
G02X787484Y589873I-1031J-1092D01*
G03Y589327I292J-273D01*
G02X787428Y587216I-1096J-1027D01*
G03X787413Y586655I277J-288D01*
G02X785363I-1025J-957D01*
G37*
G36*
G01X1012788Y584675D02*
G03X1012211I-288J-277D01*
G02Y586753I-1085J1039D01*
G03X1012788I288J277D01*
G02X1014956Y586755I1085J-1039D01*
G03X1015517Y586739I289J277D01*
G02Y584689I956J-1025D01*
G03X1014956Y584673I-272J-293D01*
G02X1012788Y584675I-1083J1041D01*
G37*
G36*
G01X724322Y580004D02*
G03X723696Y579991I-308J-255D01*
G02Y581809I-1196J909D01*
G03X724322Y581796I318J242D01*
G02Y580004I1078J-896D01*
G37*
G36*
G01X1294790Y581238D02*
G03X1295168Y580860I399J21D01*
G02X1293590Y579282I-78J-1500D01*
G03X1293212Y579660I-399J-21D01*
G02X1294790Y581238I78J1500D01*
G37*
G36*
G01X1008303Y570999D02*
G03Y570421I277J-289D01*
G02X1006361I-971J-1011D01*
G03Y570999I-277J289D01*
G02X1008303I971J1011D01*
G37*
G36*
G01X1225841Y568467D02*
G03X1225825Y567906I277J-289D01*
G02X1223775I-1025J-956D01*
G03X1223759Y568467I-293J272D01*
G02X1223712Y570585I1041J1083D01*
G03X1223706Y571142I-290J275D01*
G02X1223733Y573282I1068J1057D01*
G03X1223749Y573843I-277J289D01*
G02X1225799I1025J956D01*
G03X1225815Y573282I293J-272D01*
G02X1225862Y571164I-1041J-1083D01*
G03X1225868Y570607I290J-275D01*
G02X1225841Y568467I-1068J-1057D01*
G37*
G36*
G01X1189030D02*
G03X1189014Y567906I277J-289D01*
G02X1186964I-1025J-956D01*
G03X1186948Y568467I-293J272D01*
G02X1186901Y570585I1041J1083D01*
G03X1186895Y571142I-290J275D01*
G02X1186922Y573282I1068J1057D01*
G03X1186938Y573843I-277J289D01*
G02X1188988I1025J956D01*
G03X1189004Y573282I293J-272D01*
G02X1189051Y571164I-1041J-1083D01*
G03X1189057Y570607I290J-275D01*
G02X1189030Y568467I-1068J-1057D01*
G37*
G36*
G01X1152219D02*
G03X1152203Y567906I277J-289D01*
G02X1150153I-1025J-956D01*
G03X1150137Y568467I-293J272D01*
G02X1150090Y570585I1041J1083D01*
G03X1150084Y571142I-290J275D01*
G02X1150111Y573282I1068J1057D01*
G03X1150127Y573843I-277J289D01*
G02X1152177I1025J956D01*
G03X1152193Y573282I293J-272D01*
G02X1152240Y571164I-1041J-1083D01*
G03X1152246Y570607I290J-275D01*
G02X1152219Y568467I-1068J-1057D01*
G37*
G36*
G01X1115407D02*
G03X1115391Y567906I277J-289D01*
G02X1113341I-1025J-956D01*
G03X1113325Y568467I-293J272D01*
G02X1113278Y570585I1041J1083D01*
G03X1113272Y571142I-290J275D01*
G02X1113299Y573282I1068J1057D01*
G03X1113315Y573843I-277J289D01*
G02X1115365I1025J956D01*
G03X1115381Y573282I293J-272D01*
G02X1115428Y571164I-1041J-1083D01*
G03X1115434Y570607I290J-275D01*
G02X1115407Y568467I-1068J-1057D01*
G37*
G36*
G01X934699D02*
G03X934683Y567906I277J-289D01*
G02X932633I-1025J-956D01*
G03X932617Y568467I-293J272D01*
G02X932570Y570585I1041J1083D01*
G03X932564Y571142I-290J275D01*
G02X932591Y573282I1068J1057D01*
G03X932607Y573843I-277J289D01*
G02X934657I1025J956D01*
G03X934673Y573282I293J-272D01*
G02X934720Y571164I-1041J-1083D01*
G03X934726Y570607I290J-275D01*
G02X934699Y568467I-1068J-1057D01*
G37*
G36*
G01X897888D02*
G03X897872Y567906I277J-289D01*
G02X895822I-1025J-956D01*
G03X895806Y568467I-293J272D01*
G02X895759Y570585I1041J1083D01*
G03X895753Y571142I-290J275D01*
G02X895780Y573282I1068J1057D01*
G03X895796Y573843I-277J289D01*
G02X897846I1025J956D01*
G03X897862Y573282I293J-272D01*
G02X897909Y571164I-1041J-1083D01*
G03X897915Y570607I290J-275D01*
G02X897888Y568467I-1068J-1057D01*
G37*
G36*
G01X861077D02*
G03X861061Y567906I277J-289D01*
G02X859011I-1025J-956D01*
G03X858995Y568467I-293J272D01*
G02X858948Y570585I1041J1083D01*
G03X858942Y571142I-290J275D01*
G02X858969Y573282I1068J1057D01*
G03X858985Y573843I-277J289D01*
G02X861035I1025J956D01*
G03X861051Y573282I293J-272D01*
G02X861098Y571164I-1041J-1083D01*
G03X861104Y570607I290J-275D01*
G02X861077Y568467I-1068J-1057D01*
G37*
G36*
G01X824266D02*
G03X824250Y567906I277J-289D01*
G02X822200I-1025J-956D01*
G03X822184Y568467I-293J272D01*
G02X822137Y570585I1041J1083D01*
G03X822131Y571142I-290J275D01*
G02X822158Y573282I1068J1057D01*
G03X822174Y573843I-277J289D01*
G02X824224I1025J956D01*
G03X824240Y573282I293J-272D01*
G02X824287Y571164I-1041J-1083D01*
G03X824293Y570607I290J-275D01*
G02X824266Y568467I-1068J-1057D01*
G37*
G36*
G01X787455D02*
G03X787439Y567906I277J-289D01*
G02X785389I-1025J-956D01*
G03X785373Y568467I-293J272D01*
G02X785326Y570585I1041J1083D01*
G03X785320Y571142I-290J275D01*
G02X785347Y573282I1068J1057D01*
G03X785363Y573843I-277J289D01*
G02X787413I1025J956D01*
G03X787429Y573282I293J-272D01*
G02X787476Y571164I-1041J-1083D01*
G03X787482Y570607I290J-275D01*
G02X787455Y568467I-1068J-1057D01*
G37*
G36*
G01X1230919Y568261D02*
G03X1230906Y567699I278J-288D01*
G02X1228858Y567689I-1019J-963D01*
G03X1228840Y568250I-293J271D01*
G02X1228781Y570370I1034J1090D01*
G03Y570919I-291J274D01*
G02X1228844Y573043I1093J1031D01*
G03X1228865Y573604I-274J291D01*
G02X1230915Y573583I1035J946D01*
G03X1230925Y573022I290J-275D01*
G02X1230967Y570919I-1051J-1073D01*
G03Y570370I291J-274D01*
G02X1230919Y568261I-1093J-1030D01*
G37*
G36*
G01X1194108D02*
G03X1194095Y567699I278J-288D01*
G02X1192047Y567689I-1019J-963D01*
G03X1192029Y568250I-293J271D01*
G02X1191970Y570370I1034J1090D01*
G03Y570919I-291J274D01*
G02X1192033Y573043I1093J1031D01*
G03X1192054Y573604I-274J291D01*
G02X1194104Y573583I1035J946D01*
G03X1194114Y573022I290J-275D01*
G02X1194156Y570919I-1051J-1073D01*
G03Y570370I291J-274D01*
G02X1194108Y568261I-1093J-1030D01*
G37*
G36*
G01X1157297D02*
G03X1157284Y567699I278J-288D01*
G02X1155236Y567689I-1019J-963D01*
G03X1155218Y568250I-293J271D01*
G02X1155159Y570370I1034J1090D01*
G03Y570919I-291J274D01*
G02X1155222Y573043I1093J1031D01*
G03X1155243Y573604I-274J291D01*
G02X1157293Y573583I1035J946D01*
G03X1157303Y573022I290J-275D01*
G02X1157345Y570919I-1051J-1073D01*
G03Y570370I291J-274D01*
G02X1157297Y568261I-1093J-1030D01*
G37*
G36*
G01X1120485D02*
G03X1120472Y567699I278J-288D01*
G02X1118424Y567689I-1019J-963D01*
G03X1118406Y568250I-293J271D01*
G02X1118347Y570370I1034J1090D01*
G03Y570919I-291J274D01*
G02X1118410Y573043I1093J1031D01*
G03X1118431Y573604I-274J291D01*
G02X1120481Y573583I1035J946D01*
G03X1120491Y573022I290J-275D01*
G02X1120533Y570919I-1051J-1073D01*
G03Y570370I291J-274D01*
G02X1120485Y568261I-1093J-1030D01*
G37*
G36*
G01X939777D02*
G03X939764Y567699I278J-288D01*
G02X937716Y567689I-1019J-963D01*
G03X937698Y568250I-293J271D01*
G02X937639Y570370I1034J1090D01*
G03Y570919I-291J274D01*
G02X937702Y573043I1093J1031D01*
G03X937723Y573604I-274J291D01*
G02X939773Y573583I1035J946D01*
G03X939783Y573022I290J-275D01*
G02X939825Y570919I-1051J-1073D01*
G03Y570370I291J-274D01*
G02X939777Y568261I-1093J-1030D01*
G37*
G36*
G01X902966D02*
G03X902953Y567699I278J-288D01*
G02X900905Y567689I-1019J-963D01*
G03X900887Y568250I-293J271D01*
G02X900828Y570370I1034J1090D01*
G03Y570919I-291J274D01*
G02X900891Y573043I1093J1031D01*
G03X900912Y573604I-274J291D01*
G02X902962Y573583I1035J946D01*
G03X902972Y573022I290J-275D01*
G02X903014Y570919I-1051J-1073D01*
G03Y570370I291J-274D01*
G02X902966Y568261I-1093J-1030D01*
G37*
G36*
G01X866155D02*
G03X866142Y567699I278J-288D01*
G02X864094Y567689I-1019J-963D01*
G03X864076Y568250I-293J271D01*
G02X864017Y570370I1034J1090D01*
G03Y570919I-291J274D01*
G02X864080Y573043I1093J1031D01*
G03X864101Y573604I-274J291D01*
G02X866151Y573583I1035J946D01*
G03X866161Y573022I290J-275D01*
G02X866203Y570919I-1051J-1073D01*
G03Y570370I291J-274D01*
G02X866155Y568261I-1093J-1030D01*
G37*
G36*
G01X829344D02*
G03X829331Y567699I278J-288D01*
G02X827283Y567689I-1019J-963D01*
G03X827265Y568250I-293J271D01*
G02X827206Y570370I1034J1090D01*
G03Y570919I-291J274D01*
G02X827269Y573043I1093J1031D01*
G03X827290Y573604I-274J291D01*
G02X829340Y573583I1035J946D01*
G03X829350Y573022I290J-275D01*
G02X829392Y570919I-1051J-1073D01*
G03Y570370I291J-274D01*
G02X829344Y568261I-1093J-1030D01*
G37*
G36*
G01X792533D02*
G03X792520Y567699I278J-288D01*
G02X790472Y567689I-1019J-963D01*
G03X790454Y568250I-293J271D01*
G02X790395Y570370I1034J1090D01*
G03Y570919I-291J274D01*
G02X790458Y573043I1093J1031D01*
G03X790479Y573604I-274J291D01*
G02X792529Y573583I1035J946D01*
G03X792539Y573022I290J-275D01*
G02X792581Y570919I-1051J-1073D01*
G03Y570370I291J-274D01*
G02X792533Y568261I-1093J-1030D01*
G37*
G36*
G01X1246064Y552617D02*
G03X1246078Y552034I281J-285D01*
G02X1244078I-1000J-1120D01*
G03X1244092Y552617I-267J298D01*
G02X1246064I986J997D01*
G37*
G36*
G01X1239371D02*
G03X1239385Y552034I281J-285D01*
G02X1237385I-1000J-1120D01*
G03X1237399Y552617I-267J298D01*
G02X1239371I986J997D01*
G37*
G36*
G01X1221939D02*
G03X1221953Y552034I281J-285D01*
G02X1219953I-1000J-1120D01*
G03X1219967Y552617I-267J298D01*
G02X1221939I986J997D01*
G37*
G36*
G01X1209253D02*
G03X1209267Y552034I281J-285D01*
G02X1207267I-1000J-1120D01*
G03X1207281Y552617I-267J298D01*
G02X1209253I986J997D01*
G37*
G36*
G01X1202560D02*
G03X1202574Y552034I281J-285D01*
G02X1200574I-1000J-1120D01*
G03X1200588Y552617I-267J298D01*
G02X1202560I986J997D01*
G37*
G36*
G01X1185128D02*
G03X1185142Y552034I281J-285D01*
G02X1183142I-1000J-1120D01*
G03X1183156Y552617I-267J298D01*
G02X1185128I986J997D01*
G37*
G36*
G01X1178842Y552578D02*
G03X1178869Y552017I298J-267D01*
G02X1176788Y551977I-1020J-1103D01*
G03X1176792Y552538I-283J283D01*
G02X1178842Y552578I1006J976D01*
G37*
G36*
G01X1172442Y552617D02*
G03X1172456Y552034I281J-285D01*
G02X1170456I-1000J-1120D01*
G03X1170470Y552617I-267J298D01*
G02X1172442I986J997D01*
G37*
G36*
G01X1165749D02*
G03X1165763Y552034I281J-285D01*
G02X1163763I-1000J-1120D01*
G03X1163777Y552617I-267J298D01*
G02X1165749I986J997D01*
G37*
G36*
G01X1148317D02*
G03X1148331Y552034I281J-285D01*
G02X1146331I-1000J-1120D01*
G03X1146345Y552617I-267J298D01*
G02X1148317I986J997D01*
G37*
G36*
G01X1142031Y552578D02*
G03X1142058Y552017I298J-267D01*
G02X1139977Y551977I-1020J-1103D01*
G03X1139981Y552538I-283J283D01*
G02X1142031Y552578I1006J976D01*
G37*
G36*
G01X1135631Y552617D02*
G03X1135645Y552034I281J-285D01*
G02X1133645I-1000J-1120D01*
G03X1133659Y552617I-267J298D01*
G02X1135631I986J997D01*
G37*
G36*
G01X1128938D02*
G03X1128952Y552034I281J-285D01*
G02X1126952I-1000J-1120D01*
G03X1126966Y552617I-267J298D01*
G02X1128938I986J997D01*
G37*
G36*
G01X1111545Y552558D02*
G03X1111561Y551997I293J-272D01*
G02X1109479I-1041J-1083D01*
G03X1109495Y552558I-277J289D01*
G02X1111545I1025J956D01*
G37*
G36*
G01X1105220Y552578D02*
G03X1105247Y552017I298J-267D01*
G02X1103166Y551977I-1020J-1103D01*
G03X1103170Y552538I-283J283D01*
G02X1105220Y552578I1006J976D01*
G37*
G36*
G01X954890Y552635D02*
G03X954915Y552053I286J-279D01*
G02X952915Y552016I-979J-1139D01*
G03X952919Y552599I-272J293D01*
G02X954890Y552635I967J1015D01*
G37*
G36*
G01X948229Y552617D02*
G03X948243Y552034I281J-285D01*
G02X946243I-1000J-1120D01*
G03X946257Y552617I-267J298D01*
G02X948229I986J997D01*
G37*
G36*
G01X930797D02*
G03X930811Y552034I281J-285D01*
G02X928811I-1000J-1120D01*
G03X928825Y552617I-267J298D01*
G02X930797I986J997D01*
G37*
G36*
G01X924511Y552578D02*
G03X924538Y552017I298J-267D01*
G02X922457Y551977I-1020J-1103D01*
G03X922461Y552538I-283J283D01*
G02X924511Y552578I1006J976D01*
G37*
G36*
G01X918111Y552617D02*
G03X918125Y552034I281J-285D01*
G02X916125I-1000J-1120D01*
G03X916139Y552617I-267J298D01*
G02X918111I986J997D01*
G37*
G36*
G01X911418D02*
G03X911432Y552034I281J-285D01*
G02X909432I-1000J-1120D01*
G03X909446Y552617I-267J298D01*
G02X911418I986J997D01*
G37*
G36*
G01X893986D02*
G03X894000Y552034I281J-285D01*
G02X892000I-1000J-1120D01*
G03X892014Y552617I-267J298D01*
G02X893986I986J997D01*
G37*
G36*
G01X887700Y552578D02*
G03X887727Y552017I298J-267D01*
G02X885646Y551977I-1020J-1103D01*
G03X885650Y552538I-283J283D01*
G02X887700Y552578I1006J976D01*
G37*
G36*
G01X881300Y552617D02*
G03X881314Y552034I281J-285D01*
G02X879314I-1000J-1120D01*
G03X879328Y552617I-267J298D01*
G02X881300I986J997D01*
G37*
G36*
G01X874607D02*
G03X874621Y552034I281J-285D01*
G02X872621I-1000J-1120D01*
G03X872635Y552617I-267J298D01*
G02X874607I986J997D01*
G37*
G36*
G01X857175D02*
G03X857189Y552034I281J-285D01*
G02X855189I-1000J-1120D01*
G03X855203Y552617I-267J298D01*
G02X857175I986J997D01*
G37*
G36*
G01X850889Y552578D02*
G03X850916Y552017I298J-267D01*
G02X848835Y551977I-1020J-1103D01*
G03X848839Y552538I-283J283D01*
G02X850889Y552578I1006J976D01*
G37*
G36*
G01X844489Y552617D02*
G03X844503Y552034I281J-285D01*
G02X842503I-1000J-1120D01*
G03X842517Y552617I-267J298D01*
G02X844489I986J997D01*
G37*
G36*
G01X837796D02*
G03X837810Y552034I281J-285D01*
G02X835810I-1000J-1120D01*
G03X835824Y552617I-267J298D01*
G02X837796I986J997D01*
G37*
G36*
G01X820384Y552587D02*
G03X820399Y552016I287J-278D01*
G02X818357I-1021J-1102D01*
G03X818372Y552587I-272J293D01*
G02X820384I1006J977D01*
G37*
G36*
G01X814078Y552578D02*
G03X814105Y552017I298J-267D01*
G02X812024Y551977I-1020J-1103D01*
G03X812028Y552538I-283J283D01*
G02X814078Y552578I1006J976D01*
G37*
G36*
G01X807678Y552617D02*
G03X807692Y552034I281J-285D01*
G02X805692I-1000J-1120D01*
G03X805706Y552617I-267J298D01*
G02X807678I986J997D01*
G37*
G36*
G01X800985D02*
G03X800999Y552034I281J-285D01*
G02X798999I-1000J-1120D01*
G03X799013Y552617I-267J298D01*
G02X800985I986J997D01*
G37*
G36*
G01X783553D02*
G03X783567Y552034I281J-285D01*
G02X781567I-1000J-1120D01*
G03X781581Y552617I-267J298D01*
G02X783553I986J997D01*
G37*
G36*
G01X777267Y552578D02*
G03X777294Y552017I298J-267D01*
G02X775213Y551977I-1020J-1103D01*
G03X775217Y552538I-283J283D01*
G02X777267Y552578I1006J976D01*
G37*
G36*
G01X1008118Y552100D02*
G03Y551522I277J-289D01*
G02X1006176I-971J-1011D01*
G03Y552100I-277J289D01*
G02X1008118I971J1011D01*
G37*
G36*
G01X1230814Y549543D02*
G03X1230795Y548936I251J-312D01*
G02X1228923Y548951I-944J-1036D01*
G03X1228914Y549559I-265J300D01*
G02X1228778Y551741I960J1155D01*
G03Y552287I-292J273D01*
G02X1228833Y554397I1096J1027D01*
G03X1228849Y554958I-277J289D01*
G02X1230899I1025J956D01*
G03X1230915Y554397I293J-272D01*
G02X1230970Y552287I-1041J-1083D01*
G03Y551741I292J-273D01*
G02X1230814Y549543I-1096J-1027D01*
G37*
G36*
G01X1194003D02*
G03X1193984Y548936I251J-312D01*
G02X1192112Y548951I-944J-1036D01*
G03X1192103Y549559I-265J300D01*
G02X1191967Y551741I960J1155D01*
G03Y552287I-292J273D01*
G02X1192022Y554397I1096J1027D01*
G03X1192038Y554958I-277J289D01*
G02X1194088I1025J956D01*
G03X1194104Y554397I293J-272D01*
G02X1194159Y552287I-1041J-1083D01*
G03Y551741I292J-273D01*
G02X1194003Y549543I-1096J-1027D01*
G37*
G36*
G01X1157192D02*
G03X1157173Y548936I251J-312D01*
G02X1155301Y548951I-944J-1036D01*
G03X1155292Y549559I-265J300D01*
G02X1155156Y551741I960J1155D01*
G03Y552287I-292J273D01*
G02X1155211Y554397I1096J1027D01*
G03X1155227Y554958I-277J289D01*
G02X1157277I1025J956D01*
G03X1157293Y554397I293J-272D01*
G02X1157348Y552287I-1041J-1083D01*
G03Y551741I292J-273D01*
G02X1157192Y549543I-1096J-1027D01*
G37*
G36*
G01X1120380D02*
G03X1120361Y548936I251J-312D01*
G02X1118489Y548951I-944J-1036D01*
G03X1118480Y549559I-265J300D01*
G02X1118344Y551741I960J1155D01*
G03Y552287I-292J273D01*
G02X1118399Y554397I1096J1027D01*
G03X1118415Y554958I-277J289D01*
G02X1120465I1025J956D01*
G03X1120481Y554397I293J-272D01*
G02X1120536Y552287I-1041J-1083D01*
G03Y551741I292J-273D01*
G02X1120380Y549543I-1096J-1027D01*
G37*
G36*
G01X939672D02*
G03X939653Y548936I251J-312D01*
G02X937781Y548951I-944J-1036D01*
G03X937772Y549559I-265J300D01*
G02X937636Y551741I960J1155D01*
G03Y552287I-292J273D01*
G02X937691Y554397I1096J1027D01*
G03X937707Y554958I-277J289D01*
G02X939757I1025J956D01*
G03X939773Y554397I293J-272D01*
G02X939828Y552287I-1041J-1083D01*
G03Y551741I292J-273D01*
G02X939672Y549543I-1096J-1027D01*
G37*
G36*
G01X902861D02*
G03X902842Y548936I251J-312D01*
G02X900970Y548951I-944J-1036D01*
G03X900961Y549559I-265J300D01*
G02X900825Y551741I960J1155D01*
G03Y552287I-292J273D01*
G02X900880Y554397I1096J1027D01*
G03X900896Y554958I-277J289D01*
G02X902946I1025J956D01*
G03X902962Y554397I293J-272D01*
G02X903017Y552287I-1041J-1083D01*
G03Y551741I292J-273D01*
G02X902861Y549543I-1096J-1027D01*
G37*
G36*
G01X866050D02*
G03X866031Y548936I251J-312D01*
G02X864159Y548951I-944J-1036D01*
G03X864150Y549559I-265J300D01*
G02X864014Y551741I960J1155D01*
G03Y552287I-292J273D01*
G02X864069Y554397I1096J1027D01*
G03X864085Y554958I-277J289D01*
G02X866135I1025J956D01*
G03X866151Y554397I293J-272D01*
G02X866206Y552287I-1041J-1083D01*
G03Y551741I292J-273D01*
G02X866050Y549543I-1096J-1027D01*
G37*
G36*
G01X829239D02*
G03X829220Y548936I251J-312D01*
G02X827348Y548951I-944J-1036D01*
G03X827339Y549559I-265J300D01*
G02X827203Y551741I960J1155D01*
G03Y552287I-292J273D01*
G02X827258Y554397I1096J1027D01*
G03X827274Y554958I-277J289D01*
G02X829324I1025J956D01*
G03X829340Y554397I293J-272D01*
G02X829395Y552287I-1041J-1083D01*
G03Y551741I292J-273D01*
G02X829239Y549543I-1096J-1027D01*
G37*
G36*
G01X792428D02*
G03X792409Y548936I251J-312D01*
G02X790537Y548951I-944J-1036D01*
G03X790528Y549559I-265J300D01*
G02X790392Y551741I960J1155D01*
G03Y552287I-292J273D01*
G02X790447Y554397I1096J1027D01*
G03X790463Y554958I-277J289D01*
G02X792513I1025J956D01*
G03X792529Y554397I293J-272D01*
G02X792584Y552287I-1041J-1083D01*
G03Y551741I292J-273D01*
G02X792428Y549543I-1096J-1027D01*
G37*
G36*
G01X1225814Y549416D02*
G03X1225799Y548855I277J-288D01*
G02X1223749I-1025J-957D01*
G03X1223734Y549416I-292J273D01*
G02X1223678Y551527I1040J1084D01*
G03Y552073I-292J273D01*
G02X1223723Y554173I1096J1027D01*
G03X1223733Y554735I-280J286D01*
G02X1225784Y554753I1017J965D01*
G03X1225805Y554192I295J-270D01*
G02X1225870Y552073I-1031J-1092D01*
G03Y551527I292J-273D01*
G02X1225814Y549416I-1096J-1027D01*
G37*
G36*
G01X1189003D02*
G03X1188988Y548855I277J-288D01*
G02X1186938I-1025J-957D01*
G03X1186923Y549416I-292J273D01*
G02X1186867Y551527I1040J1084D01*
G03Y552073I-292J273D01*
G02X1186912Y554173I1096J1027D01*
G03X1186922Y554735I-280J286D01*
G02X1188973Y554753I1017J965D01*
G03X1188994Y554192I295J-270D01*
G02X1189059Y552073I-1031J-1092D01*
G03Y551527I292J-273D01*
G02X1189003Y549416I-1096J-1027D01*
G37*
G36*
G01X1152192D02*
G03X1152177Y548855I277J-288D01*
G02X1150127I-1025J-957D01*
G03X1150112Y549416I-292J273D01*
G02X1150056Y551527I1040J1084D01*
G03Y552073I-292J273D01*
G02X1150101Y554173I1096J1027D01*
G03X1150111Y554735I-280J286D01*
G02X1152162Y554753I1017J965D01*
G03X1152183Y554192I295J-270D01*
G02X1152248Y552073I-1031J-1092D01*
G03Y551527I292J-273D01*
G02X1152192Y549416I-1096J-1027D01*
G37*
G36*
G01X1115380D02*
G03X1115365Y548855I277J-288D01*
G02X1113315I-1025J-957D01*
G03X1113300Y549416I-292J273D01*
G02X1113244Y551527I1040J1084D01*
G03Y552073I-292J273D01*
G02X1113289Y554173I1096J1027D01*
G03X1113299Y554735I-280J286D01*
G02X1115350Y554753I1017J965D01*
G03X1115371Y554192I295J-270D01*
G02X1115436Y552073I-1031J-1092D01*
G03Y551527I292J-273D01*
G02X1115380Y549416I-1096J-1027D01*
G37*
G36*
G01X934672D02*
G03X934657Y548855I277J-288D01*
G02X932607I-1025J-957D01*
G03X932592Y549416I-292J273D01*
G02X932536Y551527I1040J1084D01*
G03Y552073I-292J273D01*
G02X932581Y554173I1096J1027D01*
G03X932591Y554735I-280J286D01*
G02X934642Y554753I1017J965D01*
G03X934663Y554192I295J-270D01*
G02X934728Y552073I-1031J-1092D01*
G03Y551527I292J-273D01*
G02X934672Y549416I-1096J-1027D01*
G37*
G36*
G01X897861D02*
G03X897846Y548855I277J-288D01*
G02X895796I-1025J-957D01*
G03X895781Y549416I-292J273D01*
G02X895725Y551527I1040J1084D01*
G03Y552073I-292J273D01*
G02X895770Y554173I1096J1027D01*
G03X895780Y554735I-280J286D01*
G02X897831Y554753I1017J965D01*
G03X897852Y554192I295J-270D01*
G02X897917Y552073I-1031J-1092D01*
G03Y551527I292J-273D01*
G02X897861Y549416I-1096J-1027D01*
G37*
G36*
G01X861050D02*
G03X861035Y548855I277J-288D01*
G02X858985I-1025J-957D01*
G03X858970Y549416I-292J273D01*
G02X858914Y551527I1040J1084D01*
G03Y552073I-292J273D01*
G02X858959Y554173I1096J1027D01*
G03X858969Y554735I-280J286D01*
G02X861020Y554753I1017J965D01*
G03X861041Y554192I295J-270D01*
G02X861106Y552073I-1031J-1092D01*
G03Y551527I292J-273D01*
G02X861050Y549416I-1096J-1027D01*
G37*
G36*
G01X824239D02*
G03X824224Y548855I277J-288D01*
G02X822174I-1025J-957D01*
G03X822159Y549416I-292J273D01*
G02X822103Y551527I1040J1084D01*
G03Y552073I-292J273D01*
G02X822148Y554173I1096J1027D01*
G03X822158Y554735I-280J286D01*
G02X824209Y554753I1017J965D01*
G03X824230Y554192I295J-270D01*
G02X824295Y552073I-1031J-1092D01*
G03Y551527I292J-273D01*
G02X824239Y549416I-1096J-1027D01*
G37*
G36*
G01X785363Y548855D02*
G03X785348Y549416I-292J273D01*
G02X785292Y551527I1040J1084D01*
G03Y552073I-292J273D01*
G02X785337Y554173I1096J1027D01*
G03X785347Y554735I-280J286D01*
G02X787398Y554753I1017J965D01*
G03X787419Y554192I295J-270D01*
G02X787484Y552073I-1031J-1092D01*
G03Y551527I292J-273D01*
G02X787428Y549416I-1096J-1027D01*
G03X787413Y548855I277J-288D01*
G02X785363I-1025J-957D01*
G37*
G36*
G01X1012788Y546875D02*
G03X1012211I-288J-277D01*
G02Y548953I-1085J1039D01*
G03X1012788I288J277D01*
G02Y546875I1085J-1039D01*
G37*
G36*
G01X1027510Y540027D02*
G03Y539473I288J-277D01*
G02X1025490I-1010J-973D01*
G03Y540027I-288J277D01*
G02X1025479Y541961I1010J973D01*
G03X1025442Y542543I-292J274D01*
G02Y544857I958J1157D01*
G03X1025479Y545439I-255J308D01*
G02X1027447Y545366I1021J961D01*
G03X1027441Y544783I271J-294D01*
G02Y542617I-1041J-1083D01*
G03X1027447Y542034I277J-289D01*
G02X1027510Y540027I-947J-1034D01*
G37*
G36*
G01X897909Y533364D02*
G03X897915Y532807I290J-275D01*
G02X895759Y532785I-1067J-1057D01*
G03X895753Y533342I-290J275D01*
G02X895780Y535482I1068J1057D01*
G03X895796Y536043I-277J289D01*
G02X897846I1025J956D01*
G03X897862Y535482I293J-272D01*
G02X897909Y533364I-1041J-1083D01*
G37*
G36*
G01X1008178Y533126D02*
G03Y532548I277J-289D01*
G02X1006236I-971J-1011D01*
G03Y533126I-277J289D01*
G02X1008178I971J1011D01*
G37*
G36*
G01X1225841Y530667D02*
G03X1225825Y530106I277J-289D01*
G02X1223775I-1025J-956D01*
G03X1223759Y530667I-293J272D01*
G02X1223712Y532785I1041J1083D01*
G03X1223706Y533342I-290J275D01*
G02X1223733Y535482I1068J1057D01*
G03X1223749Y536043I-277J289D01*
G02X1225799I1025J956D01*
G03X1225815Y535482I293J-272D01*
G02X1225862Y533364I-1041J-1083D01*
G03X1225868Y532807I290J-275D01*
G02X1225841Y530667I-1068J-1057D01*
G37*
G36*
G01X1189030D02*
G03X1189014Y530106I277J-289D01*
G02X1186964I-1025J-956D01*
G03X1186948Y530667I-293J272D01*
G02X1186901Y532785I1041J1083D01*
G03X1186895Y533342I-290J275D01*
G02X1186922Y535482I1068J1057D01*
G03X1186938Y536043I-277J289D01*
G02X1188988I1025J956D01*
G03X1189004Y535482I293J-272D01*
G02X1189051Y533364I-1041J-1083D01*
G03X1189057Y532807I290J-275D01*
G02X1189030Y530667I-1068J-1057D01*
G37*
G36*
G01X1152219D02*
G03X1152203Y530106I277J-289D01*
G02X1150153I-1025J-956D01*
G03X1150137Y530667I-293J272D01*
G02X1150090Y532785I1041J1083D01*
G03X1150084Y533342I-290J275D01*
G02X1150111Y535482I1068J1057D01*
G03X1150127Y536043I-277J289D01*
G02X1152177I1025J956D01*
G03X1152193Y535482I293J-272D01*
G02X1152240Y533364I-1041J-1083D01*
G03X1152246Y532807I290J-275D01*
G02X1152219Y530667I-1068J-1057D01*
G37*
G36*
G01X1115407D02*
G03X1115391Y530106I277J-289D01*
G02X1113341I-1025J-956D01*
G03X1113325Y530667I-293J272D01*
G02X1113278Y532785I1041J1083D01*
G03X1113272Y533342I-290J275D01*
G02X1113299Y535482I1068J1057D01*
G03X1113315Y536043I-277J289D01*
G02X1115365I1025J956D01*
G03X1115381Y535482I293J-272D01*
G02X1115428Y533364I-1041J-1083D01*
G03X1115434Y532807I290J-275D01*
G02X1115407Y530667I-1068J-1057D01*
G37*
G36*
G01X934699D02*
G03X934683Y530106I277J-289D01*
G02X932633I-1025J-956D01*
G03X932617Y530667I-293J272D01*
G02X932570Y532785I1041J1083D01*
G03X932564Y533342I-290J275D01*
G02X932591Y535482I1068J1057D01*
G03X932607Y536043I-277J289D01*
G02X934657I1025J956D01*
G03X934673Y535482I293J-272D01*
G02X934720Y533364I-1041J-1083D01*
G03X934726Y532807I290J-275D01*
G02X934699Y530667I-1068J-1057D01*
G37*
G36*
G01X861077D02*
G03X861061Y530106I277J-289D01*
G02X859011I-1025J-956D01*
G03X858995Y530667I-293J272D01*
G02X858948Y532785I1041J1083D01*
G03X858942Y533342I-290J275D01*
G02X858969Y535482I1068J1057D01*
G03X858985Y536043I-277J289D01*
G02X861035I1025J956D01*
G03X861051Y535482I293J-272D01*
G02X861098Y533364I-1041J-1083D01*
G03X861104Y532807I290J-275D01*
G02X861077Y530667I-1068J-1057D01*
G37*
G36*
G01X824266D02*
G03X824250Y530106I277J-289D01*
G02X822200I-1025J-956D01*
G03X822184Y530667I-293J272D01*
G02X822137Y532785I1041J1083D01*
G03X822131Y533342I-290J275D01*
G02X822158Y535482I1068J1057D01*
G03X822174Y536043I-277J289D01*
G02X824224I1025J956D01*
G03X824240Y535482I293J-272D01*
G02X824287Y533364I-1041J-1083D01*
G03X824293Y532807I290J-275D01*
G02X824266Y530667I-1068J-1057D01*
G37*
G36*
G01X787455D02*
G03X787439Y530106I277J-289D01*
G02X785389I-1025J-956D01*
G03X785373Y530667I-293J272D01*
G02X785326Y532785I1041J1083D01*
G03X785320Y533342I-290J275D01*
G02X785347Y535482I1068J1057D01*
G03X785363Y536043I-277J289D01*
G02X787413I1025J956D01*
G03X787429Y535482I293J-272D01*
G02X787476Y533364I-1041J-1083D01*
G03X787482Y532807I290J-275D01*
G02X787455Y530667I-1068J-1057D01*
G37*
G36*
G01X1230919Y530461D02*
G03X1230906Y529899I278J-288D01*
G02X1228858Y529889I-1019J-963D01*
G03X1228840Y530450I-293J271D01*
G02X1228781Y532570I1034J1090D01*
G03Y533119I-291J274D01*
G02X1228844Y535243I1093J1031D01*
G03X1228865Y535804I-274J291D01*
G02X1230915Y535783I1035J946D01*
G03X1230925Y535222I290J-275D01*
G02X1230967Y533119I-1051J-1073D01*
G03Y532570I291J-274D01*
G02X1230919Y530461I-1093J-1030D01*
G37*
G36*
G01X1194108D02*
G03X1194095Y529899I278J-288D01*
G02X1192047Y529889I-1019J-963D01*
G03X1192029Y530450I-293J271D01*
G02X1191970Y532570I1034J1090D01*
G03Y533119I-291J274D01*
G02X1192033Y535243I1093J1031D01*
G03X1192054Y535804I-274J291D01*
G02X1194104Y535783I1035J946D01*
G03X1194114Y535222I290J-275D01*
G02X1194156Y533119I-1051J-1073D01*
G03Y532570I291J-274D01*
G02X1194108Y530461I-1093J-1030D01*
G37*
G36*
G01X1157297D02*
G03X1157284Y529899I278J-288D01*
G02X1155236Y529889I-1019J-963D01*
G03X1155218Y530450I-293J271D01*
G02X1155159Y532570I1034J1090D01*
G03Y533119I-291J274D01*
G02X1155222Y535243I1093J1031D01*
G03X1155243Y535804I-274J291D01*
G02X1157293Y535783I1035J946D01*
G03X1157303Y535222I290J-275D01*
G02X1157345Y533119I-1051J-1073D01*
G03Y532570I291J-274D01*
G02X1157297Y530461I-1093J-1030D01*
G37*
G36*
G01X1120485D02*
G03X1120472Y529899I278J-288D01*
G02X1118424Y529889I-1019J-963D01*
G03X1118406Y530450I-293J271D01*
G02X1118347Y532570I1034J1090D01*
G03Y533119I-291J274D01*
G02X1118410Y535243I1093J1031D01*
G03X1118431Y535804I-274J291D01*
G02X1120481Y535783I1035J946D01*
G03X1120491Y535222I290J-275D01*
G02X1120533Y533119I-1051J-1073D01*
G03Y532570I291J-274D01*
G02X1120485Y530461I-1093J-1030D01*
G37*
G36*
G01X939777D02*
G03X939764Y529899I278J-288D01*
G02X937716Y529889I-1019J-963D01*
G03X937698Y530450I-293J271D01*
G02X937639Y532570I1034J1090D01*
G03Y533119I-291J274D01*
G02X937702Y535243I1093J1031D01*
G03X937723Y535804I-274J291D01*
G02X939773Y535783I1035J946D01*
G03X939783Y535222I290J-275D01*
G02X939825Y533119I-1051J-1073D01*
G03Y532570I291J-274D01*
G02X939777Y530461I-1093J-1030D01*
G37*
G36*
G01X902966D02*
G03X902953Y529899I278J-288D01*
G02X900905Y529889I-1019J-963D01*
G03X900887Y530450I-293J271D01*
G02X900828Y532570I1034J1090D01*
G03Y533119I-291J274D01*
G02X900891Y535243I1093J1031D01*
G03X900912Y535804I-274J291D01*
G02X902962Y535783I1035J946D01*
G03X902972Y535222I290J-275D01*
G02X903014Y533119I-1051J-1073D01*
G03Y532570I291J-274D01*
G02X902966Y530461I-1093J-1030D01*
G37*
G36*
G01X866155D02*
G03X866142Y529899I278J-288D01*
G02X864094Y529889I-1019J-963D01*
G03X864076Y530450I-293J271D01*
G02X864017Y532570I1034J1090D01*
G03Y533119I-291J274D01*
G02X864080Y535243I1093J1031D01*
G03X864101Y535804I-274J291D01*
G02X866151Y535783I1035J946D01*
G03X866161Y535222I290J-275D01*
G02X866203Y533119I-1051J-1073D01*
G03Y532570I291J-274D01*
G02X866155Y530461I-1093J-1030D01*
G37*
G36*
G01X829344D02*
G03X829331Y529899I278J-288D01*
G02X827283Y529889I-1019J-963D01*
G03X827265Y530450I-293J271D01*
G02X827206Y532570I1034J1090D01*
G03Y533119I-291J274D01*
G02X827269Y535243I1093J1031D01*
G03X827290Y535804I-274J291D01*
G02X829340Y535783I1035J946D01*
G03X829350Y535222I290J-275D01*
G02X829392Y533119I-1051J-1073D01*
G03Y532570I291J-274D01*
G02X829344Y530461I-1093J-1030D01*
G37*
G36*
G01X792533D02*
G03X792520Y529899I278J-288D01*
G02X790472Y529889I-1019J-963D01*
G03X790454Y530450I-293J271D01*
G02X790395Y532570I1034J1090D01*
G03Y533119I-291J274D01*
G02X790458Y535243I1093J1031D01*
G03X790479Y535804I-274J291D01*
G02X792529Y535783I1035J946D01*
G03X792539Y535222I290J-275D01*
G02X792581Y533119I-1051J-1073D01*
G03Y532570I291J-274D01*
G02X792533Y530461I-1093J-1030D01*
G37*
G36*
G01X1297354Y526683D02*
G03X1296766I-294J-270D01*
G02X1294737Y528885I-1105J1018D01*
G03Y529515I-246J315D01*
G02Y531885I923J1185D01*
G03Y532515I-246J315D01*
G02Y534885I923J1185D01*
G03Y535515I-246J315D01*
G02X1296766Y537717I924J1184D01*
G03X1297354I294J270D01*
G02X1299383Y535515I1105J-1018D01*
G03Y534885I246J-315D01*
G02Y532515I-923J-1185D01*
G03Y531885I246J-315D01*
G02Y529515I-923J-1185D01*
G03Y528885I246J-315D01*
G02X1297354Y526683I-924J-1184D01*
G37*
G36*
G01X1320827Y524440D02*
G03X1320273I-277J-288D01*
G02X1318254Y526384I-973J1010D01*
G03Y526916I-298J266D01*
G02Y528784I1046J934D01*
G03Y529316I-298J266D01*
G02Y531184I1046J934D01*
G03Y531716I-298J266D01*
G02X1320232Y533697I1046J934D01*
G03X1320787Y533719I266J299D01*
G02X1322810Y531777I1013J-969D01*
G03Y531223I288J-277D01*
G02X1322846Y529316I-1010J-973D01*
G03Y528784I298J-266D01*
G02Y526916I-1046J-934D01*
G03Y526384I298J-266D01*
G02X1320827Y524440I-1046J-934D01*
G37*
G36*
G01X1025932Y517869D02*
G03Y517343I302J-263D01*
G02X1023668I-1132J-987D01*
G03Y517869I-302J263D01*
G02X1025932I1132J987D01*
G37*
G36*
G01X1314796Y516773D02*
G03Y516227I292J-273D01*
G02X1312604I-1096J-1027D01*
G03Y516773I-292J273D01*
G02X1314796I1096J1027D01*
G37*
G36*
G01X1012306Y516269D02*
G03X1012857Y516258I281J284D01*
G02X1012817Y514083I1016J-1107D01*
G03X1012266Y514094I-281J-284D01*
G02X1012306Y516269I-1016J1107D01*
G37*
G36*
G01X1246064Y514817D02*
G03X1246078Y514234I281J-285D01*
G02X1244078I-1000J-1120D01*
G03X1244092Y514817I-267J298D01*
G02X1246064I986J997D01*
G37*
G36*
G01X1239371D02*
G03X1239385Y514234I281J-285D01*
G02X1237385I-1000J-1120D01*
G03X1237399Y514817I-267J298D01*
G02X1239371I986J997D01*
G37*
G36*
G01X1221939D02*
G03X1221953Y514234I281J-285D01*
G02X1219953I-1000J-1120D01*
G03X1219967Y514817I-267J298D01*
G02X1221939I986J997D01*
G37*
G36*
G01X1209253D02*
G03X1209267Y514234I281J-285D01*
G02X1207267I-1000J-1120D01*
G03X1207281Y514817I-267J298D01*
G02X1209253I986J997D01*
G37*
G36*
G01X1202560D02*
G03X1202574Y514234I281J-285D01*
G02X1200574I-1000J-1120D01*
G03X1200588Y514817I-267J298D01*
G02X1202560I986J997D01*
G37*
G36*
G01X1185128D02*
G03X1185142Y514234I281J-285D01*
G02X1183142I-1000J-1120D01*
G03X1183156Y514817I-267J298D01*
G02X1185128I986J997D01*
G37*
G36*
G01X1178842Y514778D02*
G03X1178869Y514217I298J-267D01*
G02X1176788Y514177I-1020J-1103D01*
G03X1176792Y514738I-283J283D01*
G02X1178842Y514778I1006J976D01*
G37*
G36*
G01X1172442Y514817D02*
G03X1172456Y514234I281J-285D01*
G02X1170456I-1000J-1120D01*
G03X1170470Y514817I-267J298D01*
G02X1172442I986J997D01*
G37*
G36*
G01X1165749D02*
G03X1165763Y514234I281J-285D01*
G02X1163763I-1000J-1120D01*
G03X1163777Y514817I-267J298D01*
G02X1165749I986J997D01*
G37*
G36*
G01X1148317D02*
G03X1148331Y514234I281J-285D01*
G02X1146331I-1000J-1120D01*
G03X1146345Y514817I-267J298D01*
G02X1148317I986J997D01*
G37*
G36*
G01X1142031Y514778D02*
G03X1142058Y514217I298J-267D01*
G02X1139977Y514177I-1020J-1103D01*
G03X1139981Y514738I-283J283D01*
G02X1142031Y514778I1006J976D01*
G37*
G36*
G01X1135631Y514817D02*
G03X1135645Y514234I281J-285D01*
G02X1133645I-1000J-1120D01*
G03X1133659Y514817I-267J298D01*
G02X1135631I986J997D01*
G37*
G36*
G01X1128938D02*
G03X1128952Y514234I281J-285D01*
G02X1126952I-1000J-1120D01*
G03X1126966Y514817I-267J298D01*
G02X1128938I986J997D01*
G37*
G36*
G01X1111545Y514758D02*
G03X1111561Y514197I293J-272D01*
G02X1109479I-1041J-1083D01*
G03X1109495Y514758I-277J289D01*
G02X1111545I1025J956D01*
G37*
G36*
G01X1105220Y514778D02*
G03X1105247Y514217I298J-267D01*
G02X1103166Y514177I-1020J-1103D01*
G03X1103170Y514738I-283J283D01*
G02X1105220Y514778I1006J976D01*
G37*
G36*
G01X954890Y514835D02*
G03X954915Y514253I286J-279D01*
G02X952915Y514216I-979J-1139D01*
G03X952919Y514799I-272J293D01*
G02X954890Y514835I967J1015D01*
G37*
G36*
G01X948229Y514817D02*
G03X948243Y514234I281J-285D01*
G02X946243I-1000J-1120D01*
G03X946257Y514817I-267J298D01*
G02X948229I986J997D01*
G37*
G36*
G01X930797D02*
G03X930811Y514234I281J-285D01*
G02X928811I-1000J-1120D01*
G03X928825Y514817I-267J298D01*
G02X930797I986J997D01*
G37*
G36*
G01X924511Y514778D02*
G03X924538Y514217I298J-267D01*
G02X922457Y514177I-1020J-1103D01*
G03X922461Y514738I-283J283D01*
G02X924511Y514778I1006J976D01*
G37*
G36*
G01X918111Y514817D02*
G03X918125Y514234I281J-285D01*
G02X916125I-1000J-1120D01*
G03X916139Y514817I-267J298D01*
G02X918111I986J997D01*
G37*
G36*
G01X911418D02*
G03X911432Y514234I281J-285D01*
G02X909432I-1000J-1120D01*
G03X909446Y514817I-267J298D01*
G02X911418I986J997D01*
G37*
G36*
G01X893986D02*
G03X894000Y514234I281J-285D01*
G02X892000I-1000J-1120D01*
G03X892014Y514817I-267J298D01*
G02X893986I986J997D01*
G37*
G36*
G01X887700Y514778D02*
G03X887727Y514217I298J-267D01*
G02X885646Y514177I-1020J-1103D01*
G03X885650Y514738I-283J283D01*
G02X887700Y514778I1006J976D01*
G37*
G36*
G01X881300Y514817D02*
G03X881314Y514234I281J-285D01*
G02X879314I-1000J-1120D01*
G03X879328Y514817I-267J298D01*
G02X881300I986J997D01*
G37*
G36*
G01X874607D02*
G03X874621Y514234I281J-285D01*
G02X872621I-1000J-1120D01*
G03X872635Y514817I-267J298D01*
G02X874607I986J997D01*
G37*
G36*
G01X857175D02*
G03X857189Y514234I281J-285D01*
G02X855189I-1000J-1120D01*
G03X855203Y514817I-267J298D01*
G02X857175I986J997D01*
G37*
G36*
G01X850889Y514778D02*
G03X850916Y514217I298J-267D01*
G02X848835Y514177I-1020J-1103D01*
G03X848839Y514738I-283J283D01*
G02X850889Y514778I1006J976D01*
G37*
G36*
G01X844489Y514817D02*
G03X844503Y514234I281J-285D01*
G02X842503I-1000J-1120D01*
G03X842517Y514817I-267J298D01*
G02X844489I986J997D01*
G37*
G36*
G01X837796D02*
G03X837810Y514234I281J-285D01*
G02X835810I-1000J-1120D01*
G03X835824Y514817I-267J298D01*
G02X837796I986J997D01*
G37*
G36*
G01X820384Y514787D02*
G03X820399Y514216I287J-278D01*
G02X818357I-1021J-1102D01*
G03X818372Y514787I-272J293D01*
G02X820384I1006J977D01*
G37*
G36*
G01X814078Y514778D02*
G03X814105Y514217I298J-267D01*
G02X812024Y514177I-1020J-1103D01*
G03X812028Y514738I-283J283D01*
G02X814078Y514778I1006J976D01*
G37*
G36*
G01X807678Y514817D02*
G03X807692Y514234I281J-285D01*
G02X805692I-1000J-1120D01*
G03X805706Y514817I-267J298D01*
G02X807678I986J997D01*
G37*
G36*
G01X800985D02*
G03X800999Y514234I281J-285D01*
G02X798999I-1000J-1120D01*
G03X799013Y514817I-267J298D01*
G02X800985I986J997D01*
G37*
G36*
G01X783553D02*
G03X783567Y514234I281J-285D01*
G02X781567I-1000J-1120D01*
G03X781581Y514817I-267J298D01*
G02X783553I986J997D01*
G37*
G36*
G01X777267Y514778D02*
G03X777294Y514217I298J-267D01*
G02X775213Y514177I-1020J-1103D01*
G03X775217Y514738I-283J283D01*
G02X777267Y514778I1006J976D01*
G37*
G36*
G01X1120536Y514487D02*
G03Y513941I292J-273D01*
G02X1118344I-1096J-1027D01*
G03Y514487I-292J273D01*
G02X1118399Y516597I1096J1027D01*
G03X1118415Y517158I-277J289D01*
G02X1120465I1025J956D01*
G03X1120481Y516597I293J-272D01*
G02X1120536Y514487I-1041J-1083D01*
G37*
G36*
G01X829395D02*
G03Y513941I292J-273D01*
G02X827203I-1096J-1027D01*
G03Y514487I-292J273D01*
G02X827258Y516597I1096J1027D01*
G03X827274Y517158I-277J289D01*
G02X829324I1025J956D01*
G03X829340Y516597I293J-272D01*
G02X829395Y514487I-1041J-1083D01*
G37*
G36*
G01X1098802Y513991D02*
G03X1098590Y513435I144J-373D01*
G02X1096841Y514103I-1247J-641D01*
G03X1097053Y514659I-144J373D01*
G02X1098802Y513991I1247J641D01*
G37*
G36*
G01X1297393Y509678D02*
G03X1296867I-263J-302D01*
G02X1294831Y511885I-986J1133D01*
G03X1294848Y512440I-279J286D01*
G02X1295037Y514635I1112J1010D01*
G03Y515265I-246J315D01*
G02Y517635I923J1185D01*
G03Y518265I-246J315D01*
G02X1296947Y520582I923J1185D01*
G03X1297473I263J302D01*
G02X1299383Y518265I987J-1132D01*
G03Y517635I246J-315D01*
G02Y515265I-923J-1185D01*
G03Y514635I246J-315D01*
G02X1299509Y512375I-923J-1185D01*
G03X1299492Y511820I279J-286D01*
G02X1297393Y509678I-1112J-1010D01*
G37*
G36*
G01X1230814Y511743D02*
G03X1230795Y511136I251J-312D01*
G02X1228923Y511151I-944J-1036D01*
G03X1228914Y511759I-265J300D01*
G02X1228778Y513941I960J1155D01*
G03Y514487I-292J273D01*
G02X1228833Y516597I1096J1027D01*
G03X1228849Y517158I-277J289D01*
G02X1230899I1025J956D01*
G03X1230915Y516597I293J-272D01*
G02X1230970Y514487I-1041J-1083D01*
G03Y513941I292J-273D01*
G02X1230814Y511743I-1096J-1027D01*
G37*
G36*
G01X1194003D02*
G03X1193984Y511136I251J-312D01*
G02X1192112Y511151I-944J-1036D01*
G03X1192103Y511759I-265J300D01*
G02X1191967Y513941I960J1155D01*
G03Y514487I-292J273D01*
G02X1192022Y516597I1096J1027D01*
G03X1192038Y517158I-277J289D01*
G02X1194088I1025J956D01*
G03X1194104Y516597I293J-272D01*
G02X1194159Y514487I-1041J-1083D01*
G03Y513941I292J-273D01*
G02X1194003Y511743I-1096J-1027D01*
G37*
G36*
G01X1157192D02*
G03X1157173Y511136I251J-312D01*
G02X1155301Y511151I-944J-1036D01*
G03X1155292Y511759I-265J300D01*
G02X1155156Y513941I960J1155D01*
G03Y514487I-292J273D01*
G02X1155211Y516597I1096J1027D01*
G03X1155227Y517158I-277J289D01*
G02X1157277I1025J956D01*
G03X1157293Y516597I293J-272D01*
G02X1157348Y514487I-1041J-1083D01*
G03Y513941I292J-273D01*
G02X1157192Y511743I-1096J-1027D01*
G37*
G36*
G01X939672D02*
G03X939653Y511136I251J-312D01*
G02X937781Y511151I-944J-1036D01*
G03X937772Y511759I-265J300D01*
G02X937636Y513941I960J1155D01*
G03Y514487I-292J273D01*
G02X937691Y516597I1096J1027D01*
G03X937707Y517158I-277J289D01*
G02X939757I1025J956D01*
G03X939773Y516597I293J-272D01*
G02X939828Y514487I-1041J-1083D01*
G03Y513941I292J-273D01*
G02X939672Y511743I-1096J-1027D01*
G37*
G36*
G01X902861D02*
G03X902842Y511136I251J-312D01*
G02X900970Y511151I-944J-1036D01*
G03X900961Y511759I-265J300D01*
G02X900825Y513941I960J1155D01*
G03Y514487I-292J273D01*
G02X900880Y516597I1096J1027D01*
G03X900896Y517158I-277J289D01*
G02X902946I1025J956D01*
G03X902962Y516597I293J-272D01*
G02X903017Y514487I-1041J-1083D01*
G03Y513941I292J-273D01*
G02X902861Y511743I-1096J-1027D01*
G37*
G36*
G01X866050D02*
G03X866031Y511136I251J-312D01*
G02X864159Y511151I-944J-1036D01*
G03X864150Y511759I-265J300D01*
G02X864014Y513941I960J1155D01*
G03Y514487I-292J273D01*
G02X864069Y516597I1096J1027D01*
G03X864085Y517158I-277J289D01*
G02X866135I1025J956D01*
G03X866151Y516597I293J-272D01*
G02X866206Y514487I-1041J-1083D01*
G03Y513941I292J-273D01*
G02X866050Y511743I-1096J-1027D01*
G37*
G36*
G01X792428D02*
G03X792409Y511136I251J-312D01*
G02X790537Y511151I-944J-1036D01*
G03X790528Y511759I-265J300D01*
G02X790392Y513941I960J1155D01*
G03Y514487I-292J273D01*
G02X790447Y516597I1096J1027D01*
G03X790463Y517158I-277J289D01*
G02X792513I1025J956D01*
G03X792529Y516597I293J-272D01*
G02X792584Y514487I-1041J-1083D01*
G03Y513941I292J-273D01*
G02X792428Y511743I-1096J-1027D01*
G37*
G36*
G01X1225814Y511616D02*
G03X1225799Y511055I277J-288D01*
G02X1223749I-1025J-957D01*
G03X1223734Y511616I-292J273D01*
G02X1223678Y513727I1040J1084D01*
G03Y514273I-292J273D01*
G02X1223723Y516373I1096J1027D01*
G03X1223733Y516935I-280J286D01*
G02X1225784Y516953I1017J965D01*
G03X1225805Y516392I295J-270D01*
G02X1225870Y514273I-1031J-1092D01*
G03Y513727I292J-273D01*
G02X1225814Y511616I-1096J-1027D01*
G37*
G36*
G01X1189003D02*
G03X1188988Y511055I277J-288D01*
G02X1186938I-1025J-957D01*
G03X1186923Y511616I-292J273D01*
G02X1186867Y513727I1040J1084D01*
G03Y514273I-292J273D01*
G02X1186912Y516373I1096J1027D01*
G03X1186922Y516935I-280J286D01*
G02X1188973Y516953I1017J965D01*
G03X1188994Y516392I295J-270D01*
G02X1189059Y514273I-1031J-1092D01*
G03Y513727I292J-273D01*
G02X1189003Y511616I-1096J-1027D01*
G37*
G36*
G01X1152192D02*
G03X1152177Y511055I277J-288D01*
G02X1150127I-1025J-957D01*
G03X1150112Y511616I-292J273D01*
G02X1150056Y513727I1040J1084D01*
G03Y514273I-292J273D01*
G02X1150101Y516373I1096J1027D01*
G03X1150111Y516935I-280J286D01*
G02X1152162Y516953I1017J965D01*
G03X1152183Y516392I295J-270D01*
G02X1152248Y514273I-1031J-1092D01*
G03Y513727I292J-273D01*
G02X1152192Y511616I-1096J-1027D01*
G37*
G36*
G01X1115380D02*
G03X1115365Y511055I277J-288D01*
G02X1113315I-1025J-957D01*
G03X1113300Y511616I-292J273D01*
G02X1113244Y513727I1040J1084D01*
G03Y514273I-292J273D01*
G02X1113289Y516373I1096J1027D01*
G03X1113299Y516935I-280J286D01*
G02X1115350Y516953I1017J965D01*
G03X1115371Y516392I295J-270D01*
G02X1115436Y514273I-1031J-1092D01*
G03Y513727I292J-273D01*
G02X1115380Y511616I-1096J-1027D01*
G37*
G36*
G01X934672D02*
G03X934657Y511055I277J-288D01*
G02X932607I-1025J-957D01*
G03X932592Y511616I-292J273D01*
G02X932536Y513727I1040J1084D01*
G03Y514273I-292J273D01*
G02X932581Y516373I1096J1027D01*
G03X932591Y516935I-280J286D01*
G02X934642Y516953I1017J965D01*
G03X934663Y516392I295J-270D01*
G02X934728Y514273I-1031J-1092D01*
G03Y513727I292J-273D01*
G02X934672Y511616I-1096J-1027D01*
G37*
G36*
G01X897861D02*
G03X897846Y511055I277J-288D01*
G02X895796I-1025J-957D01*
G03X895781Y511616I-292J273D01*
G02X895725Y513727I1040J1084D01*
G03Y514273I-292J273D01*
G02X895770Y516373I1096J1027D01*
G03X895780Y516935I-280J286D01*
G02X897831Y516953I1017J965D01*
G03X897852Y516392I295J-270D01*
G02X897917Y514273I-1031J-1092D01*
G03Y513727I292J-273D01*
G02X897861Y511616I-1096J-1027D01*
G37*
G36*
G01X861050D02*
G03X861035Y511055I277J-288D01*
G02X858985I-1025J-957D01*
G03X858970Y511616I-292J273D01*
G02X858914Y513727I1040J1084D01*
G03Y514273I-292J273D01*
G02X858959Y516373I1096J1027D01*
G03X858969Y516935I-280J286D01*
G02X861020Y516953I1017J965D01*
G03X861041Y516392I295J-270D01*
G02X861106Y514273I-1031J-1092D01*
G03Y513727I292J-273D01*
G02X861050Y511616I-1096J-1027D01*
G37*
G36*
G01X824239D02*
G03X824224Y511055I277J-288D01*
G02X822174I-1025J-957D01*
G03X822159Y511616I-292J273D01*
G02X822103Y513727I1040J1084D01*
G03Y514273I-292J273D01*
G02X822148Y516373I1096J1027D01*
G03X822158Y516935I-280J286D01*
G02X824209Y516953I1017J965D01*
G03X824230Y516392I295J-270D01*
G02X824295Y514273I-1031J-1092D01*
G03Y513727I292J-273D01*
G02X824239Y511616I-1096J-1027D01*
G37*
G36*
G01X787428D02*
G03X787413Y511055I277J-288D01*
G02X785363I-1025J-957D01*
G03X785348Y511616I-292J273D01*
G02X785292Y513727I1040J1084D01*
G03Y514273I-292J273D01*
G02X785337Y516373I1096J1027D01*
G03X785347Y516935I-280J286D01*
G02X787398Y516953I1017J965D01*
G03X787419Y516392I295J-270D01*
G02X787484Y514273I-1031J-1092D01*
G03Y513727I292J-273D01*
G02X787428Y511616I-1096J-1027D01*
G37*
G36*
G01X1012788Y509075D02*
G03X1012211I-288J-277D01*
G02Y511153I-1085J1039D01*
G03X1012788I288J277D01*
G02Y509075I1085J-1039D01*
G37*
G36*
G01X1256445Y611927D02*
G02X1253793Y611931I-1325J707D01*
G03X1253088Y611936I-354J-187D01*
G02X1253098Y613360I-1317J721D01*
G03X1253803Y613355I354J187D01*
G02X1256435Y613359I1317J-721D01*
G03X1257139Y613364I351J193D01*
G02X1259786Y613371I1325J-707D01*
G03X1260489I352J190D01*
G02X1263132I1322J-714D01*
G03X1263836I352J191D01*
G02Y611943I1321J-714D01*
G03X1263132I-352J-191D01*
G02X1260489I-1322J714D01*
G03X1259786I-351J-190D01*
G02X1257149Y611932I-1322J714D01*
G03X1256445Y611927I-351J-193D01*
G37*
G36*
G01X1012148Y611528D02*
G02Y612956I-1322J714D01*
G03X1012851I352J190D01*
G02Y611528I1322J-714D01*
G03X1012148I-352J-190D01*
G37*
G36*
G01X1022807Y612046D02*
G02X1021800Y610774I393J-1346D01*
G03X1021274Y611175I-399J21D01*
G02X1022296Y612465I-474J1425D01*
G03X1022807Y612046I398J-35D01*
G37*
G36*
G01X722273Y608773D02*
G02Y610327I-1167J777D01*
G03X722939I333J222D01*
G02X724780Y610779I1167J-777D01*
G03X725369Y611075I193J351D01*
G02X727949Y611902I1488J-204D01*
G03X728530Y611900I291J274D01*
G02X730762Y611834I1086J-1037D01*
G03X731385Y611850I305J259D01*
G02X731471Y610048I1115J-850D01*
G03X730849Y610005I-294J-271D01*
G02X728524Y609832I-1233J858D01*
G03X727943Y609834I-291J-274D01*
G02X726086Y609582I-1086J1037D01*
G03X725487Y609308I-205J-343D01*
G02X722939Y608773I-1381J242D01*
G03X722273I-333J-222D01*
G37*
G36*
G01X1012148Y603900D02*
G02Y605328I-1322J714D01*
G03X1012851I352J190D01*
G02Y603900I1322J-714D01*
G03X1012148I-352J-190D01*
G37*
G36*
G01X1265461Y605947D02*
G02X1263831Y603771I-304J-1471D01*
G03X1263127Y603776I-353J-188D01*
G02X1260489Y603785I-1317J723D01*
G03X1259786I-351J-190D01*
G02Y605213I-1322J714D01*
G03X1260489I352J190D01*
G02X1261997Y605989I1321J-714D01*
G03X1262435Y606478I49J397D01*
G02X1265155Y606441I1365J322D01*
G03X1265461Y605947I387J-102D01*
G37*
G36*
G01X724326Y599288D02*
G02X723867Y597660I847J-1117D01*
G03X723253Y597833I-372J-146D01*
G02X723712Y599461I-847J1117D01*
G03X724326Y599288I372J146D01*
G37*
G36*
G01X1012894Y592928D02*
G02Y594356I-1322J714D01*
G03X1013597I352J190D01*
G02Y592928I1322J-714D01*
G03X1012894I-352J-190D01*
G37*
G36*
G01X1259786Y592885D02*
G02X1257143Y592883I-1322J714D01*
G03X1256440Y592884I-352J-190D01*
G02X1256441Y594316I-1320J717D01*
G03X1257144Y594315I352J190D01*
G02X1259786Y594313I1320J-716D01*
G03X1260489I352J190D01*
G02X1263132I1322J-714D01*
G03X1263836I352J191D01*
G02X1266256Y594623I1321J-714D01*
G03X1266826Y594608I292J273D01*
G02X1268811Y594571I974J-1008D01*
G03X1269389I289J277D01*
G02Y592629I1011J-971D01*
G03X1268811I-289J-277D01*
G02X1266827Y592591I-1011J971D01*
G03X1266256Y592576I-278J-288D01*
G02X1263836Y592885I-1099J1023D01*
G03X1263132I-352J-191D01*
G02X1260489I-1322J714D01*
G03X1259786I-351J-190D01*
G37*
G36*
G01Y585043D02*
G02Y586471I-1322J714D01*
G03X1260489I352J190D01*
G02X1263132I1322J-714D01*
G03X1263836I352J191D01*
G02Y585043I1321J-714D01*
G03X1263132I-352J-191D01*
G02X1260489I-1322J714D01*
G03X1259786I-351J-190D01*
G37*
G36*
G01X764935Y585425D02*
G02X763900Y586633I-1485J-225D01*
G03X764415Y587075I120J382D01*
G02X765450Y585867I1485J225D01*
G03X764935Y585425I-120J-382D01*
G37*
G36*
G01X1283696Y582027D02*
G02X1281504I-1096J-1027D01*
G03Y582573I-292J273D01*
G02X1282512Y585099I1096J1027D01*
G03X1282793Y585758I-23J399D01*
G02X1284655Y584287I4610J3921D01*
G03X1284079Y583861I-182J-356D01*
G02X1283696Y582573I-1479J-261D01*
G03Y582027I292J-273D01*
G37*
G36*
G01X1012148Y574028D02*
G02Y575456I-1322J714D01*
G03X1012851I352J190D01*
G02Y574028I1322J-714D01*
G03X1012148I-352J-190D01*
G37*
G36*
G01X1267071Y575431D02*
G02X1266696Y573582I829J-1131D01*
G03X1266101Y573689I-344J-204D01*
G02X1263836Y574143I-944J1168D01*
G03X1263132I-352J-191D01*
G02X1260489I-1322J714D01*
G03X1259786I-351J-190D01*
G02X1257149Y574132I-1322J714D01*
G03X1256445Y574127I-351J-193D01*
G02X1253793Y574131I-1325J707D01*
G03X1253088Y574136I-354J-187D01*
G02X1253098Y575560I-1317J721D01*
G03X1253803Y575555I354J187D01*
G02X1256435Y575559I1317J-721D01*
G03X1257139Y575564I351J193D01*
G02X1259786Y575571I1325J-707D01*
G03X1260489I352J190D01*
G02X1263132I1322J-714D01*
G03X1263836I352J191D01*
G02X1266482Y575565I1321J-714D01*
G03X1267071Y575431I353J188D01*
G37*
G36*
G01X1012148Y566100D02*
G02Y567528I-1322J714D01*
G03X1012851I352J190D01*
G02Y566100I1322J-714D01*
G03X1012148I-352J-190D01*
G37*
G36*
G01X1263841Y567399D02*
G02X1263831Y565971I1316J-723D01*
G03X1263127Y565976I-353J-188D01*
G02X1260489Y565985I-1317J723D01*
G03X1259786I-351J-190D01*
G02Y567413I-1322J714D01*
G03X1260489I352J190D01*
G02X1263137Y567404I1322J-714D01*
G03X1263841Y567399I353J188D01*
G37*
G36*
G01X1291919Y574784D02*
G02X1290161Y576142I-4516J-4029D01*
G03X1290731Y576594I182J356D01*
G02X1290690Y577037I1459J358D01*
G03X1290291Y577460I-399J23D01*
G02X1291792Y578877I1J1502D01*
G03X1292191Y578454I399J-23D01*
G02X1292212Y575450I-1J-1502D01*
G03X1291919Y574784I5J-400D01*
G37*
G36*
G01X1286807Y560474D02*
G02X1286125Y562315I-1407J526D01*
G03X1286693Y562526I193J350D01*
G02X1288836Y563309I1407J-526D01*
G03X1289425Y563583I196J349D01*
G02X1290164Y561991I1475J-283D01*
G03X1289575Y561717I-196J-349D01*
G02X1287375Y560685I-1475J283D01*
G03X1286807Y560474I-193J-350D01*
G37*
G36*
G01X1012209Y555058D02*
G02Y556626I-1281J784D01*
G03X1012892I341J208D01*
G02Y555058I1281J-784D01*
G03X1012209I-342J-208D01*
G37*
G36*
G01X1259786Y555085D02*
G02Y556513I-1322J714D01*
G03X1260489I352J190D01*
G02X1263132I1322J-714D01*
G03X1263836I352J191D01*
G02Y555085I1321J-714D01*
G03X1263132I-352J-191D01*
G02X1260489I-1322J714D01*
G03X1259786I-351J-190D01*
G37*
G36*
G01X1250462Y556536D02*
G02X1250437Y555108I1309J-737D01*
G03X1249734Y555120I-355J-184D01*
G02X1249759Y556548I-1309J737D01*
G03X1250462Y556536I355J184D01*
G37*
G36*
G01X1259786Y547243D02*
G02Y548671I-1322J714D01*
G03X1260489I352J190D01*
G02X1263132I1322J-714D01*
G03X1263836I352J191D01*
G02Y547243I1321J-714D01*
G03X1263132I-352J-191D01*
G02X1260489I-1322J714D01*
G03X1259786I-351J-190D01*
G37*
G36*
G01X1279078Y546695D02*
G02X1277835Y545452I240J-1483D01*
G03X1277377Y545910I-395J63D01*
G02X1278620Y547153I-240J1483D01*
G03X1279078Y546695I395J-63D01*
G37*
G36*
G01X1256445Y536327D02*
G02X1253793Y536331I-1325J707D01*
G03X1253088Y536336I-354J-187D01*
G02X1253098Y537760I-1317J721D01*
G03X1253803Y537755I354J187D01*
G02X1256435Y537759I1317J-721D01*
G03X1257139Y537764I351J193D01*
G02X1259786Y537771I1325J-707D01*
G03X1260489I352J190D01*
G02X1263132I1322J-714D01*
G03X1263836I352J191D01*
G02Y536343I1321J-714D01*
G03X1263132I-352J-191D01*
G02X1260489I-1322J714D01*
G03X1259786I-351J-190D01*
G02X1257149Y536332I-1322J714D01*
G03X1256445Y536327I-351J-193D01*
G37*
G36*
G01X1099019Y532137D02*
G02X1097127Y532239I-1002J-981D01*
G03X1097159Y532828I-254J309D01*
G02X1097290Y534909I1001J982D01*
G03X1097264Y535556I-248J314D01*
G02X1099202Y537507I776J1168D01*
G03X1099900Y537568I332J223D01*
G02X1100019Y536215I1281J-569D01*
G03X1099321Y536154I-332J-223D01*
G02X1098910Y535623I-1282J568D01*
G03X1098936Y534976I248J-314D01*
G02X1099051Y532726I-776J-1168D01*
G03X1099019Y532137I254J-309D01*
G37*
G36*
G01X1263841Y529599D02*
G02X1263831Y528171I1316J-723D01*
G03X1263127Y528176I-353J-188D01*
G02X1260489Y528185I-1317J723D01*
G03X1259786I-351J-190D01*
G02Y529613I-1322J714D01*
G03X1260489I352J190D01*
G02X1263137Y529604I1322J-714D01*
G03X1263841Y529599I353J188D01*
G37*
G36*
G01X1259786Y517285D02*
G02X1257143Y517283I-1322J714D01*
G03X1256440Y517284I-352J-190D01*
G02X1256441Y518716I-1320J717D01*
G03X1257144Y518715I352J190D01*
G02X1259786Y518713I1320J-716D01*
G03X1260489I352J190D01*
G02X1263132I1322J-714D01*
G03X1263836I352J191D01*
G02Y517285I1321J-714D01*
G03X1263132I-352J-191D01*
G02X1260489I-1322J714D01*
G03X1259786I-351J-190D01*
G37*
G36*
G01X1273365Y511124D02*
G02X1273199Y509634I1211J-889D01*
G03X1272511Y509711I-366J-160D01*
G02X1272677Y511201I-1211J889D01*
G03X1273365Y511124I366J160D01*
G37*
G36*
G01X1253094Y509445D02*
G02X1253093Y510870I-1323J712D01*
G03X1253797I352J190D01*
G02X1256441Y510874I1323J-712D01*
G03X1257144Y510873I352J190D01*
G02X1259786Y510871I1320J-716D01*
G03X1260489I352J190D01*
G02X1263132I1322J-714D01*
G03X1263836I352J191D01*
G02Y509443I1321J-714D01*
G03X1263132I-352J-191D01*
G02X1260489I-1322J714D01*
G03X1259786I-351J-190D01*
G02X1257143Y509441I-1322J714D01*
G03X1256440Y509442I-352J-190D01*
G02X1253798Y509445I-1320J716D01*
G03X1253094I-352J-190D01*
G37*
G36*
G01X1246064Y89417D02*
G03X1246078Y88834I281J-285D01*
G02X1244078I-1000J-1120D01*
G03X1244092Y89417I-267J298D01*
G02X1246064I986J997D01*
G37*
G36*
G01X1239371D02*
G03X1239385Y88834I281J-285D01*
G02X1237385I-1000J-1120D01*
G03X1237399Y89417I-267J298D01*
G02X1239371I986J997D01*
G37*
G36*
G01X1221939D02*
G03X1221953Y88834I281J-285D01*
G02X1219953I-1000J-1120D01*
G03X1219967Y89417I-267J298D01*
G02X1221939I986J997D01*
G37*
G36*
G01X1209253D02*
G03X1209267Y88834I281J-285D01*
G02X1207267I-1000J-1120D01*
G03X1207281Y89417I-267J298D01*
G02X1209253I986J997D01*
G37*
G36*
G01X1202560D02*
G03X1202574Y88834I281J-285D01*
G02X1200574I-1000J-1120D01*
G03X1200588Y89417I-267J298D01*
G02X1202560I986J997D01*
G37*
G36*
G01X1185128D02*
G03X1185142Y88834I281J-285D01*
G02X1183142I-1000J-1120D01*
G03X1183156Y89417I-267J298D01*
G02X1185128I986J997D01*
G37*
G36*
G01X1178842Y89378D02*
G03X1178869Y88817I298J-267D01*
G02X1176788Y88777I-1020J-1103D01*
G03X1176792Y89338I-283J283D01*
G02X1178842Y89378I1006J976D01*
G37*
G36*
G01X1172442Y89417D02*
G03X1172456Y88834I281J-285D01*
G02X1170456I-1000J-1120D01*
G03X1170470Y89417I-267J298D01*
G02X1172442I986J997D01*
G37*
G36*
G01X1165749D02*
G03X1165763Y88834I281J-285D01*
G02X1163763I-1000J-1120D01*
G03X1163777Y89417I-267J298D01*
G02X1165749I986J997D01*
G37*
G36*
G01X1148317D02*
G03X1148331Y88834I281J-285D01*
G02X1146331I-1000J-1120D01*
G03X1146345Y89417I-267J298D01*
G02X1148317I986J997D01*
G37*
G36*
G01X1142031Y89378D02*
G03X1142058Y88817I298J-267D01*
G02X1139977Y88777I-1020J-1103D01*
G03X1139981Y89338I-283J283D01*
G02X1142031Y89378I1006J976D01*
G37*
G36*
G01X1135631Y89417D02*
G03X1135645Y88834I281J-285D01*
G02X1133645I-1000J-1120D01*
G03X1133659Y89417I-267J298D01*
G02X1135631I986J997D01*
G37*
G36*
G01X1128938D02*
G03X1128952Y88834I281J-285D01*
G02X1126952I-1000J-1120D01*
G03X1126966Y89417I-267J298D01*
G02X1128938I986J997D01*
G37*
G36*
G01X1111545Y89358D02*
G03X1111561Y88797I293J-272D01*
G02X1109479I-1041J-1083D01*
G03X1109495Y89358I-277J289D01*
G02X1111545I1025J956D01*
G37*
G36*
G01X1105220Y89378D02*
G03X1105247Y88817I298J-267D01*
G02X1103166Y88777I-1020J-1103D01*
G03X1103170Y89338I-283J283D01*
G02X1105220Y89378I1006J976D01*
G37*
G36*
G01X954890Y89435D02*
G03X954915Y88853I286J-279D01*
G02X952915Y88816I-979J-1139D01*
G03X952919Y89399I-272J293D01*
G02X954890Y89435I967J1015D01*
G37*
G36*
G01X948229Y89417D02*
G03X948243Y88834I281J-285D01*
G02X946243I-1000J-1120D01*
G03X946257Y89417I-267J298D01*
G02X948229I986J997D01*
G37*
G36*
G01X930797D02*
G03X930811Y88834I281J-285D01*
G02X928811I-1000J-1120D01*
G03X928825Y89417I-267J298D01*
G02X930797I986J997D01*
G37*
G36*
G01X924511Y89378D02*
G03X924538Y88817I298J-267D01*
G02X922457Y88777I-1020J-1103D01*
G03X922461Y89338I-283J283D01*
G02X924511Y89378I1006J976D01*
G37*
G36*
G01X918111Y89417D02*
G03X918125Y88834I281J-285D01*
G02X916125I-1000J-1120D01*
G03X916139Y89417I-267J298D01*
G02X918111I986J997D01*
G37*
G36*
G01X911418D02*
G03X911432Y88834I281J-285D01*
G02X909432I-1000J-1120D01*
G03X909446Y89417I-267J298D01*
G02X911418I986J997D01*
G37*
G36*
G01X893986D02*
G03X894000Y88834I281J-285D01*
G02X892000I-1000J-1120D01*
G03X892014Y89417I-267J298D01*
G02X893986I986J997D01*
G37*
G36*
G01X887700Y89378D02*
G03X887727Y88817I298J-267D01*
G02X885646Y88777I-1020J-1103D01*
G03X885650Y89338I-283J283D01*
G02X887700Y89378I1006J976D01*
G37*
G36*
G01X881300Y89417D02*
G03X881314Y88834I281J-285D01*
G02X879314I-1000J-1120D01*
G03X879328Y89417I-267J298D01*
G02X881300I986J997D01*
G37*
G36*
G01X874607D02*
G03X874621Y88834I281J-285D01*
G02X872621I-1000J-1120D01*
G03X872635Y89417I-267J298D01*
G02X874607I986J997D01*
G37*
G36*
G01X857175D02*
G03X857189Y88834I281J-285D01*
G02X855189I-1000J-1120D01*
G03X855203Y89417I-267J298D01*
G02X857175I986J997D01*
G37*
G36*
G01X850889Y89378D02*
G03X850916Y88817I298J-267D01*
G02X848835Y88777I-1020J-1103D01*
G03X848839Y89338I-283J283D01*
G02X850889Y89378I1006J976D01*
G37*
G36*
G01X844489Y89417D02*
G03X844503Y88834I281J-285D01*
G02X842503I-1000J-1120D01*
G03X842517Y89417I-267J298D01*
G02X844489I986J997D01*
G37*
G36*
G01X837796D02*
G03X837810Y88834I281J-285D01*
G02X835810I-1000J-1120D01*
G03X835824Y89417I-267J298D01*
G02X837796I986J997D01*
G37*
G36*
G01X820384Y89387D02*
G03X820399Y88816I287J-278D01*
G02X818357I-1021J-1102D01*
G03X818372Y89387I-272J293D01*
G02X820384I1006J977D01*
G37*
G36*
G01X814078Y89378D02*
G03X814105Y88817I298J-267D01*
G02X812024Y88777I-1020J-1103D01*
G03X812028Y89338I-283J283D01*
G02X814078Y89378I1006J976D01*
G37*
G36*
G01X807678Y89417D02*
G03X807692Y88834I281J-285D01*
G02X805692I-1000J-1120D01*
G03X805706Y89417I-267J298D01*
G02X807678I986J997D01*
G37*
G36*
G01X800985D02*
G03X800999Y88834I281J-285D01*
G02X798999I-1000J-1120D01*
G03X799013Y89417I-267J298D01*
G02X800985I986J997D01*
G37*
G36*
G01X783553D02*
G03X783567Y88834I281J-285D01*
G02X781567I-1000J-1120D01*
G03X781581Y89417I-267J298D01*
G02X783553I986J997D01*
G37*
G36*
G01X777267Y89378D02*
G03X777294Y88817I298J-267D01*
G02X775213Y88777I-1020J-1103D01*
G03X775217Y89338I-283J283D01*
G02X777267Y89378I1006J976D01*
G37*
G36*
G01X1013737Y86483D02*
G03X1013148I-295J-271D01*
G02Y88517I-1105J1017D01*
G03X1013737I295J271D01*
G02Y86483I1105J-1017D01*
G37*
G36*
G01X1026077Y85390D02*
G03Y84864I302J-263D01*
G02X1023813I-1132J-987D01*
G03Y85390I-302J263D01*
G02X1026077I1132J987D01*
G37*
G36*
G01X1008351Y69924D02*
G03Y69346I277J-289D01*
G02X1006409I-971J-1011D01*
G03Y69924I-277J289D01*
G02X1008351I971J1011D01*
G37*
G36*
G01X958546Y69365D02*
G03X958532Y68789I270J-295D01*
G02X956590Y68837I-996J-987D01*
G03X956604Y69413I-270J295D01*
G02X958546Y69365I996J987D01*
G37*
G36*
G01X1225841Y67467D02*
G03X1225825Y66906I277J-289D01*
G02X1223775I-1025J-956D01*
G03X1223759Y67467I-293J272D01*
G02X1223712Y69585I1041J1083D01*
G03X1223706Y70142I-290J275D01*
G02X1223733Y72282I1068J1057D01*
G03X1223749Y72843I-277J289D01*
G02X1225799I1025J956D01*
G03X1225815Y72282I293J-272D01*
G02X1225862Y70164I-1041J-1083D01*
G03X1225868Y69607I290J-275D01*
G02X1225841Y67467I-1068J-1057D01*
G37*
G36*
G01X1189030D02*
G03X1189014Y66906I277J-289D01*
G02X1186964I-1025J-956D01*
G03X1186948Y67467I-293J272D01*
G02X1186901Y69585I1041J1083D01*
G03X1186895Y70142I-290J275D01*
G02X1186922Y72282I1068J1057D01*
G03X1186938Y72843I-277J289D01*
G02X1188988I1025J956D01*
G03X1189004Y72282I293J-272D01*
G02X1189051Y70164I-1041J-1083D01*
G03X1189057Y69607I290J-275D01*
G02X1189030Y67467I-1068J-1057D01*
G37*
G36*
G01X1152219D02*
G03X1152203Y66906I277J-289D01*
G02X1150153I-1025J-956D01*
G03X1150137Y67467I-293J272D01*
G02X1150090Y69585I1041J1083D01*
G03X1150084Y70142I-290J275D01*
G02X1150111Y72282I1068J1057D01*
G03X1150127Y72843I-277J289D01*
G02X1152177I1025J956D01*
G03X1152193Y72282I293J-272D01*
G02X1152240Y70164I-1041J-1083D01*
G03X1152246Y69607I290J-275D01*
G02X1152219Y67467I-1068J-1057D01*
G37*
G36*
G01X1115407D02*
G03X1115391Y66906I277J-289D01*
G02X1113341I-1025J-956D01*
G03X1113325Y67467I-293J272D01*
G02X1113278Y69585I1041J1083D01*
G03X1113272Y70142I-290J275D01*
G02X1113299Y72282I1068J1057D01*
G03X1113315Y72843I-277J289D01*
G02X1115365I1025J956D01*
G03X1115381Y72282I293J-272D01*
G02X1115428Y70164I-1041J-1083D01*
G03X1115434Y69607I290J-275D01*
G02X1115407Y67467I-1068J-1057D01*
G37*
G36*
G01X934699D02*
G03X934683Y66906I277J-289D01*
G02X932633I-1025J-956D01*
G03X932617Y67467I-293J272D01*
G02X932570Y69585I1041J1083D01*
G03X932564Y70142I-290J275D01*
G02X932591Y72282I1068J1057D01*
G03X932607Y72843I-277J289D01*
G02X934657I1025J956D01*
G03X934673Y72282I293J-272D01*
G02X934720Y70164I-1041J-1083D01*
G03X934726Y69607I290J-275D01*
G02X934699Y67467I-1068J-1057D01*
G37*
G36*
G01X897888D02*
G03X897872Y66906I277J-289D01*
G02X895822I-1025J-956D01*
G03X895806Y67467I-293J272D01*
G02X895759Y69585I1041J1083D01*
G03X895753Y70142I-290J275D01*
G02X895780Y72282I1068J1057D01*
G03X895796Y72843I-277J289D01*
G02X897846I1025J956D01*
G03X897862Y72282I293J-272D01*
G02X897909Y70164I-1041J-1083D01*
G03X897915Y69607I290J-275D01*
G02X897888Y67467I-1068J-1057D01*
G37*
G36*
G01X861077D02*
G03X861061Y66906I277J-289D01*
G02X859011I-1025J-956D01*
G03X858995Y67467I-293J272D01*
G02X858948Y69585I1041J1083D01*
G03X858942Y70142I-290J275D01*
G02X858969Y72282I1068J1057D01*
G03X858985Y72843I-277J289D01*
G02X861035I1025J956D01*
G03X861051Y72282I293J-272D01*
G02X861098Y70164I-1041J-1083D01*
G03X861104Y69607I290J-275D01*
G02X861077Y67467I-1068J-1057D01*
G37*
G36*
G01X824266D02*
G03X824250Y66906I277J-289D01*
G02X822200I-1025J-956D01*
G03X822184Y67467I-293J272D01*
G02X822137Y69585I1041J1083D01*
G03X822131Y70142I-290J275D01*
G02X822158Y72282I1068J1057D01*
G03X822174Y72843I-277J289D01*
G02X824224I1025J956D01*
G03X824240Y72282I293J-272D01*
G02X824287Y70164I-1041J-1083D01*
G03X824293Y69607I290J-275D01*
G02X824266Y67467I-1068J-1057D01*
G37*
G36*
G01X787455D02*
G03X787439Y66906I277J-289D01*
G02X785389I-1025J-956D01*
G03X785373Y67467I-293J272D01*
G02X785326Y69585I1041J1083D01*
G03X785320Y70142I-290J275D01*
G02X785347Y72282I1068J1057D01*
G03X785363Y72843I-277J289D01*
G02X787413I1025J956D01*
G03X787429Y72282I293J-272D01*
G02X787476Y70164I-1041J-1083D01*
G03X787482Y69607I290J-275D01*
G02X787455Y67467I-1068J-1057D01*
G37*
G36*
G01X1230919Y67261D02*
G03X1230906Y66699I278J-288D01*
G02X1228858Y66689I-1019J-963D01*
G03X1228840Y67250I-293J271D01*
G02X1228781Y69370I1034J1090D01*
G03Y69919I-291J274D01*
G02X1228844Y72043I1093J1031D01*
G03X1228865Y72604I-274J291D01*
G02X1230915Y72583I1035J946D01*
G03X1230925Y72022I290J-275D01*
G02X1230967Y69919I-1051J-1073D01*
G03Y69370I291J-274D01*
G02X1230919Y67261I-1093J-1030D01*
G37*
G36*
G01X1194108D02*
G03X1194095Y66699I278J-288D01*
G02X1192047Y66689I-1019J-963D01*
G03X1192029Y67250I-293J271D01*
G02X1191970Y69370I1034J1090D01*
G03Y69919I-291J274D01*
G02X1192033Y72043I1093J1031D01*
G03X1192054Y72604I-274J291D01*
G02X1194104Y72583I1035J946D01*
G03X1194114Y72022I290J-275D01*
G02X1194156Y69919I-1051J-1073D01*
G03Y69370I291J-274D01*
G02X1194108Y67261I-1093J-1030D01*
G37*
G36*
G01X1157297D02*
G03X1157284Y66699I278J-288D01*
G02X1155236Y66689I-1019J-963D01*
G03X1155218Y67250I-293J271D01*
G02X1155159Y69370I1034J1090D01*
G03Y69919I-291J274D01*
G02X1155222Y72043I1093J1031D01*
G03X1155243Y72604I-274J291D01*
G02X1157293Y72583I1035J946D01*
G03X1157303Y72022I290J-275D01*
G02X1157345Y69919I-1051J-1073D01*
G03Y69370I291J-274D01*
G02X1157297Y67261I-1093J-1030D01*
G37*
G36*
G01X1120485D02*
G03X1120472Y66699I278J-288D01*
G02X1118424Y66689I-1019J-963D01*
G03X1118406Y67250I-293J271D01*
G02X1118347Y69370I1034J1090D01*
G03Y69919I-291J274D01*
G02X1118410Y72043I1093J1031D01*
G03X1118431Y72604I-274J291D01*
G02X1120481Y72583I1035J946D01*
G03X1120491Y72022I290J-275D01*
G02X1120533Y69919I-1051J-1073D01*
G03Y69370I291J-274D01*
G02X1120485Y67261I-1093J-1030D01*
G37*
G36*
G01X939777D02*
G03X939764Y66699I278J-288D01*
G02X937716Y66689I-1019J-963D01*
G03X937698Y67250I-293J271D01*
G02X937639Y69370I1034J1090D01*
G03Y69919I-291J274D01*
G02X937702Y72043I1093J1031D01*
G03X937723Y72604I-274J291D01*
G02X939773Y72583I1035J946D01*
G03X939783Y72022I290J-275D01*
G02X939825Y69919I-1051J-1073D01*
G03Y69370I291J-274D01*
G02X939777Y67261I-1093J-1030D01*
G37*
G36*
G01X902966D02*
G03X902953Y66699I278J-288D01*
G02X900905Y66689I-1019J-963D01*
G03X900887Y67250I-293J271D01*
G02X900828Y69370I1034J1090D01*
G03Y69919I-291J274D01*
G02X900891Y72043I1093J1031D01*
G03X900912Y72604I-274J291D01*
G02X902962Y72583I1035J946D01*
G03X902972Y72022I290J-275D01*
G02X903014Y69919I-1051J-1073D01*
G03Y69370I291J-274D01*
G02X902966Y67261I-1093J-1030D01*
G37*
G36*
G01X866155D02*
G03X866142Y66699I278J-288D01*
G02X864094Y66689I-1019J-963D01*
G03X864076Y67250I-293J271D01*
G02X864017Y69370I1034J1090D01*
G03Y69919I-291J274D01*
G02X864080Y72043I1093J1031D01*
G03X864101Y72604I-274J291D01*
G02X866151Y72583I1035J946D01*
G03X866161Y72022I290J-275D01*
G02X866203Y69919I-1051J-1073D01*
G03Y69370I291J-274D01*
G02X866155Y67261I-1093J-1030D01*
G37*
G36*
G01X829344D02*
G03X829331Y66699I278J-288D01*
G02X827283Y66689I-1019J-963D01*
G03X827265Y67250I-293J271D01*
G02X827206Y69370I1034J1090D01*
G03Y69919I-291J274D01*
G02X827269Y72043I1093J1031D01*
G03X827290Y72604I-274J291D01*
G02X829340Y72583I1035J946D01*
G03X829350Y72022I290J-275D01*
G02X829392Y69919I-1051J-1073D01*
G03Y69370I291J-274D01*
G02X829344Y67261I-1093J-1030D01*
G37*
G36*
G01X792533D02*
G03X792520Y66699I278J-288D01*
G02X790472Y66689I-1019J-963D01*
G03X790454Y67250I-293J271D01*
G02X790395Y69370I1034J1090D01*
G03Y69919I-291J274D01*
G02X790458Y72043I1093J1031D01*
G03X790479Y72604I-274J291D01*
G02X792529Y72583I1035J946D01*
G03X792539Y72022I290J-275D01*
G02X792581Y69919I-1051J-1073D01*
G03Y69370I291J-274D01*
G02X792533Y67261I-1093J-1030D01*
G37*
G36*
G01X1099508Y55935D02*
G03X1100069Y55966I265J300D01*
G02X1100128Y53886I1112J-1009D01*
G03X1099566I-281J-285D01*
G02X1099508Y55935I-985J997D01*
G37*
G36*
G01X1246064Y51617D02*
G03X1246078Y51034I281J-285D01*
G02X1244078I-1000J-1120D01*
G03X1244092Y51617I-267J298D01*
G02X1246064I986J997D01*
G37*
G36*
G01X1239371D02*
G03X1239385Y51034I281J-285D01*
G02X1237385I-1000J-1120D01*
G03X1237399Y51617I-267J298D01*
G02X1239371I986J997D01*
G37*
G36*
G01X1221939D02*
G03X1221953Y51034I281J-285D01*
G02X1219953I-1000J-1120D01*
G03X1219967Y51617I-267J298D01*
G02X1221939I986J997D01*
G37*
G36*
G01X1209253D02*
G03X1209267Y51034I281J-285D01*
G02X1207267I-1000J-1120D01*
G03X1207281Y51617I-267J298D01*
G02X1209253I986J997D01*
G37*
G36*
G01X1202560D02*
G03X1202574Y51034I281J-285D01*
G02X1200574I-1000J-1120D01*
G03X1200588Y51617I-267J298D01*
G02X1202560I986J997D01*
G37*
G36*
G01X1185128D02*
G03X1185142Y51034I281J-285D01*
G02X1183142I-1000J-1120D01*
G03X1183156Y51617I-267J298D01*
G02X1185128I986J997D01*
G37*
G36*
G01X1172442D02*
G03X1172456Y51034I281J-285D01*
G02X1170456I-1000J-1120D01*
G03X1170470Y51617I-267J298D01*
G02X1172442I986J997D01*
G37*
G36*
G01X1165749D02*
G03X1165763Y51034I281J-285D01*
G02X1163763I-1000J-1120D01*
G03X1163777Y51617I-267J298D01*
G02X1165749I986J997D01*
G37*
G36*
G01X1148317D02*
G03X1148331Y51034I281J-285D01*
G02X1146331I-1000J-1120D01*
G03X1146345Y51617I-267J298D01*
G02X1148317I986J997D01*
G37*
G36*
G01X1135631D02*
G03X1135645Y51034I281J-285D01*
G02X1133645I-1000J-1120D01*
G03X1133659Y51617I-267J298D01*
G02X1135631I986J997D01*
G37*
G36*
G01X1128938D02*
G03X1128952Y51034I281J-285D01*
G02X1126952I-1000J-1120D01*
G03X1126966Y51617I-267J298D01*
G02X1128938I986J997D01*
G37*
G36*
G01X1111506D02*
G03X1111520Y51034I281J-285D01*
G02X1109520I-1000J-1120D01*
G03X1109534Y51617I-267J298D01*
G02X1111506I986J997D01*
G37*
G36*
G01X954922D02*
G03X954936Y51034I281J-285D01*
G02X952936I-1000J-1120D01*
G03X952950Y51617I-267J298D01*
G02X954922I986J997D01*
G37*
G36*
G01X948229D02*
G03X948243Y51034I281J-285D01*
G02X946243I-1000J-1120D01*
G03X946257Y51617I-267J298D01*
G02X948229I986J997D01*
G37*
G36*
G01X930797D02*
G03X930811Y51034I281J-285D01*
G02X928811I-1000J-1120D01*
G03X928825Y51617I-267J298D01*
G02X930797I986J997D01*
G37*
G36*
G01X918111D02*
G03X918125Y51034I281J-285D01*
G02X916125I-1000J-1120D01*
G03X916139Y51617I-267J298D01*
G02X918111I986J997D01*
G37*
G36*
G01X911418D02*
G03X911432Y51034I281J-285D01*
G02X909432I-1000J-1120D01*
G03X909446Y51617I-267J298D01*
G02X911418I986J997D01*
G37*
G36*
G01X893986D02*
G03X894000Y51034I281J-285D01*
G02X892000I-1000J-1120D01*
G03X892014Y51617I-267J298D01*
G02X893986I986J997D01*
G37*
G36*
G01X887700Y51578D02*
G03X887727Y51017I298J-267D01*
G02X885646Y50977I-1020J-1103D01*
G03X885650Y51538I-283J283D01*
G02X887700Y51578I1006J976D01*
G37*
G36*
G01X881300Y51617D02*
G03X881314Y51034I281J-285D01*
G02X879314I-1000J-1120D01*
G03X879328Y51617I-267J298D01*
G02X881300I986J997D01*
G37*
G36*
G01X874607D02*
G03X874621Y51034I281J-285D01*
G02X872621I-1000J-1120D01*
G03X872635Y51617I-267J298D01*
G02X874607I986J997D01*
G37*
G36*
G01X857175D02*
G03X857189Y51034I281J-285D01*
G02X855189I-1000J-1120D01*
G03X855203Y51617I-267J298D01*
G02X857175I986J997D01*
G37*
G36*
G01X850889Y51578D02*
G03X850916Y51017I298J-267D01*
G02X848835Y50977I-1020J-1103D01*
G03X848839Y51538I-283J283D01*
G02X850889Y51578I1006J976D01*
G37*
G36*
G01X844489Y51617D02*
G03X844503Y51034I281J-285D01*
G02X842503I-1000J-1120D01*
G03X842517Y51617I-267J298D01*
G02X844489I986J997D01*
G37*
G36*
G01X837796D02*
G03X837810Y51034I281J-285D01*
G02X835810I-1000J-1120D01*
G03X835824Y51617I-267J298D01*
G02X837796I986J997D01*
G37*
G36*
G01X820364D02*
G03X820378Y51034I281J-285D01*
G02X818378I-1000J-1120D01*
G03X818392Y51617I-267J298D01*
G02X820364I986J997D01*
G37*
G36*
G01X814078Y51578D02*
G03X814105Y51017I298J-267D01*
G02X812024Y50977I-1020J-1103D01*
G03X812028Y51538I-283J283D01*
G02X814078Y51578I1006J976D01*
G37*
G36*
G01X807678Y51617D02*
G03X807692Y51034I281J-285D01*
G02X805692I-1000J-1120D01*
G03X805706Y51617I-267J298D01*
G02X807678I986J997D01*
G37*
G36*
G01X800985D02*
G03X800999Y51034I281J-285D01*
G02X798999I-1000J-1120D01*
G03X799013Y51617I-267J298D01*
G02X800985I986J997D01*
G37*
G36*
G01X783553D02*
G03X783567Y51034I281J-285D01*
G02X781567I-1000J-1120D01*
G03X781581Y51617I-267J298D01*
G02X783553I986J997D01*
G37*
G36*
G01X777267Y51578D02*
G03X777294Y51017I298J-267D01*
G02X775213Y50977I-1020J-1103D01*
G03X775217Y51538I-283J283D01*
G02X777267Y51578I1006J976D01*
G37*
G36*
G01X1008310Y51293D02*
G03Y50699I268J-297D01*
G02X1006430I-940J-1040D01*
G03Y51293I-268J297D01*
G02X1008310I940J1040D01*
G37*
G36*
G01X1230970Y51287D02*
G03Y50741I292J-273D01*
G02X1228778I-1096J-1027D01*
G03Y51287I-292J273D01*
G02X1228833Y53397I1096J1027D01*
G03X1228849Y53958I-277J289D01*
G02X1230899I1025J956D01*
G03X1230915Y53397I293J-272D01*
G02X1230970Y51287I-1041J-1083D01*
G37*
G36*
G01X1297959Y50236D02*
G03X1297942Y49668I273J-292D01*
G02X1295919Y49673I-1014J-968D01*
G03X1295905Y50242I-288J278D01*
G02X1297959Y50236I1030J1093D01*
G37*
G36*
G01X1120459Y48610D02*
G03X1120435Y48046I271J-294D01*
G02X1118395Y48077I-1035J-946D01*
G03X1118388Y48642I-287J279D01*
G02X1118344Y50741I1052J1072D01*
G03Y51287I-292J273D01*
G02X1118399Y53397I1096J1027D01*
G03X1118415Y53958I-277J289D01*
G02X1120465I1025J956D01*
G03X1120481Y53397I293J-272D01*
G02X1120536Y51287I-1041J-1083D01*
G03Y50741I292J-273D01*
G02X1120459Y48610I-1096J-1027D01*
G37*
G36*
G01X1194036Y48570D02*
G03X1194010Y47984I259J-305D01*
G02X1192051Y48021I-998J-984D01*
G03X1192048Y48607I-274J292D01*
G02X1191967Y50741I1015J1107D01*
G03Y51287I-292J273D01*
G02X1192022Y53397I1096J1027D01*
G03X1192038Y53958I-277J289D01*
G02X1194088I1025J956D01*
G03X1194104Y53397I293J-272D01*
G02X1194159Y51287I-1041J-1083D01*
G03Y50741I292J-273D01*
G02X1194036Y48570I-1096J-1027D01*
G37*
G36*
G01X1157224D02*
G03X1157198Y47984I259J-305D01*
G02X1155239Y48021I-998J-984D01*
G03X1155236Y48607I-274J292D01*
G02X1155155Y50741I1015J1107D01*
G03Y51287I-292J273D01*
G02X1155211Y53397I1096J1027D01*
G03X1155226Y53958I-277J288D01*
G02X1157277I1025J956D01*
G03X1157292Y53396I292J-273D01*
G02X1157347Y51287I-1041J-1082D01*
G03Y50741I292J-273D01*
G02X1157224Y48570I-1096J-1027D01*
G37*
G36*
G01X939672Y48543D02*
G03X939653Y47936I251J-312D01*
G02X937781Y47951I-944J-1036D01*
G03X937772Y48559I-265J300D01*
G02X937636Y50741I960J1155D01*
G03Y51287I-292J273D01*
G02X937691Y53397I1096J1027D01*
G03X937707Y53958I-277J289D01*
G02X939757I1025J956D01*
G03X939773Y53397I293J-272D01*
G02X939828Y51287I-1041J-1083D01*
G03Y50741I292J-273D01*
G02X939672Y48543I-1096J-1027D01*
G37*
G36*
G01X902861D02*
G03X902842Y47936I251J-312D01*
G02X900970Y47951I-944J-1036D01*
G03X900961Y48559I-265J300D01*
G02X900825Y50741I960J1155D01*
G03Y51287I-292J273D01*
G02X900880Y53397I1096J1027D01*
G03X900896Y53958I-277J289D01*
G02X902946I1025J956D01*
G03X902962Y53397I293J-272D01*
G02X903017Y51287I-1041J-1083D01*
G03Y50741I292J-273D01*
G02X902861Y48543I-1096J-1027D01*
G37*
G36*
G01X866050D02*
G03X866031Y47936I251J-312D01*
G02X864159Y47951I-944J-1036D01*
G03X864150Y48559I-265J300D01*
G02X864014Y50741I960J1155D01*
G03Y51287I-292J273D01*
G02X864069Y53397I1096J1027D01*
G03X864085Y53958I-277J289D01*
G02X866135I1025J956D01*
G03X866151Y53397I293J-272D01*
G02X866206Y51287I-1041J-1083D01*
G03Y50741I292J-273D01*
G02X866050Y48543I-1096J-1027D01*
G37*
G36*
G01X829239D02*
G03X829220Y47936I251J-312D01*
G02X827348Y47951I-944J-1036D01*
G03X827339Y48559I-265J300D01*
G02X827203Y50741I960J1155D01*
G03Y51287I-292J273D01*
G02X827258Y53397I1096J1027D01*
G03X827274Y53958I-277J289D01*
G02X829324I1025J956D01*
G03X829340Y53397I293J-272D01*
G02X829395Y51287I-1041J-1083D01*
G03Y50741I292J-273D01*
G02X829239Y48543I-1096J-1027D01*
G37*
G36*
G01X792428D02*
G03X792409Y47936I251J-312D01*
G02X790537Y47951I-944J-1036D01*
G03X790528Y48559I-265J300D01*
G02X790392Y50741I960J1155D01*
G03Y51287I-292J273D01*
G02X790447Y53397I1096J1027D01*
G03X790463Y53958I-277J289D01*
G02X792513I1025J956D01*
G03X792529Y53397I293J-272D01*
G02X792584Y51287I-1041J-1083D01*
G03Y50741I292J-273D01*
G02X792428Y48543I-1096J-1027D01*
G37*
G36*
G01X1225814Y48416D02*
G03X1225799Y47855I277J-288D01*
G02X1223749I-1025J-957D01*
G03X1223734Y48416I-292J273D01*
G02X1223678Y50527I1040J1084D01*
G03Y51073I-292J273D01*
G02X1225870I1096J1027D01*
G03Y50527I292J-273D01*
G02X1225814Y48416I-1096J-1027D01*
G37*
G36*
G01X1189003D02*
G03X1188988Y47855I277J-288D01*
G02X1186938I-1025J-957D01*
G03X1186923Y48416I-292J273D01*
G02X1186867Y50527I1040J1084D01*
G03Y51073I-292J273D01*
G02X1186901Y53162I1096J1027D01*
G03X1186906Y53724I-282J284D01*
G02X1188956Y53764I1006J976D01*
G03X1188982Y53203I298J-267D01*
G02X1189059Y51073I-1019J-1103D01*
G03Y50527I292J-273D01*
G02X1189003Y48416I-1096J-1027D01*
G37*
G36*
G01X1152192Y48417D02*
G03X1152176Y47855I277J-289D01*
G02X1150127Y47854I-1024J-957D01*
G03X1150111Y48416I-292J273D01*
G02X1150055Y50527I1040J1084D01*
G03Y51073I-292J273D01*
G02X1150089Y53162I1096J1027D01*
G03X1150094Y53724I-282J284D01*
G02X1152144Y53764I1006J976D01*
G03X1152170Y53203I298J-267D01*
G02X1152247Y51073I-1019J-1103D01*
G03Y50527I292J-273D01*
G02X1152192Y48417I-1096J-1027D01*
G37*
G36*
G01X1115380Y48416D02*
G03X1115365Y47855I277J-288D01*
G02X1113315I-1025J-957D01*
G03X1113300Y48416I-292J273D01*
G02X1113244Y50527I1040J1084D01*
G03Y51073I-292J273D01*
G02X1113283Y53167I1096J1027D01*
G03X1113289Y53728I-282J284D01*
G02X1115340Y53760I1011J972D01*
G03X1115364Y53199I297J-268D01*
G02X1115436Y51073I-1024J-1099D01*
G03Y50527I292J-273D01*
G02X1115380Y48416I-1096J-1027D01*
G37*
G36*
G01X934672D02*
G03X934657Y47855I277J-288D01*
G02X932607I-1025J-957D01*
G03X932592Y48416I-292J273D01*
G02X932536Y50527I1040J1084D01*
G03Y51073I-292J273D01*
G02X932581Y53173I1096J1027D01*
G03X932591Y53735I-280J286D01*
G02X934642Y53753I1017J965D01*
G03X934663Y53192I295J-270D01*
G02X934728Y51073I-1031J-1092D01*
G03Y50527I292J-273D01*
G02X934672Y48416I-1096J-1027D01*
G37*
G36*
G01X897861D02*
G03X897846Y47855I277J-288D01*
G02X895796I-1025J-957D01*
G03X895781Y48416I-292J273D01*
G02X895725Y50527I1040J1084D01*
G03Y51073I-292J273D01*
G02X895770Y53173I1096J1027D01*
G03X895780Y53735I-280J286D01*
G02X897831Y53753I1017J965D01*
G03X897852Y53192I295J-270D01*
G02X897917Y51073I-1031J-1092D01*
G03Y50527I292J-273D01*
G02X897861Y48416I-1096J-1027D01*
G37*
G36*
G01X861050D02*
G03X861035Y47855I277J-288D01*
G02X858985I-1025J-957D01*
G03X858970Y48416I-292J273D01*
G02X858914Y50527I1040J1084D01*
G03Y51073I-292J273D01*
G02X858959Y53173I1096J1027D01*
G03X858969Y53735I-280J286D01*
G02X861020Y53753I1017J965D01*
G03X861041Y53192I295J-270D01*
G02X861106Y51073I-1031J-1092D01*
G03Y50527I292J-273D01*
G02X861050Y48416I-1096J-1027D01*
G37*
G36*
G01X824239D02*
G03X824224Y47855I277J-288D01*
G02X822174I-1025J-957D01*
G03X822159Y48416I-292J273D01*
G02X822103Y50527I1040J1084D01*
G03Y51073I-292J273D01*
G02X822148Y53173I1096J1027D01*
G03X822158Y53735I-280J286D01*
G02X824209Y53753I1017J965D01*
G03X824230Y53192I295J-270D01*
G02X824295Y51073I-1031J-1092D01*
G03Y50527I292J-273D01*
G02X824239Y48416I-1096J-1027D01*
G37*
G36*
G01X787428D02*
G03X787413Y47855I277J-288D01*
G02X785363I-1025J-957D01*
G03X785348Y48416I-292J273D01*
G02X785292Y50527I1040J1084D01*
G03Y51073I-292J273D01*
G02X785337Y53173I1096J1027D01*
G03X785347Y53735I-280J286D01*
G02X787398Y53753I1017J965D01*
G03X787419Y53192I295J-270D01*
G02X787484Y51073I-1031J-1092D01*
G03Y50527I292J-273D01*
G02X787428Y48416I-1096J-1027D01*
G37*
G36*
G01X1012788Y45875D02*
G03X1012211I-288J-277D01*
G02Y47953I-1085J1039D01*
G03X1012788I288J277D01*
G02Y45875I1085J-1039D01*
G37*
G36*
G01X1009185Y32318D02*
G03X1009179Y31740I273J-292D01*
G02X1007242Y31760I-979J-1004D01*
G03X1007248Y32338I-273J292D01*
G02X1009185Y32318I979J1004D01*
G37*
G36*
G01X934699Y29667D02*
G03X934683Y29106I277J-289D01*
G02X932633I-1025J-956D01*
G03X932617Y29667I-293J272D01*
G02X932570Y31785I1041J1083D01*
G03X932564Y32342I-290J275D01*
G02X932591Y34482I1068J1057D01*
G03X932607Y35043I-277J289D01*
G02X934657I1025J956D01*
G03X934673Y34482I293J-272D01*
G02X934720Y32364I-1041J-1083D01*
G03X934726Y31807I290J-275D01*
G02X934699Y29667I-1068J-1057D01*
G37*
G36*
G01X897888D02*
G03X897872Y29106I277J-289D01*
G02X895822I-1025J-956D01*
G03X895806Y29667I-293J272D01*
G02X895759Y31785I1041J1083D01*
G03X895753Y32342I-290J275D01*
G02X895780Y34482I1068J1057D01*
G03X895796Y35043I-277J289D01*
G02X897846I1025J956D01*
G03X897862Y34482I293J-272D01*
G02X897909Y32364I-1041J-1083D01*
G03X897915Y31807I290J-275D01*
G02X897888Y29667I-1068J-1057D01*
G37*
G36*
G01X861077D02*
G03X861061Y29106I277J-289D01*
G02X859011I-1025J-956D01*
G03X858995Y29667I-293J272D01*
G02X858948Y31785I1041J1083D01*
G03X858942Y32342I-290J275D01*
G02X858969Y34482I1068J1057D01*
G03X858985Y35043I-277J289D01*
G02X861035I1025J956D01*
G03X861051Y34482I293J-272D01*
G02X861098Y32364I-1041J-1083D01*
G03X861104Y31807I290J-275D01*
G02X861077Y29667I-1068J-1057D01*
G37*
G36*
G01X824266D02*
G03X824250Y29106I277J-289D01*
G02X822200I-1025J-956D01*
G03X822184Y29667I-293J272D01*
G02X822137Y31785I1041J1083D01*
G03X822131Y32342I-290J275D01*
G02X822158Y34482I1068J1057D01*
G03X822174Y35043I-277J289D01*
G02X824224I1025J956D01*
G03X824240Y34482I293J-272D01*
G02X824287Y32364I-1041J-1083D01*
G03X824293Y31807I290J-275D01*
G02X824266Y29667I-1068J-1057D01*
G37*
G36*
G01X787455D02*
G03X787439Y29106I277J-289D01*
G02X785389I-1025J-956D01*
G03X785373Y29667I-293J272D01*
G02X785326Y31785I1041J1083D01*
G03X785320Y32342I-290J275D01*
G02X785347Y34482I1068J1057D01*
G03X785363Y35043I-277J289D01*
G02X787413I1025J956D01*
G03X787429Y34482I293J-272D01*
G02X787476Y32364I-1041J-1083D01*
G03X787482Y31807I290J-275D01*
G02X787455Y29667I-1068J-1057D01*
G37*
G36*
G01X1225821Y29648D02*
G03X1225806Y29077I272J-293D01*
G02X1223794I-1006J-977D01*
G03X1223779Y29648I-287J278D01*
G02X1223712Y31785I1021J1102D01*
G03X1223706Y32342I-290J275D01*
G02X1223733Y34482I1068J1057D01*
G03X1223749Y35043I-277J289D01*
G02X1225799I1025J956D01*
G03X1225815Y34482I293J-272D01*
G02X1225862Y32364I-1041J-1083D01*
G03X1225868Y31807I290J-275D01*
G02X1225821Y29648I-1068J-1057D01*
G37*
G36*
G01X1189024Y29662D02*
G03X1189016Y29089I275J-290D01*
G02X1187005Y29064I-993J-989D01*
G03X1186982Y29635I-291J274D01*
G02X1186901Y31785I1007J1114D01*
G03X1186895Y32342I-290J275D01*
G02X1186922Y34482I1068J1057D01*
G03X1186938Y35043I-277J289D01*
G02X1188988I1025J956D01*
G03X1189004Y34482I293J-272D01*
G02X1189051Y32364I-1041J-1083D01*
G03X1189057Y31807I290J-275D01*
G02X1189024Y29662I-1068J-1056D01*
G37*
G36*
G01X1152212D02*
G03X1152204Y29089I275J-290D01*
G02X1150193Y29064I-993J-989D01*
G03X1150170Y29635I-291J274D01*
G02X1150089Y31785I1007J1114D01*
G03X1150083Y32342I-290J275D01*
G02X1150111Y34482I1068J1056D01*
G03X1150126Y35043I-277J288D01*
G02X1152177I1025J956D01*
G03X1152192Y34481I292J-273D01*
G02X1152239Y32364I-1041J-1082D01*
G03X1152245Y31807I290J-275D01*
G02X1152212Y29662I-1068J-1056D01*
G37*
G36*
G01X1115401D02*
G03X1115393Y29089I275J-290D01*
G02X1113382Y29064I-993J-989D01*
G03X1113359Y29635I-291J274D01*
G02X1113278Y31785I1007J1114D01*
G03X1113272Y32342I-290J275D01*
G02X1113299Y34482I1068J1057D01*
G03X1113315Y35043I-277J289D01*
G02X1115365I1025J956D01*
G03X1115381Y34482I293J-272D01*
G02X1115428Y32364I-1041J-1083D01*
G03X1115434Y31807I290J-275D01*
G02X1115401Y29662I-1068J-1056D01*
G37*
G36*
G01X1230919Y29461D02*
G03X1230906Y28899I278J-288D01*
G02X1228858Y28889I-1019J-963D01*
G03X1228840Y29450I-293J271D01*
G02X1228781Y31570I1034J1090D01*
G03Y32119I-291J274D01*
G02X1228804Y34203I1093J1030D01*
G03X1228803Y34764I-286J280D01*
G02X1230851Y34823I996J986D01*
G03X1230883Y34262I300J-264D01*
G02X1230967Y32119I-1009J-1113D01*
G03Y31570I291J-275D01*
G02X1230919Y29461I-1093J-1030D01*
G37*
G36*
G01X1194108D02*
G03X1194095Y28899I278J-288D01*
G02X1192047Y28889I-1019J-963D01*
G03X1192029Y29450I-293J271D01*
G02X1191970Y31570I1034J1090D01*
G03Y32119I-291J274D01*
G02X1192026Y34236I1093J1030D01*
G03X1192032Y34808I-276J289D01*
G02X1194043Y34838I991J992D01*
G03X1194067Y34266I291J-274D01*
G02X1194156Y32119I-1004J-1117D01*
G03Y31570I291J-275D01*
G02X1194108Y29461I-1093J-1030D01*
G37*
G36*
G01X1157296D02*
G03X1157284Y28899I278J-287D01*
G02X1155236Y28888I-1019J-963D01*
G03X1155218Y29450I-294J272D01*
G02X1155158Y31570I1033J1090D01*
G03Y32119I-291J274D01*
G02X1155214Y34236I1093J1030D01*
G03X1155220Y34808I-276J289D01*
G02X1157231Y34838I991J992D01*
G03X1157255Y34266I291J-274D01*
G02X1157344Y32119I-1004J-1117D01*
G03Y31570I291J-275D01*
G02X1157296Y29461I-1093J-1030D01*
G37*
G36*
G01X1120485D02*
G03X1120472Y28899I278J-288D01*
G02X1118424Y28889I-1019J-963D01*
G03X1118406Y29450I-293J271D01*
G02X1118347Y31570I1034J1090D01*
G03Y32119I-291J274D01*
G02X1118403Y34236I1093J1030D01*
G03X1118409Y34808I-276J289D01*
G02X1120420Y34838I991J992D01*
G03X1120444Y34266I291J-274D01*
G02X1120533Y32119I-1004J-1117D01*
G03Y31570I291J-275D01*
G02X1120485Y29461I-1093J-1030D01*
G37*
G36*
G01X939777D02*
G03X939764Y28899I278J-288D01*
G02X937716Y28889I-1019J-963D01*
G03X937698Y29450I-293J271D01*
G02X937639Y31570I1034J1090D01*
G03Y32119I-291J274D01*
G02X937702Y34243I1093J1031D01*
G03X937723Y34804I-274J291D01*
G02X939773Y34783I1035J946D01*
G03X939783Y34222I290J-275D01*
G02X939825Y32119I-1051J-1073D01*
G03Y31570I291J-275D01*
G02X939777Y29461I-1093J-1030D01*
G37*
G36*
G01X902966D02*
G03X902953Y28899I278J-288D01*
G02X900905Y28889I-1019J-963D01*
G03X900887Y29450I-293J271D01*
G02X900828Y31570I1034J1090D01*
G03Y32119I-291J274D01*
G02X900891Y34243I1093J1031D01*
G03X900912Y34804I-274J291D01*
G02X902962Y34783I1035J946D01*
G03X902972Y34222I290J-275D01*
G02X903014Y32119I-1051J-1073D01*
G03Y31570I291J-275D01*
G02X902966Y29461I-1093J-1030D01*
G37*
G36*
G01X866155D02*
G03X866142Y28899I278J-288D01*
G02X864094Y28889I-1019J-963D01*
G03X864076Y29450I-293J271D01*
G02X864017Y31570I1034J1090D01*
G03Y32119I-291J274D01*
G02X864080Y34243I1093J1031D01*
G03X864101Y34804I-274J291D01*
G02X866151Y34783I1035J946D01*
G03X866161Y34222I290J-275D01*
G02X866203Y32119I-1051J-1073D01*
G03Y31570I291J-275D01*
G02X866155Y29461I-1093J-1030D01*
G37*
G36*
G01X829344D02*
G03X829331Y28899I278J-288D01*
G02X827283Y28889I-1019J-963D01*
G03X827265Y29450I-293J271D01*
G02X827206Y31570I1034J1090D01*
G03Y32119I-291J274D01*
G02X827269Y34243I1093J1031D01*
G03X827290Y34804I-274J291D01*
G02X829340Y34783I1035J946D01*
G03X829350Y34222I290J-275D01*
G02X829392Y32119I-1051J-1073D01*
G03Y31570I291J-275D01*
G02X829344Y29461I-1093J-1030D01*
G37*
G36*
G01X792533D02*
G03X792520Y28899I278J-288D01*
G02X790472Y28889I-1019J-963D01*
G03X790454Y29450I-293J271D01*
G02X790395Y31570I1034J1090D01*
G03Y32119I-291J274D01*
G02X790458Y34243I1093J1031D01*
G03X790479Y34804I-274J291D01*
G02X792529Y34783I1035J946D01*
G03X792539Y34222I290J-275D01*
G02X792581Y32119I-1051J-1073D01*
G03Y31570I291J-275D01*
G02X792533Y29461I-1093J-1030D01*
G37*
G36*
G01X1100127Y16087D02*
G03X1099547Y16068I-281J-285D01*
G02X1099431Y18048I-1047J932D01*
G03X1100009Y18097I266J299D01*
G02X1100127Y16087I1172J-940D01*
G37*
G36*
G01X1013884Y15953D02*
G03X1013327Y15947I-275J-290D01*
G02X1013305Y18103I-1057J1067D01*
G03X1013862Y18109I275J290D01*
G02X1013884Y15953I1057J-1067D01*
G37*
G36*
G01X1047471Y15650D02*
G03X1047025Y15275I-47J-397D01*
G02X1045778Y16838I-1500J82D01*
G03X1046243Y17190I67J394D01*
G02X1047471Y15650I1394J-148D01*
G37*
G36*
G01X1246064Y13817D02*
G03X1246078Y13234I281J-285D01*
G02X1244078I-1000J-1120D01*
G03X1244092Y13817I-267J298D01*
G02X1246064I986J997D01*
G37*
G36*
G01X1239371D02*
G03X1239385Y13234I281J-285D01*
G02X1237385I-1000J-1120D01*
G03X1237399Y13817I-267J298D01*
G02X1239371I986J997D01*
G37*
G36*
G01X1221939D02*
G03X1221953Y13234I281J-285D01*
G02X1219953I-1000J-1120D01*
G03X1219967Y13817I-267J298D01*
G02X1221939I986J997D01*
G37*
G36*
G01X1215647Y13782D02*
G03X1215675Y13221I299J-266D01*
G02X1213595Y13173I-1015J-1107D01*
G03X1213597Y13734I-284J282D01*
G02X1215647Y13782I1003J980D01*
G37*
G36*
G01X1209253Y13817D02*
G03X1209267Y13234I281J-285D01*
G02X1207267I-1000J-1120D01*
G03X1207281Y13817I-267J298D01*
G02X1209253I986J997D01*
G37*
G36*
G01X1202560D02*
G03X1202574Y13234I281J-285D01*
G02X1200574I-1000J-1120D01*
G03X1200588Y13817I-267J298D01*
G02X1202560I986J997D01*
G37*
G36*
G01X1185128D02*
G03X1185142Y13234I281J-285D01*
G02X1183142I-1000J-1120D01*
G03X1183156Y13817I-267J298D01*
G02X1185128I986J997D01*
G37*
G36*
G01X1178842Y13778D02*
G03X1178869Y13217I298J-267D01*
G02X1176788Y13177I-1020J-1103D01*
G03X1176792Y13738I-283J283D01*
G02X1178842Y13778I1006J976D01*
G37*
G36*
G01X1172442Y13817D02*
G03X1172456Y13234I281J-285D01*
G02X1170456I-1000J-1120D01*
G03X1170470Y13817I-267J298D01*
G02X1172442I986J997D01*
G37*
G36*
G01X1165749D02*
G03X1165763Y13234I281J-285D01*
G02X1163763I-1000J-1120D01*
G03X1163777Y13817I-267J298D01*
G02X1165749I986J997D01*
G37*
G36*
G01X1148317D02*
G03X1148331Y13234I281J-285D01*
G02X1146331I-1000J-1120D01*
G03X1146345Y13817I-267J298D01*
G02X1148317I986J997D01*
G37*
G36*
G01X1142031Y13778D02*
G03X1142058Y13217I298J-267D01*
G02X1139977Y13177I-1020J-1103D01*
G03X1139981Y13738I-283J283D01*
G02X1142031Y13778I1006J976D01*
G37*
G36*
G01X1135631Y13817D02*
G03X1135645Y13234I281J-285D01*
G02X1133645I-1000J-1120D01*
G03X1133659Y13817I-267J298D01*
G02X1135631I986J997D01*
G37*
G36*
G01X1128938D02*
G03X1128952Y13234I281J-285D01*
G02X1126952I-1000J-1120D01*
G03X1126966Y13817I-267J298D01*
G02X1128938I986J997D01*
G37*
G36*
G01X1111506D02*
G03X1111520Y13234I281J-285D01*
G02X1109520I-1000J-1120D01*
G03X1109534Y13817I-267J298D01*
G02X1111506I986J997D01*
G37*
G36*
G01X1105220Y13778D02*
G03X1105247Y13217I298J-267D01*
G02X1103166Y13177I-1020J-1103D01*
G03X1103170Y13738I-283J283D01*
G02X1105220Y13778I1006J976D01*
G37*
G36*
G01X954922Y13817D02*
G03X954936Y13234I281J-285D01*
G02X952936I-1000J-1120D01*
G03X952950Y13817I-267J298D01*
G02X954922I986J997D01*
G37*
G36*
G01X948229D02*
G03X948243Y13234I281J-285D01*
G02X946243I-1000J-1120D01*
G03X946257Y13817I-267J298D01*
G02X948229I986J997D01*
G37*
G36*
G01X930797D02*
G03X930811Y13234I281J-285D01*
G02X928811I-1000J-1120D01*
G03X928825Y13817I-267J298D01*
G02X930797I986J997D01*
G37*
G36*
G01X924511Y13778D02*
G03X924538Y13217I298J-267D01*
G02X922457Y13177I-1020J-1103D01*
G03X922461Y13738I-283J283D01*
G02X924511Y13778I1006J976D01*
G37*
G36*
G01X918111Y13817D02*
G03X918125Y13234I281J-285D01*
G02X916125I-1000J-1120D01*
G03X916139Y13817I-267J298D01*
G02X918111I986J997D01*
G37*
G36*
G01X911418D02*
G03X911432Y13234I281J-285D01*
G02X909432I-1000J-1120D01*
G03X909446Y13817I-267J298D01*
G02X911418I986J997D01*
G37*
G36*
G01X893986D02*
G03X894000Y13234I281J-285D01*
G02X892000I-1000J-1120D01*
G03X892014Y13817I-267J298D01*
G02X893986I986J997D01*
G37*
G36*
G01X887700Y13778D02*
G03X887727Y13217I298J-267D01*
G02X885646Y13177I-1020J-1103D01*
G03X885650Y13738I-283J283D01*
G02X887700Y13778I1006J976D01*
G37*
G36*
G01X881300Y13817D02*
G03X881314Y13234I281J-285D01*
G02X879314I-1000J-1120D01*
G03X879328Y13817I-267J298D01*
G02X881300I986J997D01*
G37*
G36*
G01X874607D02*
G03X874621Y13234I281J-285D01*
G02X872621I-1000J-1120D01*
G03X872635Y13817I-267J298D01*
G02X874607I986J997D01*
G37*
G36*
G01X857175D02*
G03X857189Y13234I281J-285D01*
G02X855189I-1000J-1120D01*
G03X855203Y13817I-267J298D01*
G02X857175I986J997D01*
G37*
G36*
G01X850889Y13778D02*
G03X850916Y13217I298J-267D01*
G02X848835Y13177I-1020J-1103D01*
G03X848839Y13738I-283J283D01*
G02X850889Y13778I1006J976D01*
G37*
G36*
G01X844489Y13817D02*
G03X844503Y13234I281J-285D01*
G02X842503I-1000J-1120D01*
G03X842517Y13817I-267J298D01*
G02X844489I986J997D01*
G37*
G36*
G01X837796D02*
G03X837810Y13234I281J-285D01*
G02X835810I-1000J-1120D01*
G03X835824Y13817I-267J298D01*
G02X837796I986J997D01*
G37*
G36*
G01X820364D02*
G03X820378Y13234I281J-285D01*
G02X818378I-1000J-1120D01*
G03X818392Y13817I-267J298D01*
G02X820364I986J997D01*
G37*
G36*
G01X814078Y13778D02*
G03X814105Y13217I298J-267D01*
G02X812024Y13177I-1020J-1103D01*
G03X812028Y13738I-283J283D01*
G02X814078Y13778I1006J976D01*
G37*
G36*
G01X807678Y13817D02*
G03X807692Y13234I281J-285D01*
G02X805692I-1000J-1120D01*
G03X805706Y13817I-267J298D01*
G02X807678I986J997D01*
G37*
G36*
G01X800985D02*
G03X800999Y13234I281J-285D01*
G02X798999I-1000J-1120D01*
G03X799013Y13817I-267J298D01*
G02X800985I986J997D01*
G37*
G36*
G01X783553D02*
G03X783567Y13234I281J-285D01*
G02X781567I-1000J-1120D01*
G03X781581Y13817I-267J298D01*
G02X783553I986J997D01*
G37*
G36*
G01X777267Y13778D02*
G03X777294Y13217I298J-267D01*
G02X775213Y13177I-1020J-1103D01*
G03X775217Y13738I-283J283D01*
G02X777267Y13778I1006J976D01*
G37*
G36*
G01X1008071Y13303D02*
G03Y12725I277J-289D01*
G02X1006129I-971J-1011D01*
G03Y13303I-277J289D01*
G02X1008071I971J1011D01*
G37*
G36*
G01X1098901Y12718D02*
G03X1098902Y12156I285J-280D01*
G02X1096821Y12209I-1068J-1056D01*
G03X1096851Y12770I-269J296D01*
G02X1098901Y12718I1049J930D01*
G37*
G36*
G01X1230878Y10797D02*
G03X1230847Y10233I267J-298D01*
G02X1228808Y10291I-1047J-933D01*
G03X1228809Y10855I-283J283D01*
G02X1228778Y12941I1065J1059D01*
G03Y13487I-292J273D01*
G02X1228833Y15597I1096J1027D01*
G03X1228849Y16158I-277J289D01*
G02X1230899I1025J956D01*
G03X1230915Y15597I293J-272D01*
G02X1230970Y13487I-1041J-1083D01*
G03Y12941I292J-273D01*
G02X1230878Y10797I-1096J-1027D01*
G37*
G36*
G01X1194082Y10810D02*
G03X1194058Y10246I271J-294D01*
G02X1192018Y10277I-1035J-946D01*
G03X1192011Y10842I-287J279D01*
G02X1191967Y12941I1052J1072D01*
G03Y13487I-292J273D01*
G02X1192022Y15597I1096J1027D01*
G03X1192038Y16158I-277J289D01*
G02X1194088I1025J956D01*
G03X1194104Y15597I293J-272D01*
G02X1194159Y13487I-1041J-1083D01*
G03Y12941I292J-273D01*
G02X1194082Y10810I-1096J-1027D01*
G37*
G36*
G01X1157271D02*
G03X1157247Y10246I271J-294D01*
G02X1155207Y10277I-1035J-946D01*
G03X1155200Y10842I-287J279D01*
G02X1155156Y12941I1052J1072D01*
G03Y13487I-292J273D01*
G02X1155211Y15597I1096J1027D01*
G03X1155227Y16158I-277J289D01*
G02X1157277I1025J956D01*
G03X1157293Y15597I293J-272D01*
G02X1157348Y13487I-1041J-1083D01*
G03Y12941I292J-273D01*
G02X1157271Y10810I-1096J-1027D01*
G37*
G36*
G01X1120459D02*
G03X1120435Y10246I271J-294D01*
G02X1118395Y10277I-1035J-946D01*
G03X1118388Y10842I-287J279D01*
G02X1118344Y12941I1052J1072D01*
G03Y13487I-292J273D01*
G02X1118399Y15597I1096J1027D01*
G03X1118415Y16158I-277J289D01*
G02X1120465I1025J956D01*
G03X1120481Y15597I293J-272D01*
G02X1120536Y13487I-1041J-1083D01*
G03Y12941I292J-273D01*
G02X1120459Y10810I-1096J-1027D01*
G37*
G36*
G01X939672Y10743D02*
G03X939653Y10136I251J-312D01*
G02X937781Y10151I-944J-1036D01*
G03X937772Y10759I-265J300D01*
G02X937636Y12941I960J1155D01*
G03Y13487I-292J273D01*
G02X937691Y15597I1096J1027D01*
G03X937707Y16158I-277J289D01*
G02X939757I1025J956D01*
G03X939773Y15597I293J-272D01*
G02X939828Y13487I-1041J-1083D01*
G03Y12941I292J-273D01*
G02X939672Y10743I-1096J-1027D01*
G37*
G36*
G01X902861D02*
G03X902842Y10136I251J-312D01*
G02X900970Y10151I-944J-1036D01*
G03X900961Y10759I-265J300D01*
G02X900825Y12941I960J1155D01*
G03Y13487I-292J273D01*
G02X900880Y15597I1096J1027D01*
G03X900896Y16158I-277J289D01*
G02X902946I1025J956D01*
G03X902962Y15597I293J-272D01*
G02X903017Y13487I-1041J-1083D01*
G03Y12941I292J-273D01*
G02X902861Y10743I-1096J-1027D01*
G37*
G36*
G01X866050D02*
G03X866031Y10136I251J-312D01*
G02X864159Y10151I-944J-1036D01*
G03X864150Y10759I-265J300D01*
G02X864014Y12941I960J1155D01*
G03Y13487I-292J273D01*
G02X864069Y15597I1096J1027D01*
G03X864085Y16158I-277J289D01*
G02X866135I1025J956D01*
G03X866151Y15597I293J-272D01*
G02X866206Y13487I-1041J-1083D01*
G03Y12941I292J-273D01*
G02X866050Y10743I-1096J-1027D01*
G37*
G36*
G01X829239D02*
G03X829220Y10136I251J-312D01*
G02X827348Y10151I-944J-1036D01*
G03X827339Y10759I-265J300D01*
G02X827203Y12941I960J1155D01*
G03Y13487I-292J273D01*
G02X827258Y15597I1096J1027D01*
G03X827274Y16158I-277J289D01*
G02X829324I1025J956D01*
G03X829340Y15597I293J-272D01*
G02X829395Y13487I-1041J-1083D01*
G03Y12941I292J-273D01*
G02X829239Y10743I-1096J-1027D01*
G37*
G36*
G01X792428D02*
G03X792409Y10136I251J-312D01*
G02X790537Y10151I-944J-1036D01*
G03X790528Y10759I-265J300D01*
G02X790392Y12941I960J1155D01*
G03Y13487I-292J273D01*
G02X790447Y15597I1096J1027D01*
G03X790463Y16158I-277J289D01*
G02X792513I1025J956D01*
G03X792529Y15597I293J-272D01*
G02X792584Y13487I-1041J-1083D01*
G03Y12941I292J-273D01*
G02X792428Y10743I-1096J-1027D01*
G37*
G36*
G01X1225814Y10616D02*
G03X1225799Y10055I277J-288D01*
G02X1223749I-1025J-957D01*
G03X1223734Y10616I-292J273D01*
G02X1223678Y12727I1040J1084D01*
G03Y13273I-292J273D01*
G02X1223740Y15389I1096J1027D01*
G03X1223759Y15950I-275J290D01*
G02X1225810Y15938I1031J950D01*
G03X1225821Y15376I290J-275D01*
G02X1225870Y13273I-1047J-1076D01*
G03Y12727I292J-273D01*
G02X1225814Y10616I-1096J-1027D01*
G37*
G36*
G01X1189003D02*
G03X1188988Y10055I277J-288D01*
G02X1186938I-1025J-957D01*
G03X1186923Y10616I-292J273D01*
G02X1186867Y12727I1040J1084D01*
G03Y13273I-292J273D01*
G02X1186906Y15367I1096J1027D01*
G03X1186912Y15928I-282J284D01*
G02X1188963Y15960I1011J972D01*
G03X1188987Y15399I297J-268D01*
G02X1189059Y13273I-1024J-1099D01*
G03Y12727I292J-273D01*
G02X1189003Y10616I-1096J-1027D01*
G37*
G36*
G01X1152192D02*
G03X1152177Y10055I277J-288D01*
G02X1150127I-1025J-957D01*
G03X1150112Y10616I-292J273D01*
G02X1150056Y12727I1040J1084D01*
G03Y13273I-292J273D01*
G02X1150095Y15367I1096J1027D01*
G03X1150101Y15928I-282J284D01*
G02X1152152Y15960I1011J972D01*
G03X1152176Y15399I297J-268D01*
G02X1152248Y13273I-1024J-1099D01*
G03Y12727I292J-273D01*
G02X1152192Y10616I-1096J-1027D01*
G37*
G36*
G01X1115380D02*
G03X1115365Y10055I277J-288D01*
G02X1113315I-1025J-957D01*
G03X1113300Y10616I-292J273D01*
G02X1113244Y12727I1040J1084D01*
G03Y13273I-292J273D01*
G02X1113283Y15367I1096J1027D01*
G03X1113289Y15928I-282J284D01*
G02X1115340Y15960I1011J972D01*
G03X1115364Y15399I297J-268D01*
G02X1115436Y13273I-1024J-1099D01*
G03Y12727I292J-273D01*
G02X1115380Y10616I-1096J-1027D01*
G37*
G36*
G01X934672D02*
G03X934657Y10055I277J-288D01*
G02X932607I-1025J-957D01*
G03X932592Y10616I-292J273D01*
G02X932536Y12727I1040J1084D01*
G03Y13273I-292J273D01*
G02X932581Y15373I1096J1027D01*
G03X932591Y15935I-280J286D01*
G02X934642Y15953I1017J965D01*
G03X934663Y15392I295J-270D01*
G02X934728Y13273I-1031J-1092D01*
G03Y12727I292J-273D01*
G02X934672Y10616I-1096J-1027D01*
G37*
G36*
G01X897861D02*
G03X897846Y10055I277J-288D01*
G02X895796I-1025J-957D01*
G03X895781Y10616I-292J273D01*
G02X895725Y12727I1040J1084D01*
G03Y13273I-292J273D01*
G02X895770Y15373I1096J1027D01*
G03X895780Y15935I-280J286D01*
G02X897831Y15953I1017J965D01*
G03X897852Y15392I295J-270D01*
G02X897917Y13273I-1031J-1092D01*
G03Y12727I292J-273D01*
G02X897861Y10616I-1096J-1027D01*
G37*
G36*
G01X861050D02*
G03X861035Y10055I277J-288D01*
G02X858985I-1025J-957D01*
G03X858970Y10616I-292J273D01*
G02X858914Y12727I1040J1084D01*
G03Y13273I-292J273D01*
G02X858959Y15373I1096J1027D01*
G03X858969Y15935I-280J286D01*
G02X861020Y15953I1017J965D01*
G03X861041Y15392I295J-270D01*
G02X861106Y13273I-1031J-1092D01*
G03Y12727I292J-273D01*
G02X861050Y10616I-1096J-1027D01*
G37*
G36*
G01X824239D02*
G03X824224Y10055I277J-288D01*
G02X822174I-1025J-957D01*
G03X822159Y10616I-292J273D01*
G02X822103Y12727I1040J1084D01*
G03Y13273I-292J273D01*
G02X822148Y15373I1096J1027D01*
G03X822158Y15935I-280J286D01*
G02X824209Y15953I1017J965D01*
G03X824230Y15392I295J-270D01*
G02X824295Y13273I-1031J-1092D01*
G03Y12727I292J-273D01*
G02X824239Y10616I-1096J-1027D01*
G37*
G36*
G01X787428D02*
G03X787413Y10055I277J-288D01*
G02X785363I-1025J-957D01*
G03X785348Y10616I-292J273D01*
G02X785292Y12727I1040J1084D01*
G03Y13273I-292J273D01*
G02X785337Y15373I1096J1027D01*
G03X785347Y15935I-280J286D01*
G02X787398Y15953I1017J965D01*
G03X787419Y15392I295J-270D01*
G02X787484Y13273I-1031J-1092D01*
G03Y12727I292J-273D01*
G02X787428Y10616I-1096J-1027D01*
G37*
G36*
G01X1026852Y7567D02*
G03X1027440Y7522I315J247D01*
G02X1027341Y5581I960J-1022D01*
G03X1026751Y5597I-302J-262D01*
G02X1026852Y7567I-1081J1043D01*
G37*
G36*
G01X753005Y1417D02*
G03X753573Y1396I294J271D01*
G02X753495Y-717I1027J-1096D01*
G03X752927Y-696I-294J-271D01*
G02X753005Y1417I-1027J1096D01*
G37*
G36*
G01X755174Y-5280D02*
G03X754602I-286J-280D01*
G02Y-3320I-1002J980D01*
G03X755174I286J280D01*
G02Y-5280I1002J-980D01*
G37*
G36*
G01X1115428Y-5436D02*
G03X1115434Y-5993I290J-275D01*
G02X1113278Y-6015I-1067J-1057D01*
G03X1113272Y-5458I-290J275D01*
G02X1113299Y-3318I1068J1057D01*
G03X1113315Y-2757I-277J289D01*
G02X1115365I1025J956D01*
G03X1115381Y-3318I293J-272D01*
G02X1115428Y-5436I-1041J-1083D01*
G37*
G36*
G01X934699Y-8133D02*
G03X934683Y-8694I277J-289D01*
G02X932633I-1025J-956D01*
G03X932617Y-8133I-293J272D01*
G02X932570Y-6015I1041J1083D01*
G03X932564Y-5458I-290J275D01*
G02X932591Y-3318I1068J1057D01*
G03X932607Y-2757I-277J289D01*
G02X934657I1025J956D01*
G03X934673Y-3318I293J-272D01*
G02X934720Y-5436I-1041J-1083D01*
G03X934726Y-5993I290J-275D01*
G02X934699Y-8133I-1068J-1057D01*
G37*
G36*
G01X897888D02*
G03X897872Y-8694I277J-289D01*
G02X895822I-1025J-956D01*
G03X895806Y-8133I-293J272D01*
G02X895759Y-6015I1041J1083D01*
G03X895753Y-5458I-290J275D01*
G02X895780Y-3318I1068J1057D01*
G03X895796Y-2757I-277J289D01*
G02X897846I1025J956D01*
G03X897862Y-3318I293J-272D01*
G02X897909Y-5436I-1041J-1083D01*
G03X897915Y-5993I290J-275D01*
G02X897888Y-8133I-1068J-1057D01*
G37*
G36*
G01X861077D02*
G03X861061Y-8694I277J-289D01*
G02X859011I-1025J-956D01*
G03X858995Y-8133I-293J272D01*
G02X858948Y-6015I1041J1083D01*
G03X858942Y-5458I-290J275D01*
G02X858969Y-3318I1068J1057D01*
G03X858985Y-2757I-277J289D01*
G02X861035I1025J956D01*
G03X861051Y-3318I293J-272D01*
G02X861098Y-5436I-1041J-1083D01*
G03X861104Y-5993I290J-275D01*
G02X861077Y-8133I-1068J-1057D01*
G37*
G36*
G01X824266D02*
G03X824250Y-8694I277J-289D01*
G02X822200I-1025J-956D01*
G03X822184Y-8133I-293J272D01*
G02X822137Y-6015I1041J1083D01*
G03X822131Y-5458I-290J275D01*
G02X822158Y-3318I1068J1057D01*
G03X822174Y-2757I-277J289D01*
G02X824224I1025J956D01*
G03X824240Y-3318I293J-272D01*
G02X824287Y-5436I-1041J-1083D01*
G03X824293Y-5993I290J-275D01*
G02X824266Y-8133I-1068J-1057D01*
G37*
G36*
G01X787455D02*
G03X787439Y-8694I277J-289D01*
G02X785389I-1025J-956D01*
G03X785373Y-8133I-293J272D01*
G02X785326Y-6015I1041J1083D01*
G03X785320Y-5458I-290J275D01*
G02X785347Y-3318I1068J1057D01*
G03X785363Y-2757I-277J289D01*
G02X787413I1025J956D01*
G03X787429Y-3318I293J-272D01*
G02X787476Y-5436I-1041J-1083D01*
G03X787482Y-5993I290J-275D01*
G02X787455Y-8133I-1068J-1057D01*
G37*
G36*
G01X1225830Y-8143D02*
G03X1225820Y-8715I274J-291D01*
G02X1223808Y-8732I-998J-985D01*
G03X1223788Y-8160I-289J276D01*
G02X1223712Y-6015I1012J1110D01*
G03X1223706Y-5458I-290J275D01*
G02X1223733Y-3318I1068J1057D01*
G03X1223749Y-2757I-277J289D01*
G02X1225799I1025J956D01*
G03X1225815Y-3318I293J-272D01*
G02X1225862Y-5436I-1041J-1083D01*
G03X1225868Y-5993I290J-275D01*
G02X1225830Y-8143I-1068J-1056D01*
G37*
G36*
G01X1189019D02*
G03X1189009Y-8715I274J-291D01*
G02X1186997Y-8732I-998J-985D01*
G03X1186977Y-8160I-289J276D01*
G02X1186901Y-6015I1012J1110D01*
G03X1186895Y-5458I-290J275D01*
G02X1186922Y-3318I1068J1057D01*
G03X1186938Y-2757I-277J289D01*
G02X1188988I1025J956D01*
G03X1189004Y-3318I293J-272D01*
G02X1189051Y-5436I-1041J-1083D01*
G03X1189057Y-5993I290J-275D01*
G02X1189019Y-8143I-1068J-1056D01*
G37*
G36*
G01X1152208D02*
G03X1152198Y-8715I274J-291D01*
G02X1150186Y-8732I-998J-985D01*
G03X1150166Y-8160I-289J276D01*
G02X1150090Y-6015I1012J1110D01*
G03X1150084Y-5458I-290J275D01*
G02X1150111Y-3318I1068J1057D01*
G03X1150127Y-2757I-277J289D01*
G02X1152177I1025J956D01*
G03X1152193Y-3318I293J-272D01*
G02X1152240Y-5436I-1041J-1083D01*
G03X1152246Y-5993I290J-275D01*
G02X1152208Y-8143I-1068J-1056D01*
G37*
G36*
G01X1230919Y-8339D02*
G03X1230906Y-8901I278J-288D01*
G02X1228858Y-8911I-1019J-963D01*
G03X1228840Y-8350I-293J271D01*
G02X1228781Y-6230I1034J1090D01*
G03Y-5681I-291J274D01*
G02X1228874Y-3531I1093J1030D01*
G03X1228899Y-2959I-267J298D01*
G02X1230910Y-2995I1023J959D01*
G03X1230914Y-3568I281J-285D01*
G02X1230967Y-5681I-1040J-1083D01*
G03Y-6230I291J-274D01*
G02X1230919Y-8339I-1093J-1030D01*
G37*
G36*
G01X1194108D02*
G03X1194095Y-8901I278J-288D01*
G02X1192047Y-8911I-1019J-963D01*
G03X1192029Y-8350I-293J271D01*
G02X1191970Y-6230I1034J1090D01*
G03Y-5681I-291J274D01*
G02X1192063Y-3531I1093J1030D01*
G03X1192088Y-2959I-267J298D01*
G02X1194099Y-2995I1023J959D01*
G03X1194103Y-3568I281J-285D01*
G02X1194156Y-5681I-1040J-1083D01*
G03Y-6230I291J-274D01*
G02X1194108Y-8339I-1093J-1030D01*
G37*
G36*
G01X1157297D02*
G03X1157284Y-8901I278J-288D01*
G02X1155236Y-8911I-1019J-963D01*
G03X1155218Y-8350I-293J271D01*
G02X1155159Y-6230I1034J1090D01*
G03Y-5681I-291J274D01*
G02X1155252Y-3531I1093J1030D01*
G03X1155277Y-2959I-267J298D01*
G02X1157288Y-2995I1023J959D01*
G03X1157292Y-3568I281J-285D01*
G02X1157345Y-5681I-1040J-1083D01*
G03Y-6230I291J-274D01*
G02X1157297Y-8339I-1093J-1030D01*
G37*
G36*
G01X1120485D02*
G03X1120472Y-8901I278J-288D01*
G02X1118424Y-8911I-1019J-963D01*
G03X1118406Y-8350I-293J271D01*
G02X1118347Y-6230I1034J1090D01*
G03Y-5681I-291J274D01*
G02X1120533I1093J1030D01*
G03Y-6230I291J-274D01*
G02X1120485Y-8339I-1093J-1030D01*
G37*
G36*
G01X939777D02*
G03X939764Y-8901I278J-288D01*
G02X937716Y-8911I-1019J-963D01*
G03X937698Y-8350I-293J271D01*
G02X937639Y-6230I1034J1090D01*
G03Y-5681I-291J274D01*
G02X937702Y-3557I1093J1031D01*
G03X937723Y-2996I-274J291D01*
G02X939773Y-3017I1035J946D01*
G03X939783Y-3578I290J-275D01*
G02X939825Y-5681I-1051J-1073D01*
G03Y-6230I291J-274D01*
G02X939777Y-8339I-1093J-1030D01*
G37*
G36*
G01X902966D02*
G03X902953Y-8901I278J-288D01*
G02X900905Y-8911I-1019J-963D01*
G03X900887Y-8350I-293J271D01*
G02X900828Y-6230I1034J1090D01*
G03Y-5681I-291J274D01*
G02X900891Y-3557I1093J1031D01*
G03X900912Y-2996I-274J291D01*
G02X902962Y-3017I1035J946D01*
G03X902972Y-3578I290J-275D01*
G02X903014Y-5681I-1051J-1073D01*
G03Y-6230I291J-274D01*
G02X902966Y-8339I-1093J-1030D01*
G37*
G36*
G01X866155D02*
G03X866142Y-8901I278J-288D01*
G02X864094Y-8911I-1019J-963D01*
G03X864076Y-8350I-293J271D01*
G02X864017Y-6230I1034J1090D01*
G03Y-5681I-291J274D01*
G02X864080Y-3557I1093J1031D01*
G03X864101Y-2996I-274J291D01*
G02X866151Y-3017I1035J946D01*
G03X866161Y-3578I290J-275D01*
G02X866203Y-5681I-1051J-1073D01*
G03Y-6230I291J-274D01*
G02X866155Y-8339I-1093J-1030D01*
G37*
G36*
G01X829344D02*
G03X829331Y-8901I278J-288D01*
G02X827283Y-8911I-1019J-963D01*
G03X827265Y-8350I-293J271D01*
G02X827206Y-6230I1034J1090D01*
G03Y-5681I-291J274D01*
G02X827269Y-3557I1093J1031D01*
G03X827290Y-2996I-274J291D01*
G02X829340Y-3017I1035J946D01*
G03X829350Y-3578I290J-275D01*
G02X829392Y-5681I-1051J-1073D01*
G03Y-6230I291J-274D01*
G02X829344Y-8339I-1093J-1030D01*
G37*
G36*
G01X792533D02*
G03X792520Y-8901I278J-288D01*
G02X790472Y-8911I-1019J-963D01*
G03X790454Y-8350I-293J271D01*
G02X790395Y-6230I1034J1090D01*
G03Y-5681I-291J274D01*
G02X790458Y-3557I1093J1031D01*
G03X790479Y-2996I-274J291D01*
G02X792529Y-3017I1035J946D01*
G03X792539Y-3578I290J-275D01*
G02X792581Y-5681I-1051J-1073D01*
G03Y-6230I291J-274D01*
G02X792533Y-8339I-1093J-1030D01*
G37*
G36*
G01X1300447Y-16726D02*
G03X1300497Y-17327I287J-279D01*
G02X1298451Y-17453I-947J-1292D01*
G03X1298427Y-16850I-274J291D01*
G02X1300447Y-16726I942J1170D01*
G37*
G36*
G01X1100176Y85691D02*
G02X1099881Y84189I1005J-977D01*
G03X1099223Y84319I-371J-149D01*
G02X1099518Y85821I-1005J977D01*
G03X1100176Y85691I371J149D01*
G37*
G36*
G01X768870Y85952D02*
G02X768137Y84373I630J-1252D01*
G03X767553Y84630I-389J-93D01*
G02X765872Y84781I-729J1313D01*
G03X765244Y84611I-253J-310D01*
G02X764776Y86218I-1314J489D01*
G03X765397Y86412I241J319D01*
G02X768298Y86233I1427J-469D01*
G03X768870Y85952I393J77D01*
G37*
G36*
G01X1253093Y84043D02*
G02Y85471I-1322J714D01*
G03X1253796I352J190D01*
G02X1256439I1321J-714D01*
G03X1257143I352J191D01*
G02X1259786I1321J-714D01*
G03X1260489I352J190D01*
G02X1263132I1322J-714D01*
G03X1263836I352J191D01*
G02Y84043I1321J-714D01*
G03X1263132I-352J-191D01*
G02X1260489I-1322J714D01*
G03X1259786I-351J-190D01*
G02X1257143I-1322J714D01*
G03X1256439I-352J-191D01*
G02X1253796I-1322J714D01*
G03X1253093I-352J-190D01*
G37*
G36*
G01X1024615Y75306D02*
G02X1023185I-715J-1206D01*
G03Y75994I-204J344D01*
G02X1024615I715J1206D01*
G03Y75306I204J-344D01*
G37*
G36*
G01X1266990Y74673D02*
G02X1266871Y72814I986J-996D01*
G03X1266261Y72839I-316J-246D01*
G02X1263836Y73143I-1104J1018D01*
G03X1263132I-352J-191D01*
G02X1260489I-1322J714D01*
G03X1259786I-351J-190D01*
G02X1257143I-1322J714D01*
G03X1256439I-352J-191D01*
G02X1253796I-1322J714D01*
G03X1253093I-352J-190D01*
G02Y74571I-1322J714D01*
G03X1253796I352J190D01*
G02X1256439I1321J-714D01*
G03X1257143I352J191D01*
G02X1259786I1321J-714D01*
G03X1260489I352J190D01*
G02X1263132I1322J-714D01*
G03X1263836I352J191D01*
G02X1266382Y74726I1321J-714D01*
G03X1266990Y74673I326J231D01*
G37*
G36*
G01X1099124Y69174D02*
G02X1097365Y69189I-889J-1084D01*
G03X1097370Y69812I-249J314D01*
G02X1097307Y71926I889J1084D01*
G03X1097296Y72523I-271J294D01*
G02X1099308Y74456I910J1066D01*
G03X1099969Y74503I315J248D01*
G02X1100080Y72932I1212J-704D01*
G03X1099419Y72885I-315J-248D01*
G02X1099159Y72559I-1214J702D01*
G03X1099170Y71962I271J-294D01*
G02X1099129Y69797I-911J-1066D01*
G03X1099124Y69174I249J-314D01*
G37*
G36*
G01X1256439Y64985D02*
G02Y66413I-1321J714D01*
G03X1257143I352J191D01*
G02X1259786I1321J-714D01*
G03X1260489I352J190D01*
G02X1263132I1322J-714D01*
G03X1263836I352J191D01*
G02Y64985I1321J-714D01*
G03X1263132I-352J-191D01*
G02X1260489I-1322J714D01*
G03X1259786I-351J-190D01*
G02X1257143I-1322J714D01*
G03X1256439I-352J-191D01*
G37*
G36*
G01X1302167Y61223D02*
G02Y62777I-1167J777D01*
G03X1302833I333J222D01*
G02Y61223I1167J-777D01*
G03X1302167I-333J-222D01*
G37*
G36*
G01X1319118Y61167D02*
G02X1317564I-777J-1167D01*
G03Y61833I-222J333D01*
G02X1319118I777J1167D01*
G03Y61167I222J-333D01*
G37*
G36*
G01X1012148Y54128D02*
G02Y55556I-1322J714D01*
G03X1012851I352J190D01*
G02Y54128I1322J-714D01*
G03X1012148I-352J-190D01*
G37*
G36*
G01X1267068Y55471D02*
G02X1266846Y53680I954J-1028D01*
G03X1266226Y53744I-336J-218D01*
G02X1263836Y54085I-1069J1055D01*
G03X1263132I-352J-191D01*
G02X1260489I-1322J714D01*
G03X1259786I-351J-190D01*
G02X1257143I-1322J714D01*
G03X1256439I-352J-191D01*
G02X1253796I-1322J714D01*
G03X1253093I-352J-190D01*
G02X1250437Y54108I-1322J714D01*
G03X1249734Y54120I-355J-184D01*
G02X1249759Y55548I-1309J737D01*
G03X1250462Y55536I355J184D01*
G02X1253093Y55513I1309J-737D01*
G03X1253796I352J190D01*
G02X1256439I1321J-714D01*
G03X1257143I352J191D01*
G02X1259786I1321J-714D01*
G03X1260489I352J190D01*
G02X1263132I1322J-714D01*
G03X1263836I352J191D01*
G02X1266451Y55561I1321J-714D01*
G03X1267068Y55471I345J203D01*
G37*
G36*
G01X1215655Y51039D02*
G02X1213912Y51217I-995J-1125D01*
G03X1213990Y51852I-199J347D01*
G02X1215707Y51677I971J1012D01*
G03X1215655Y51039I213J-338D01*
G37*
G36*
G01X1105090Y50793D02*
G02X1103323Y50763I-863J-1229D01*
G03X1103325Y51400I-241J319D01*
G02X1105066Y51430I852J1114D01*
G03X1105090Y50793I254J-309D01*
G37*
G36*
G01X1100010Y47672D02*
G02X1099974Y46187I1171J-771D01*
G03X1099296Y46203I-344J-204D01*
G02X1099332Y47688I-1171J771D01*
G03X1100010Y47672I344J204D01*
G37*
G36*
G01X1253093Y46243D02*
G02Y47671I-1322J714D01*
G03X1253796I352J190D01*
G02X1256439I1321J-714D01*
G03X1257143I352J191D01*
G02X1259786I1321J-714D01*
G03X1260489I352J190D01*
G02X1263132I1322J-714D01*
G03X1263836I352J191D01*
G02X1266218Y48020I1321J-714D01*
G03X1266824Y48068I282J283D01*
G02X1267015Y46208I1135J-823D01*
G03X1266412Y46132I-269J-296D01*
G02X1263836Y46243I-1255J825D01*
G03X1263132I-352J-191D01*
G02X1260489I-1322J714D01*
G03X1259786I-351J-190D01*
G02X1257143I-1322J714D01*
G03X1256439I-352J-191D01*
G02X1253796I-1322J714D01*
G03X1253093I-352J-190D01*
G37*
G36*
G01Y35343D02*
G02Y36771I-1322J714D01*
G03X1253796I352J190D01*
G02X1256439I1321J-714D01*
G03X1257143I352J191D01*
G02X1259786I1321J-714D01*
G03X1260489I352J190D01*
G02X1263132I1322J-714D01*
G03X1263836I352J191D01*
G02Y35343I1321J-714D01*
G03X1263132I-352J-191D01*
G02X1260489I-1322J714D01*
G03X1259786I-351J-190D01*
G02X1257143I-1322J714D01*
G03X1256439I-352J-191D01*
G02X1253796I-1322J714D01*
G03X1253093I-352J-190D01*
G37*
G36*
G01X1012148Y35228D02*
G02Y36656I-1322J714D01*
G03X1012851I352J190D01*
G02Y35228I1322J-714D01*
G03X1012148I-352J-190D01*
G37*
G36*
G01X1099301Y35187D02*
G02X1099201Y36520I-1279J574D01*
G03X1099902Y36573I336J217D01*
G02X1100002Y35240I1279J-574D01*
G03X1099301Y35187I-336J-217D01*
G37*
G36*
G01X1012148Y27300D02*
G02Y28728I-1322J714D01*
G03X1012851I352J190D01*
G02Y27300I1322J-714D01*
G03X1012148I-352J-190D01*
G37*
G36*
G01X1253093Y27185D02*
G02Y28613I-1322J714D01*
G03X1253796I352J190D01*
G02X1256439I1321J-714D01*
G03X1257143I352J191D01*
G02X1259786I1321J-714D01*
G03X1260489I352J190D01*
G02X1263132I1322J-714D01*
G03X1263836I352J191D01*
G02X1266121Y29051I1321J-714D01*
G03X1266729Y29166I257J306D01*
G02X1267108Y27380I1231J-672D01*
G03X1266506Y27239I-243J-317D01*
G02X1263836Y27185I-1349J660D01*
G03X1263132I-352J-191D01*
G02X1260489I-1322J714D01*
G03X1259786I-351J-190D01*
G02X1257143I-1322J714D01*
G03X1256439I-352J-191D01*
G02X1253796I-1322J714D01*
G03X1253093I-352J-190D01*
G37*
G36*
G01X1031207Y24330D02*
G02X1029654Y24304I-757J-1180D01*
G03X1029643Y24970I-227J329D01*
G02X1031196Y24996I757J1180D01*
G03X1031207Y24330I227J-329D01*
G37*
G36*
G01X1025138Y18699D02*
G02X1023567Y19642I-1398J-549D01*
G03X1023893Y20185I-47J397D01*
G02X1025464Y19242I1398J549D01*
G03X1025138Y18699I47J-397D01*
G37*
G36*
G01X1256439Y16285D02*
G02Y17713I-1321J714D01*
G03X1257143I352J191D01*
G02X1259786I1321J-714D01*
G03X1260489I352J190D01*
G02X1263132I1322J-714D01*
G03X1263836I352J191D01*
G02Y16285I1321J-714D01*
G03X1263132I-352J-191D01*
G02X1260489I-1322J714D01*
G03X1259786I-351J-190D01*
G02X1257143I-1322J714D01*
G03X1256439I-352J-191D01*
G37*
G36*
G01X1012148Y8400D02*
G02Y9828I-1322J714D01*
G03X1012851I352J190D01*
G02Y8400I1322J-714D01*
G03X1012148I-352J-190D01*
G37*
G36*
G01X1260024Y10242D02*
G02X1259973Y8004I976J-1142D01*
G03X1259440Y8015I-273J-293D01*
G02X1257143Y8443I-976J1142D01*
G03X1256439I-352J-191D01*
G02X1253796I-1322J714D01*
G03X1253093I-352J-190D01*
G02Y9871I-1322J714D01*
G03X1253796I352J190D01*
G02X1256439I1321J-714D01*
G03X1257143I352J191D01*
G02X1259491Y10253I1321J-714D01*
G03X1260024Y10242I273J293D01*
G37*
G36*
G01X1253093Y-2457D02*
G02Y-1029I-1322J714D01*
G03X1253796I352J190D01*
G02X1256439I1321J-714D01*
G03X1257143I352J191D01*
G02X1259786I1321J-714D01*
G03X1260489I352J190D01*
G02X1263132I1322J-714D01*
G03X1263836I352J191D01*
G02Y-2457I1321J-714D01*
G03X1263132I-352J-191D01*
G02X1260489I-1322J714D01*
G03X1259786I-351J-190D01*
G02X1257143I-1322J714D01*
G03X1256439I-352J-191D01*
G02X1253796I-1322J714D01*
G03X1253093I-352J-190D01*
G37*
G36*
G01X1012148Y-2572D02*
G02Y-1144I-1322J714D01*
G03X1012851I352J190D01*
G02Y-2572I1322J-714D01*
G03X1012148I-352J-190D01*
G37*
G36*
G01X1030454Y-7537D02*
G02X1029044Y-8610I-47J-1401D01*
G03X1028652Y-8117I-389J93D01*
G02X1030083Y-7027I-13J1502D01*
G03X1030454Y-7537I385J-110D01*
G37*
G36*
G01X1012148Y-10500D02*
G02Y-9072I-1322J714D01*
G03X1012851I352J190D01*
G02Y-10500I1322J-714D01*
G03X1012148I-352J-190D01*
G37*
G36*
G01X1256439Y-10615D02*
G02Y-9187I-1321J714D01*
G03X1257143I352J191D01*
G02X1259786I1321J-714D01*
G03X1260489I352J190D01*
G02X1263132I1322J-714D01*
G03X1263836I352J191D01*
G02Y-10615I1321J-714D01*
G03X1263132I-352J-191D01*
G02X1260489I-1322J714D01*
G03X1259786I-351J-190D01*
G02X1257143I-1322J714D01*
G03X1256439I-352J-191D01*
G37*
G36*
G01X1280343Y-15495D02*
G02X1280321Y-14060I-1443J696D01*
G03X1281025Y-14068I354J186D01*
G02X1283184Y-13700I1227J-679D01*
G03X1283763Y-13650I266J299D01*
G02X1283927Y-15571I1096J-874D01*
G03X1283348Y-15621I-266J-299D01*
G02X1281047Y-15464I-1096J874D01*
G03X1280343Y-15495I-344J-205D01*
G37*
G36*
G01X1069992Y337612D02*
G03X1069392I-300J-265D01*
G02Y339734I-1200J1061D01*
G03X1069992I300J265D01*
G02Y337612I1200J-1061D01*
G37*
G36*
G01X1062792D02*
G03X1062192I-300J-265D01*
G02Y339734I-1200J1061D01*
G03X1062792I300J265D01*
G02Y337612I1200J-1061D01*
G37*
G36*
G01X1079082Y337472D02*
G03X1078482I-300J-265D01*
G02Y339594I-1200J1061D01*
G03X1079082I300J265D01*
G02Y337472I1200J-1061D01*
G37*
G36*
G01X1049571Y337418D02*
G03X1048941I-315J-246D01*
G02Y339264I-1185J923D01*
G03X1049571I315J246D01*
G02X1051899Y339316I1185J-923D01*
G03X1052518Y339329I304J259D01*
G02X1054791Y339438I1183J-925D01*
G03X1055423Y339505I290J275D01*
G02X1055588Y337617I1369J-832D01*
G03X1054954Y337574I-301J-264D01*
G02X1052559Y337429I-1252J830D01*
G03X1051940Y337416I-304J-259D01*
G02X1049571Y337418I-1184J925D01*
G37*
G36*
G01X844127Y330490D02*
G03X843573I-277J-288D01*
G02Y332510I-973J1010D01*
G03X844127I277J288D01*
G02X846073I973J-1010D01*
G03X846627I277J288D01*
G02Y330490I973J-1010D01*
G03X846073I-277J-288D01*
G02X844127I-973J1010D01*
G37*
G36*
G01X1018043Y325226D02*
G03X1017834Y324747I173J-361D01*
G02X1015749Y325658I-1435J-443D01*
G03X1015958Y326137I-173J361D01*
G02X1018380Y327712I1435J443D01*
G03X1018906I263J302D01*
G02X1020880I987J-1132D01*
G03X1021406I263J302D01*
G02X1023380I987J-1132D01*
G03X1023906I263J302D01*
G02X1024177Y327900I986J-1133D01*
G03X1024358Y328399I-191J352D01*
G02X1026552Y330224I1397J552D01*
G03X1027107Y330356I213J339D01*
G02X1028790Y328131I1286J-776D01*
G03X1028580Y327501I106J-385D01*
G02X1026406Y325448I-1186J-921D01*
G03X1025880I-263J-302D01*
G02X1023906I-987J1132D01*
G03X1023380I-263J-302D01*
G02X1021406I-987J1132D01*
G03X1020880I-263J-302D01*
G02X1018906I-987J1132D01*
G03X1018380I-263J-302D01*
G02X1018043Y325226I-987J1132D01*
G37*
G36*
G01X1077820Y323113D02*
G03X1077220I-300J-265D01*
G02Y325235I-1200J1061D01*
G03X1077820I300J265D01*
G02Y323113I1200J-1061D01*
G37*
G36*
G01X1017207Y311236D02*
G03X1016654Y311109I-213J-338D01*
G02X1016286Y313212I-1361J846D01*
G03X1016850Y313281I248J314D01*
G02X1018914Y313445I1107J-860D01*
G03X1019458Y313442I274J292D01*
G02X1021395Y313399I946J-1034D01*
G03X1021953Y313391I283J283D01*
G02X1023893Y313377I963J-1019D01*
G03X1024453Y313379I279J286D01*
G02X1026438Y313364I985J-998D01*
G03X1027015Y313371I285J281D01*
G02X1027039Y311431I1024J-957D01*
G03X1026462Y311424I-285J-281D01*
G02X1024460Y311376I-1025J957D01*
G03X1023900Y311374I-279J-286D01*
G02X1021924Y311381I-984J998D01*
G03X1021366Y311389I-283J-283D01*
G02X1019447Y311384I-962J1019D01*
G03X1018903Y311387I-274J-292D01*
G02X1017207Y311236I-947J1034D01*
G37*
G36*
G01X844127Y298890D02*
G03X843573I-277J-288D01*
G02Y300910I-973J1010D01*
G03X844127I277J288D01*
G02X846073I973J-1010D01*
G03X846627I277J288D01*
G02Y298890I973J-1010D01*
G03X846073I-277J-288D01*
G02X844127I-973J1010D01*
G37*
G36*
G01X1048167Y294798D02*
G03X1047567I-300J-265D01*
G02Y296920I-1200J1061D01*
G03X1048167I300J265D01*
G02Y294798I1200J-1061D01*
G37*
G36*
G01X1040967D02*
G03X1040367I-300J-265D01*
G02Y296920I-1200J1061D01*
G03X1040967I300J265D01*
G02Y294798I1200J-1061D01*
G37*
G36*
G01X1033767D02*
G03X1033167I-300J-265D01*
G02Y296920I-1200J1061D01*
G03X1033767I300J265D01*
G02Y294798I1200J-1061D01*
G37*
G36*
G01X1026567D02*
G03X1025967I-300J-265D01*
G02Y296920I-1200J1061D01*
G03X1026567I300J265D01*
G02Y294798I1200J-1061D01*
G37*
G36*
G01X1019367D02*
G03X1018767I-300J-265D01*
G02Y296920I-1200J1061D01*
G03X1019367I300J265D01*
G02Y294798I1200J-1061D01*
G37*
G36*
G01X1026702Y277843D02*
G03X1026102I-300J-265D01*
G02Y279965I-1200J1061D01*
G03X1026702I300J265D01*
G02Y277843I1200J-1061D01*
G37*
G36*
G01X1019502D02*
G03X1018902I-300J-265D01*
G02Y279965I-1200J1061D01*
G03X1019502I300J265D01*
G02Y277843I1200J-1061D01*
G37*
G36*
G01X1031550Y272689D02*
G03Y272089I265J-300D01*
G02X1029428I-1061J-1200D01*
G03Y272689I-265J300D01*
G02X1031550I1061J1200D01*
G37*
G36*
G01X844127Y267190D02*
G03X843573I-277J-288D01*
G02Y269210I-973J1010D01*
G03X844127I277J288D01*
G02X846073I973J-1010D01*
G03X846627I277J288D01*
G02Y267190I973J-1010D01*
G03X846073I-277J-288D01*
G02X844127I-973J1010D01*
G37*
G36*
G01X1048817Y263976D02*
G03X1048187I-315J-246D01*
G02Y265822I-1185J923D01*
G03X1048817I315J246D01*
G02Y263976I1185J-923D01*
G37*
G36*
G01X1042317D02*
G03X1041687I-315J-246D01*
G02Y265822I-1185J923D01*
G03X1042317I315J246D01*
G02Y263976I1185J-923D01*
G37*
G36*
G01X848610Y239927D02*
G03Y239373I288J-277D01*
G02X846590I-1010J-973D01*
G03Y239927I-288J277D01*
G02Y241873I1010J973D01*
G03Y242427I-288J277D01*
G02X848610I1010J973D01*
G03Y241873I288J-277D01*
G02Y239927I-1010J-973D01*
G37*
G36*
G01X842410Y239827D02*
G03Y239273I288J-277D01*
G02X840390I-1010J-973D01*
G03Y239827I-288J277D01*
G02Y241773I1010J973D01*
G03Y242327I-288J277D01*
G02X842410I1010J973D01*
G03Y241773I288J-277D01*
G02Y239827I-1010J-973D01*
G37*
G36*
G01X1036980Y323069D02*
G02Y325279I-1160J1105D01*
G03X1037560I290J275D01*
G02X1039820Y325338I1160J-1105D01*
G03X1040370I275J291D01*
G02X1042570I1100J-1164D01*
G03X1043120I275J291D01*
G02X1045420Y325235I1100J-1164D01*
G03X1046020I300J265D01*
G02X1048420I1200J-1061D01*
G03X1049020I300J265D01*
G02X1051420I1200J-1061D01*
G03X1052020I300J265D01*
G02X1054420I1200J-1061D01*
G03X1055020I300J265D01*
G02X1057420I1200J-1061D01*
G03X1058020I300J265D01*
G02X1060420I1200J-1061D01*
G03X1061020I300J265D01*
G02X1063420I1200J-1061D01*
G03X1064020I300J265D01*
G02X1066660Y324875I1200J-1061D01*
G03X1067380I360J175D01*
G02X1070020Y325235I1440J-701D01*
G03X1070620I300J265D01*
G02Y323113I1200J-1061D01*
G03X1070020I-300J-265D01*
G02X1067380Y323473I-1200J1061D01*
G03X1066660I-360J-175D01*
G02X1064020Y323113I-1440J701D01*
G03X1063420I-300J-265D01*
G02X1061020I-1200J1061D01*
G03X1060420I-300J-265D01*
G02X1058020I-1200J1061D01*
G03X1057420I-300J-265D01*
G02X1055020I-1200J1061D01*
G03X1054420I-300J-265D01*
G02X1052020I-1200J1061D01*
G03X1051420I-300J-265D01*
G02X1049020I-1200J1061D01*
G03X1048420I-300J-265D01*
G02X1046020I-1200J1061D01*
G03X1045420I-300J-265D01*
G02X1043120Y323010I-1200J1061D01*
G03X1042570I-275J-291D01*
G02X1040370I-1100J1164D01*
G03X1039820I-275J-291D01*
G02X1037560Y323069I-1100J1164D01*
G03X1036980I-290J-275D01*
G37*
G36*
G01X1037239Y278042D02*
G02X1037181Y279611I-1425J733D01*
G03X1037877Y279637I341J209D01*
G02X1040502Y279965I1425J-733D01*
G03X1041102I300J265D01*
G02Y277843I1200J-1061D01*
G03X1040502I-300J-265D01*
G02X1037935Y278068I-1200J1061D01*
G03X1037239Y278042I-341J-209D01*
G37*
G36*
G01X1113707Y314299D02*
G03X1113702Y313770I298J-267D01*
G02X1111298Y313793I-1212J-1047D01*
G03X1111303Y314322I-298J267D01*
G02X1113707Y314299I1212J1047D01*
G37*
G36*
G01X1115399Y297711D02*
G03X1115861Y297293I399J-23D01*
G02X1114597Y295898I235J-1483D01*
G03X1114135Y296316I-399J23D01*
G02X1115399Y297711I-235J1483D01*
G37*
G36*
G01X1084167Y294798D02*
G03X1083567I-300J-265D01*
G02Y296920I-1200J1061D01*
G03X1084167I300J265D01*
G02Y294798I1200J-1061D01*
G37*
G36*
G01X1076967D02*
G03X1076367I-300J-265D01*
G02Y296920I-1200J1061D01*
G03X1076967I300J265D01*
G02Y294798I1200J-1061D01*
G37*
G36*
G01X1069767D02*
G03X1069167I-300J-265D01*
G02Y296920I-1200J1061D01*
G03X1069767I300J265D01*
G02Y294798I1200J-1061D01*
G37*
G36*
G01X1102935Y293354D02*
G03X1103463Y293233I330J227D01*
G02X1102936Y290934I793J-1392D01*
G03X1102408Y291055I-330J-227D01*
G02X1100320Y291505I-792J1392D01*
G03X1099748Y291583I-323J-236D01*
G02X1097556Y291780I-992J1258D01*
G03X1096956I-300J-265D01*
G02X1094624Y293975I-1200J1062D01*
G03X1094586Y294574I-283J283D01*
G02X1094360Y294787I981J1267D01*
G03X1093761Y294791I-301J-263D01*
G02X1091367Y294798I-1194J1068D01*
G03X1090767I-300J-265D01*
G02Y296920I-1200J1061D01*
G03X1091367I300J265D01*
G02X1093774Y296913I1200J-1061D01*
G03X1094373Y296909I301J263D01*
G02X1096767Y296902I1194J-1068D01*
G03X1097367I300J265D01*
G02X1099761Y296909I1200J-1061D01*
G03X1100360Y296913I298J267D01*
G02X1102702Y296989I1206J-1054D01*
G03X1103233Y296957I283J282D01*
G02X1103086Y294566I988J-1261D01*
G03X1102555Y294598I-283J-282D01*
G02X1102424Y294506I-985J1263D01*
G03X1102434Y293824I214J-338D01*
G02X1102935Y293354I-820J-1376D01*
G37*
G36*
G01X1097717Y280095D02*
G03X1098228I255J308D01*
G02X1098225Y277784I958J-1157D01*
G03X1097714I-256J-308D01*
G02X1097717Y280095I-958J1157D01*
G37*
G36*
G01X1084242Y277941D02*
G03X1083606I-318J-242D01*
G02Y279879I-1276J969D01*
G03X1084242I318J242D01*
G02Y277941I1276J-969D01*
G37*
G36*
G01X1077102Y277849D02*
G03X1076502I-300J-265D01*
G02Y279971I-1200J1061D01*
G03X1077102I300J265D01*
G02Y277849I1200J-1061D01*
G37*
G36*
G01X1069668Y277918D02*
G03X1069041I-314J-248D01*
G02Y279902I-1258J992D01*
G03X1069668I314J248D01*
G02Y277918I1258J-992D01*
G37*
G36*
G01X1109765Y275810D02*
G03X1109221Y275772I-252J-311D01*
G02X1109137Y277909I-1096J1027D01*
G03X1109682Y277915I269J296D01*
G02X1109765Y275810I966J-1016D01*
G37*
G36*
G01X1102046Y273345D02*
G03X1101576Y273030I-78J-392D01*
G02X1100397Y274688I-1376J270D01*
G03X1100849Y275028I56J396D01*
G02X1102046Y273345I1487J-209D01*
G37*
G36*
G01X1096677Y267649D02*
G03Y267041I260J-304D01*
G02X1094723I-977J-1141D01*
G03Y267649I-260J304D01*
G02X1096677I977J1141D01*
G37*
G36*
G01X1215224Y266528D02*
G03Y267082I-288J277D01*
G02X1215718Y269359I1010J973D01*
G03X1215932Y269901I-148J371D01*
G02X1217716Y269196I1268J599D01*
G03X1217502Y268654I148J-371D01*
G02X1217244Y267082I-1268J-599D01*
G03Y266528I288J-277D01*
G02X1215586Y264312I-1010J-973D01*
G03X1215047Y264144I-185J-355D01*
G02X1214456Y266043I-1239J656D01*
G03X1214995Y266211I185J355D01*
G02X1215224Y266528I1240J-655D01*
G37*
G36*
G01X1074367Y266089D02*
G03X1074899Y266044I291J274D01*
G02X1074698Y263668I966J-1278D01*
G03X1074166Y263713I-291J-274D01*
G02X1072074Y263851I-966J1278D01*
G03X1071495Y263833I-281J-285D01*
G02X1071426Y266040I-1195J1067D01*
G03X1072005Y266058I281J285D01*
G02X1074367Y266089I1195J-1067D01*
G37*
G36*
G01X1160440Y261386D02*
G03X1160444Y260810I279J-286D01*
G02X1158360Y260794I-1034J-1090D01*
G03X1158356Y261370I-279J286D01*
G02X1158455Y263636I1034J1090D01*
G03X1158511Y264208I-249J313D01*
G02X1158176Y265100I1067J910D01*
G03X1157786Y265494I-400J-6D01*
G02X1159222Y266913I34J1402D01*
G03X1159612Y266519I400J6D01*
G02X1160645Y266027I-34J-1402D01*
G03X1161233Y266004I305J259D01*
G02X1161110Y264030I1067J-1057D01*
G03X1160523Y264082I-317J-243D01*
G02X1160507Y264067I-966J1015D01*
G03X1160481Y263492I265J-300D01*
G02X1160440Y261386I-1091J-1032D01*
G37*
G36*
G01X1275468Y254991D02*
G03X1275795Y254508I390J-88D01*
G02X1274209Y253432I-218J-1385D01*
G03X1273882Y253915I-390J88D01*
G02X1275468Y254991I218J1385D01*
G37*
G36*
G01X1218566Y244363D02*
G03X1219170Y244341I312J251D01*
G02X1219104Y242503I1024J-957D01*
G03X1218500Y242525I-312J-251D01*
G02X1216404Y242579I-1024J957D01*
G03X1215795Y242582I-306J-258D01*
G02X1213747Y242499I-1063J914D01*
G03X1213184I-282J-285D01*
G02Y244493I-985J997D01*
G03X1213747I282J285D01*
G02X1215804Y244399I985J-997D01*
G03X1216413Y244396I306J258D01*
G02X1218566Y244363I1063J-914D01*
G37*
G36*
G01X1321324Y233905D02*
G03X1321338Y233291I263J-301D01*
G02X1319462I-938J-1173D01*
G03X1319476Y233905I-249J313D01*
G02X1319380Y235921I924J1054D01*
G03X1319341Y236506I-291J274D01*
G02X1321329Y236587I948J1165D01*
G03X1321338Y236001I277J-289D01*
G02X1321324Y233905I-938J-1042D01*
G37*
G36*
G01X1315824D02*
G03X1315838Y233291I263J-301D01*
G02X1313962I-938J-1173D01*
G03X1313976Y233905I-249J313D01*
G02X1313988Y236024I924J1054D01*
G03X1314017Y236605I-260J304D01*
G02X1316017Y236456I1083J1040D01*
G03X1315960Y235877I245J-316D01*
G02X1315824Y233905I-1060J-918D01*
G37*
G36*
G01X1321474Y217713D02*
G03X1322045Y217665I309J254D01*
G02X1321821Y215640I985J-1134D01*
G03X1321252Y215719I-323J-237D01*
G02X1321474Y217713I-862J1105D01*
G37*
G36*
G01X1323990Y208218D02*
G03X1323448I-271J-294D01*
G02Y210284I-948J1033D01*
G03X1323990I271J294D01*
G02Y208218I948J-1033D01*
G37*
G36*
G01X1330822Y207932D02*
G03X1330281Y207927I-268J-297D01*
G02X1330197Y210048I-957J1024D01*
G03X1330735Y210086I248J313D01*
G02X1332969Y210023I1089J-1035D01*
G03X1333579I305J259D01*
G02Y208079I1145J-972D01*
G03X1332969I-305J-259D01*
G02X1330822Y207932I-1145J972D01*
G37*
G36*
G01X1227949Y209453D02*
G03X1227966Y208928I310J-253D01*
G02X1225703Y208854I-1099J-1024D01*
G03X1225686Y209379I-310J253D01*
G02X1225689Y211430I1099J1024D01*
G03Y211976I-292J273D01*
G02X1225857Y214184I1096J1027D01*
G03X1225945Y214718I-247J315D01*
G02X1228128Y214362I1255J825D01*
G03X1228040Y213828I247J-315D01*
G02X1227881Y211976I-1255J-825D01*
G03Y211430I292J-273D01*
G02X1227949Y209453I-1096J-1027D01*
G37*
G36*
G01X1222396Y206973D02*
G03Y206427I292J-273D01*
G02X1220204I-1096J-1027D01*
G03Y206973I-292J273D01*
G02X1222396I1096J1027D01*
G37*
G36*
G01X1305383Y168925D02*
G03X1304823Y168924I-279J-286D01*
G02X1304818Y170925I-985J998D01*
G03X1305378Y170926I279J286D01*
G02X1305383Y168925I985J-998D01*
G37*
G36*
G01X1104888Y308828D02*
G02X1102375Y307251I-1132J-987D01*
G03X1101849Y307461I-368J-157D01*
G02X1099875Y308251I-593J1380D01*
G03X1099349Y308461I-368J-157D01*
G02X1097532Y308971I-593J1380D01*
G03X1096889Y308984I-326J-232D01*
G02X1096926Y310774I-1187J920D01*
G03X1097569Y310761I326J232D01*
G02X1100137Y310431I1187J-920D01*
G03X1100663Y310221I368J157D01*
G02X1101747Y310261I594J-1380D01*
G03X1102272Y310576I130J378D01*
G02X1104888Y309354I1484J-235D01*
G03Y308828I302J-263D01*
G37*
G36*
G01X1118706Y287537D02*
G02X1118374Y285590I815J-1141D01*
G03X1117814Y285685I-327J-230D01*
G02X1115658Y287234I-815J1141D01*
G03X1115266Y287750I-383J116D01*
G02X1113797Y289702I-36J1502D01*
G03X1113356Y290217I-382J119D01*
G02X1114565Y291252I-224J1485D01*
G03X1115006Y290737I382J-119D01*
G02X1116649Y288759I224J-1485D01*
G03X1117020Y288228I378J-131D01*
G02X1118146Y287632I-21J-1402D01*
G03X1118706Y287537I327J230D01*
G37*
G36*
G01X1327243Y278152D02*
X1323734D01*
G02X1322936Y280946I0J1511D01*
G03X1322763Y281305I-106J170D01*
G02X1322260Y281218I-505J1425D01*
G01X1318751D01*
G02X1318025Y281404I0J1512D01*
G03X1317493Y281263I-192J-351D01*
G02X1314898Y281969I-1193J737D01*
G03X1314497Y282360I-400J-9D01*
G02X1313514Y285004I-7J1502D01*
G03X1313578Y285543I-260J304D01*
G02X1315768Y285285I1214J884D01*
G03X1315704Y284746I260J-304D01*
G02X1315991Y283813I-1214J-884D01*
G03X1316371Y283400I400J-13D01*
G02X1316896Y283269I-71J-1400D01*
G03X1317418Y283443I169J362D01*
G02X1318751Y284242I1333J-713D01*
G01X1322261D01*
G02X1323551Y283517I-1J-1512D01*
G03X1324205Y283475I342J208D01*
G02X1326453Y281802I1095J-876D01*
G03X1326782Y281174I329J-228D01*
G01X1327244D01*
G02X1328422Y280609I0J-1511D01*
G03X1329023Y280584I311J251D01*
G02X1328993Y278685I1016J-966D01*
G03X1328390Y278679I-299J-266D01*
G02X1327243Y278152I-1147J984D01*
G37*
G36*
G01X1106370Y267394D02*
G02X1105573Y268628I-1499J-94D01*
G03X1106160Y268994I187J354D01*
G02X1106662Y270113I1401J44D01*
G03X1106656Y270731I-257J307D01*
G02X1108512Y270706I944J1169D01*
G03X1108489Y270089I242J-318D01*
G02X1106945Y267779I-928J-1051D01*
G03X1106370Y267394I-176J-359D01*
G37*
G36*
G01X1350658Y264710D02*
G02X1348215Y266062I-1159J790D01*
G03X1347769Y266614I-366J160D01*
G02X1347468Y266584I-300J1481D01*
G01X1343668D01*
G02X1342283Y267491I0J1511D01*
G03X1341683Y267656I-367J-160D01*
G02X1339726Y269611I-817J1139D01*
G03X1339401Y270244I-325J233D01*
G01X1336448D01*
G02X1334967Y271453I0J1511D01*
G03X1334473Y271760I-392J-80D01*
G02X1332951Y273900I-360J1355D01*
G03X1332620Y274524I-331J224D01*
G01X1330171D01*
G02X1329128Y274941I-1J1511D01*
G03X1328580Y274944I-276J-290D01*
G02X1328527Y277044I-955J1027D01*
G03X1329074Y277075I257J307D01*
G02X1330171Y277546I1096J-1040D01*
G01X1333681D01*
G02X1335192Y276045I0J-1512D01*
G01Y275950D01*
X1335182Y275866D01*
G02X1334740Y274957I-1502J168D01*
G03X1334819Y274326I280J-285D01*
G02X1335469Y273471I-706J-1211D01*
G03X1335980Y273192I387J101D01*
G02X1336448Y273266I467J-1437D01*
G01X1340249D01*
G02X1341760Y271765I0J-1512D01*
G01Y271670D01*
X1341750Y271586D01*
G02X1341337Y270707I-1502J169D01*
G03X1341457Y270067I288J-277D01*
G02X1342123Y269416I-592J-1271D01*
G03X1342730Y269280I358J177D01*
G02X1343668Y269606I938J-1185D01*
G01X1347469D01*
G02X1348980Y268105I0J-1512D01*
G01Y268010D01*
X1348970Y267926D01*
G02X1348834Y267447I-1502J168D01*
G03X1349263Y266882I361J-171D01*
G02X1350545Y266435I237J-1382D01*
G03X1351183Y266491I298J267D01*
G02X1352468Y267206I1285J-797D01*
G01X1356269D01*
G02X1357476Y266603I-1J-1511D01*
G03X1358085Y266568I319J241D01*
G02X1358023Y264703I1015J-967D01*
G03X1357413Y264708I-307J-256D01*
G02X1356268Y264184I-1144J987D01*
G01X1352468D01*
G02X1351298Y264738I-1J1511D01*
G03X1350658Y264710I-310J-253D01*
G37*
G36*
G01X1087254Y263369D02*
G02X1084819Y263312I-1193J-1069D01*
G03X1084807Y263831I-310J252D01*
G02X1084629Y264072I1194J1068D01*
G03X1083916Y264016I-342J-207D01*
G02X1081173Y263629I-1484J604D01*
G03X1080648Y263722I-314J-247D01*
G02X1080984Y265995I-789J1278D01*
G03X1081513Y265932I300J265D01*
G02X1083803Y265448I919J-1312D01*
G03X1084516Y265504I342J207D01*
G02X1087517Y265414I1484J-604D01*
G03X1087871Y265363I190J64D01*
G02X1087930Y265442I1232J-859D01*
G03X1087909Y265968I-311J251D01*
G02X1090258Y267821I1091J1032D01*
G03X1090952Y267863I335J218D01*
G02X1093212Y266006I1348J-663D01*
G03X1093154Y265425I243J-318D01*
G02X1090981Y263655I-1054J-925D01*
G03X1090333Y263643I-320J-241D01*
G02X1087692Y263978I-1233J857D01*
G03X1087337Y264018I-188J-70D01*
G02X1087242Y263888I-1339J879D01*
G03X1087254Y263369I310J-252D01*
G37*
G36*
G01X1224394Y258062D02*
G02X1223990Y259683I-1294J538D01*
G03X1224614Y259838I255J309D01*
G02X1224898Y260273I1296J-536D01*
G03Y260827I-288J277D01*
G02X1224659Y261164I1012J971D01*
G03X1224126Y261341I-356J-182D01*
G02X1224757Y263236I-618J1258D01*
G03X1225290Y263059I356J182D01*
G02X1226918Y260827I619J-1258D01*
G03Y260273I288J-277D01*
G02X1225018Y258217I-1009J-973D01*
G03X1224394Y258062I-255J-309D01*
G37*
G36*
G01X1309929Y256611D02*
G02X1309831Y254805I1021J-961D01*
G03X1309221Y254839I-319J-241D01*
G02X1306892Y256305I-1021J961D01*
G03X1306534Y256849I-373J144D01*
G02X1307893Y257745I51J1401D01*
G03X1308251Y257201I373J-144D01*
G02X1309319Y256645I-51J-1401D01*
G03X1309929Y256611I319J241D01*
G37*
G36*
G01X1381838Y233291D02*
G02X1379962I-938J-1173D01*
G03X1379976Y233905I-249J313D01*
G02X1380025Y236054I924J1054D01*
G03X1380011Y236689I-250J312D01*
G02X1381789I889J1211D01*
G03X1381775Y236054I236J-323D01*
G02X1381824Y233905I-875J-1095D01*
G03X1381838Y233291I263J-301D01*
G37*
G36*
G01X1376267Y233344D02*
G02X1374533I-867J-1226D01*
G03X1374546Y233988I-231J327D01*
G02X1374457Y236138I854J1112D01*
G03X1374443Y236742I-269J296D01*
G02X1376357I957J1158D01*
G03X1376343Y236138I255J-308D01*
G02X1376254Y233988I-943J-1038D01*
G03X1376267Y233344I244J-317D01*
G37*
G36*
G01X1370838Y233291D02*
G02X1368962I-938J-1173D01*
G03X1368976Y233905I-249J313D01*
G02X1369025Y236054I924J1054D01*
G03X1369011Y236689I-250J312D01*
G02X1370789I889J1211D01*
G03X1370775Y236054I236J-323D01*
G02X1370824Y233905I-875J-1095D01*
G03X1370838Y233291I263J-301D01*
G37*
G36*
G01X1365338D02*
G02X1363462I-938J-1173D01*
G03X1363476Y233905I-249J313D01*
G02X1363525Y236054I924J1054D01*
G03X1363511Y236689I-250J312D01*
G02X1365289I889J1211D01*
G03X1365275Y236054I236J-323D01*
G02X1365324Y233905I-875J-1095D01*
G03X1365338Y233291I263J-301D01*
G37*
G36*
G01X1359838D02*
G02X1357962I-938J-1173D01*
G03X1357976Y233905I-249J313D01*
G02X1358025Y236054I924J1054D01*
G03X1358011Y236689I-250J312D01*
G02X1359789I889J1211D01*
G03X1359775Y236054I236J-323D01*
G02X1359824Y233905I-875J-1095D01*
G03X1359838Y233291I263J-301D01*
G37*
G36*
G01X1354338D02*
G02X1352462I-938J-1173D01*
G03X1352476Y233905I-249J313D01*
G02X1352525Y236054I924J1054D01*
G03X1352511Y236689I-250J312D01*
G02X1354289I889J1211D01*
G03X1354275Y236054I236J-323D01*
G02X1354324Y233905I-875J-1095D01*
G03X1354338Y233291I263J-301D01*
G37*
G36*
G01X1348838D02*
G02X1346962I-938J-1173D01*
G03X1346976Y233905I-249J313D01*
G02X1347025Y236054I924J1054D01*
G03X1347011Y236689I-250J312D01*
G02X1348789I889J1211D01*
G03X1348775Y236054I236J-323D01*
G02X1348824Y233905I-875J-1095D01*
G03X1348838Y233291I263J-301D01*
G37*
G36*
G01X1343338D02*
G02X1341462I-938J-1173D01*
G03X1341476Y233905I-249J313D01*
G02X1341525Y236054I924J1054D01*
G03X1341511Y236689I-250J312D01*
G02X1343289I889J1211D01*
G03X1343275Y236054I236J-323D01*
G02X1343324Y233905I-875J-1095D01*
G03X1343338Y233291I263J-301D01*
G37*
G36*
G01X1337838D02*
G02X1335962I-938J-1173D01*
G03X1335976Y233905I-249J313D01*
G02X1336025Y236054I924J1054D01*
G03X1336011Y236689I-250J312D01*
G02X1337789I889J1211D01*
G03X1337775Y236054I236J-323D01*
G02X1337824Y233905I-875J-1095D01*
G03X1337838Y233291I263J-301D01*
G37*
G36*
G01X1332338D02*
G02X1330462I-938J-1173D01*
G03X1330476Y233905I-249J313D01*
G02X1330525Y236054I924J1054D01*
G03X1330511Y236689I-250J312D01*
G02X1332289I889J1211D01*
G03X1332275Y236054I236J-323D01*
G02X1332324Y233905I-875J-1095D01*
G03X1332338Y233291I263J-301D01*
G37*
G36*
G01X1326838D02*
G02X1324962I-938J-1173D01*
G03X1324976Y233905I-249J313D01*
G02X1325025Y236054I924J1054D01*
G03X1325011Y236689I-250J312D01*
G02X1326789I889J1211D01*
G03X1326775Y236054I236J-323D01*
G02X1326824Y233905I-875J-1095D01*
G03X1326838Y233291I263J-301D01*
G37*
G36*
G01X1388307Y232175D02*
G02X1387178Y230376I211J-1386D01*
G03X1386713Y230649I-382J-118D01*
G02X1385462Y233291I-313J1469D01*
G03X1385476Y233905I-249J313D01*
G02X1385525Y236054I924J1054D01*
G03X1385511Y236689I-250J312D01*
G02X1387289I889J1211D01*
G03X1387275Y236054I236J-323D01*
G02X1387324Y233905I-875J-1095D01*
G03X1387338Y233291I263J-301D01*
G02X1387859Y232475I-938J-1173D01*
G03X1388307Y232175I388J95D01*
G37*
G36*
G01X1279936Y230740D02*
G02X1278642Y229842I14J-1402D01*
G03X1278251Y230386I-373J144D01*
G02X1276758Y232359I-68J1500D01*
G03X1276433Y232882I-380J126D01*
G02X1275240Y234465I195J1388D01*
G03X1274912Y234915I-396J56D01*
G02X1276542Y236101I242J1381D01*
G03X1276870Y235651I396J-56D01*
G02X1277977Y233888I-242J-1381D01*
G03X1278324Y233381I385J-109D01*
G02X1279565Y231297I-141J-1495D01*
G03X1279936Y230740I368J-157D01*
G37*
G36*
G01X1334259Y215577D02*
G02X1331841Y215643I-1185J923D01*
G03X1331193Y215655I-328J-229D01*
G02Y217345I-1119J845D01*
G03X1331841Y217357I320J241D01*
G02X1334259Y217423I1233J-857D01*
G03X1334889I315J246D01*
G02Y215577I1185J-923D01*
G03X1334259I-315J-246D01*
G37*
G36*
G01X1220270Y214898D02*
G02X1218893Y216271I-1402J-29D01*
G03X1219300Y216679I7J400D01*
G02X1219317Y216923I1402J25D01*
G03X1218979Y217097I-198J31D01*
G02X1218210Y219486I-979J1003D01*
G03X1218658Y219980I60J396D01*
G02X1219807Y218937I1359J343D01*
G03X1219359Y218443I-60J-396D01*
G02X1219396Y218228I-1359J-345D01*
G03X1219996Y217919I398J37D01*
G02X1220677Y215306I706J-1211D01*
G03X1220270Y214898I-7J-400D01*
G37*
G36*
G01X1354924Y208312D02*
G02X1354865Y209719I-1355J648D01*
G03X1355571Y209748I345J202D01*
G02X1357899Y210244I1355J-648D01*
G03X1358441Y210265I260J304D01*
G02X1360442Y210370I1059J-1065D01*
G03X1360968Y210391I251J311D01*
G02X1361058Y208130I1032J-1091D01*
G03X1360532Y208109I-251J-311D01*
G02X1358527Y208056I-1032J1091D01*
G03X1357985Y208035I-260J-304D01*
G02X1355630Y208341I-1059J1065D01*
G03X1354924Y208312I-345J-202D01*
G37*
G36*
G01X1318333Y417768D02*
G03X1317807I-263J-302D01*
G02X1315688Y419887I-987J1132D01*
G03Y420413I-302J263D01*
G02X1317839Y420297I1132J987D01*
G03Y420003I136J-147D01*
G02X1317923Y419919I-1019J-1103D01*
G03X1318217I147J136D01*
G02X1318333Y417768I1103J-1019D01*
G37*
G36*
G01X1244901Y398344D02*
G02X1243959Y399733I-1502J-5D01*
G03X1244508Y400105I149J371D01*
G02X1245450Y398716I1502J5D01*
G03X1244901Y398344I-149J-371D01*
G37*
G36*
G01X1106863Y335153D02*
G02X1104858Y335082I-963J-1153D01*
G03X1104837Y335677I-277J288D01*
G02X1106316Y338240I963J1153D01*
G03X1106853Y338645I138J376D01*
G02X1107815Y337413I1398J100D01*
G03X1107293Y336990I-124J-380D01*
G02X1106842Y335748I-1493J-161D01*
G03X1106863Y335153I277J-288D01*
G37*
G36*
G01X1370996Y395697D02*
G03X1370418I-289J-277D01*
G02Y397639I-1011J971D01*
G03X1370996I289J277D01*
G02Y395697I1011J-971D01*
G37*
G36*
G01X1375339Y386481D02*
G03Y385955I302J-263D01*
G02X1373075I-1132J-987D01*
G03Y386481I-302J263D01*
G02X1373105Y388489I1132J987D01*
G03X1373118Y389018I-293J272D01*
G02X1375370Y388964I1150J967D01*
G03X1375357Y388435I293J-272D01*
G02X1375339Y386481I-1150J-966D01*
G37*
G36*
G01X1343321Y360990D02*
G03X1343905Y360822I364J166D01*
G02X1343364Y358945I826J-1255D01*
G03X1342780Y359113I-364J-166D01*
G02X1343321Y360990I-826J1255D01*
G37*
G36*
G01X1347898Y322736D02*
G03X1348462Y322488I385J110D01*
G02X1347673Y320797I672J-1343D01*
G03X1347121Y321070I-389J-93D01*
G02X1347898Y322736I-571J1280D01*
G37*
G36*
G01X1339545Y320535D02*
G03X1340165Y320565I298J267D01*
G02X1340213Y318723I1210J-890D01*
G03X1339592Y318721I-310J-253D01*
G02X1339545Y320535I-1092J879D01*
G37*
G36*
G01X1350557Y316957D02*
G03X1350873Y316434I379J-128D01*
G02X1349302Y315436I-223J-1384D01*
G03X1348963Y315944I-384J111D01*
G02X1350557Y316957I171J1492D01*
G37*
G36*
G01X1361610Y315749D02*
G03X1362204Y315625I350J193D01*
G02X1361863Y313782I855J-1111D01*
G03X1361264Y313878I-341J-209D01*
G02X1361610Y315749I-970J1147D01*
G37*
G36*
G01X1306859Y308248D02*
G03X1306876Y307664I281J-284D01*
G02X1304964Y307608I-926J-1053D01*
G03X1304947Y308192I-281J284D01*
G02X1304877Y308258I926J1053D01*
G03X1304338Y308284I-284J-282D01*
G02X1304507Y310434I-958J1157D01*
G03X1305044Y310376I300J264D01*
G02X1306859Y308248I830J-1130D01*
G37*
G36*
G01X1300762Y300202D02*
G03X1300755Y299626I274J-291D01*
G02X1298673Y299653I-1055J-1069D01*
G03X1298680Y300229I-274J291D01*
G02X1300762Y300202I1055J1069D01*
G37*
G36*
G01X1359490Y372797D02*
G02X1357525Y372788I-978J-1005D01*
G03X1357508Y373372I-281J284D01*
G02X1358565Y376001I992J1128D01*
G03X1358922Y376610I17J399D01*
G02X1358699Y377466I1278J790D01*
G03X1358375Y377876I-399J17D01*
G02X1358605Y380853I280J1476D01*
G03X1358799Y381059I-6J200D01*
G02X1358798Y381098I1501J58D01*
G03X1358598Y381298I-200J0D01*
G02X1358362Y384283I2J1502D01*
G03X1358698Y384683I-64J395D01*
G02X1358702Y384810I1502J16D01*
G03X1358387Y385231I-399J30D01*
G02X1358422Y388176I313J1469D01*
G03X1358737Y388660I-74J393D01*
G02X1358698Y389002I1463J340D01*
G03X1358355Y389398I-400J0D01*
G02X1357436Y391872I213J1487D01*
G03Y392398I-302J263D01*
G02X1359700I1132J987D01*
G03Y391872I302J-263D01*
G02X1360061Y390723I-1132J-987D01*
G03X1360253Y390501I199J-22D01*
G02X1360356Y390494I-50J-1501D01*
G03X1360576Y390715I21J199D01*
G02X1360936Y391872I1492J170D01*
G03Y392398I-302J263D01*
G02X1363200I1132J987D01*
G03Y391872I302J-263D01*
G02X1362095Y389383I-1132J-987D01*
G03X1361702Y388987I7J-400D01*
G02X1360478Y387524I-1502J13D01*
G03X1360163Y387040I74J-393D01*
G02X1360198Y386590I-1463J-340D01*
G03X1360513Y386169I399J-30D01*
G02X1360438Y383217I-313J-1469D01*
G03X1360102Y382817I64J-395D01*
G01Y382802D01*
G03X1360302Y382602I200J0D01*
G02X1360350Y379599I-2J-1502D01*
G03X1360156Y379393I6J-200D01*
G02Y379286I-1501J-54D01*
G03X1360480Y378876I399J-17D01*
G02X1360135Y375899I-280J-1476D01*
G03X1359778Y375290I-17J-399D01*
G02X1359502Y373381I-1278J-790D01*
G03X1359490Y372797I267J-298D01*
G37*
G36*
G01X1381129Y371450D02*
G02X1379271I-929J-1050D01*
G03Y372050I-265J300D01*
G02X1378921Y372526I929J1050D01*
G03X1378233Y372599I-365J-164D01*
G02X1377889Y372267I-1131J828D01*
G03X1377862Y371625I224J-331D01*
G02X1375667Y370041I-883J-1089D01*
G03X1375083Y370239I-374J-142D01*
G02X1373399Y372466I-739J1192D01*
G03X1373369Y373082I-270J296D01*
G02X1375689Y374773I899J1203D01*
G03X1376297Y374575I378J129D01*
G02X1378382Y374002I806J-1147D01*
G03X1379070Y373929I365J164D01*
G02X1381129Y372050I1131J-829D01*
G03Y371450I265J-300D01*
G37*
G36*
G01X1357736Y359878D02*
G02X1357671Y361577I-1270J802D01*
G03X1358330Y361602I321J239D01*
G02X1360825Y361669I1270J-802D01*
G03X1361453Y361638I326J232D01*
G02X1361402Y359858I1057J-921D01*
G03X1360773Y359862I-316J-245D01*
G02X1358395Y359903I-1173J938D01*
G03X1357736Y359878I-321J-239D01*
G37*
G36*
G01X1338933Y351103D02*
G02X1338120Y349481I664J-1347D01*
G03X1337550Y349766I-393J-74D01*
G02X1338363Y351388I-664J1347D01*
G03X1338933Y351103I393J74D01*
G37*
G36*
G01X1331530Y347307D02*
G02X1331474Y345600I1083J-890D01*
G03X1330840Y345621I-325J-233D01*
G02X1330896Y347328I-1083J890D01*
G03X1331530Y347307I325J233D01*
G37*
G36*
G01X1322999Y321051D02*
G02X1322250Y319673I751J-1301D01*
G03X1321651Y319999I-399J-21D01*
G02X1322400Y321377I-751J1301D01*
G03X1322999Y321051I399J21D01*
G37*
G36*
G01X1359301Y319952D02*
G02X1358943Y318168I993J-1127D01*
G03X1358333Y318304I-359J-175D01*
G02X1356112Y319807I-881J1091D01*
G03X1355634Y320313I-382J118D01*
G02X1356640Y321263I-334J1362D01*
G03X1357118Y320757I382J-118D01*
G02X1358685Y320062I334J-1362D01*
G03X1359301Y319952I352J190D01*
G37*
G36*
G01X1348816Y305065D02*
G02X1347155Y304756I-626J-1255D01*
G03X1347025Y305391I-295J270D01*
G02X1347027Y308130I617J1369D01*
G03X1347134Y308791I-163J366D01*
G02X1348699Y308567I947J1034D01*
G03X1348616Y307903I176J-359D01*
G02X1348710Y305704I-974J-1143D01*
G03X1348816Y305065I284J-281D01*
G37*
G36*
G01X1354120Y304944D02*
G02X1352436Y304822I-761J-1177D01*
G03X1352377Y305468I-263J302D01*
G02X1352285Y307994I765J1293D01*
G03X1352298Y308642I-228J329D01*
G02X1353986I844J1119D01*
G03X1353999Y307994I241J-319D01*
G02X1354086Y305592I-857J-1234D01*
G03X1354120Y304944I251J-312D01*
G37*
G36*
G01X1343005Y302053D02*
G02X1341089Y302597I-1265J-810D01*
G03X1341263Y303156I-173J360D01*
G02X1341386Y304729I1217J696D01*
G03X1341214Y305353I-312J250D01*
G02X1340958Y308043I526J1407D01*
G03X1341010Y308688I-208J341D01*
G02X1341136Y310917I910J1067D01*
G03X1341264Y311438I-224J331D01*
G02X1341223Y312679I1236J662D01*
G03X1340967Y313229I-364J165D01*
G02X1342713Y313992I408J1446D01*
G03X1342943Y313430I356J-182D01*
G02X1343284Y310938I-443J-1330D01*
G03X1343156Y310417I224J-331D01*
G02X1342696Y308587I-1236J-662D01*
G03X1342670Y307940I221J-333D01*
G02X1342875Y305776I-930J-1180D01*
G03X1343022Y305145I302J-262D01*
G02X1343150Y302621I-542J-1293D01*
G03X1343005Y302053I191J-351D01*
G37*
G36*
G01X1337487Y302080D02*
G02X1335453Y302523I-1247J-837D01*
G03X1335588Y303068I-209J341D01*
G02X1335771Y304743I1205J716D01*
G03X1335639Y305384I-292J274D01*
G02X1335487Y308059I601J1376D01*
G03X1335551Y308705I-201J346D01*
G02X1337230Y308570I929J1050D01*
G03X1337191Y307923I214J-338D01*
G02X1337295Y305691I-951J-1163D01*
G03X1337403Y305047I282J-284D01*
G02X1337592Y302632I-610J-1263D01*
G03X1337487Y302080I227J-329D01*
G37*
G36*
G01X1365010Y301939D02*
G02X1363182Y302066I-996J-1124D01*
G03X1363238Y302686I-222J333D01*
G02X1363307Y304764I975J1008D01*
G03X1363258Y305410I-258J305D01*
G02X1363187Y307924I786J1280D01*
G03X1363200Y308572I-228J329D01*
G02X1364888I844J1119D01*
G03X1364901Y307924I241J-319D01*
G02X1364969Y305507I-857J-1234D01*
G03X1364993Y304859I246J-315D01*
G02X1365040Y302562I-780J-1165D01*
G03X1365010Y301939I235J-324D01*
G37*
G36*
G01X1359537Y301915D02*
G02X1357727Y302094I-1023J-1100D01*
G03X1357802Y302716I-210J341D01*
G02X1357863Y304743I998J984D01*
G03X1357796Y305388I-267J298D01*
G02X1357836Y308015I748J1302D01*
G03X1357902Y308677I-188J353D01*
G02X1359497Y308548I890J1083D01*
G03X1359455Y307884I201J-346D01*
G02X1359503Y305534I-911J-1194D01*
G03X1359546Y304887I255J-308D01*
G02X1359586Y302539I-746J-1187D01*
G03X1359537Y301915I224J-331D01*
G37*
G36*
G01X1321261Y296163D02*
G02X1320120Y294957I339J-1463D01*
G03X1319636Y295415I-394J68D01*
G02X1320777Y296621I-339J1463D01*
G03X1321261Y296163I394J-68D01*
G37*
G36*
G01X1543599Y324505D02*
G03X1543935Y324083I399J-27D01*
G02X1542210Y322790I-235J-1483D01*
G03X1541899Y323231I-397J50D01*
G02X1543599Y324505I301J1369D01*
G37*
G36*
G01X1547593Y317126D02*
G03X1547366Y317638I-374J140D01*
G02X1549220Y318524I516J1304D01*
G03X1549475Y318025I382J-120D01*
G02X1547593Y317126I-475J-1425D01*
G37*
G36*
G01X1568271Y314778D02*
G03X1568629Y314283I388J-96D01*
G02X1567163Y313224I-105J-1398D01*
G03X1566805Y313719I-388J96D01*
G02X1565900Y314144I104J1398D01*
G03X1565346Y314165I-288J-277D01*
G02X1565421Y316183I-935J1045D01*
G03X1565975Y316162I288J277D01*
G02X1568271Y314778I935J-1045D01*
G37*
G36*
G01X1690105Y175241D02*
G02X1690058Y173542I1334J-887D01*
G03X1689380Y173560I-345J-203D01*
G02X1689427Y175259I-1334J887D01*
G03X1690105Y175241I345J203D01*
G37*
G36*
G01X1678525Y171043D02*
G02X1676379Y169307I-919J-1058D01*
G03X1675679Y169308I-350J-194D01*
G02X1673512Y171029I-1224J683D01*
G03Y171620I-269J295D01*
G02X1675669Y173359I943J1038D01*
G03X1676367Y173368I346J200D01*
G02X1678524Y171646I1233J-668D01*
G03X1678525Y171043I264J-301D01*
G37*
G36*
G01X1701968Y162401D02*
G03X1702523Y162390I283J283D01*
G02X1702478Y160081I1087J-1176D01*
G03X1701923Y160092I-283J-283D01*
G02X1701968Y162401I-1087J1176D01*
G37*
G36*
G01X1700076Y154255D02*
G03X1700357Y154249I144J140D01*
G02X1700306Y151967I1098J-1166D01*
G03X1700025Y151973I-144J-140D01*
G02X1700076Y154255I-1098J1166D01*
G37*
G36*
G01X1760020Y118137D02*
G03X1759380I-320J-240D01*
G02Y120063I-1280J963D01*
G03X1760020I320J240D01*
G02Y118137I1280J-963D01*
G37*
G36*
G01X1688081Y100017D02*
G03X1688358Y99994I150J132D01*
G02X1688163Y97695I1010J-1243D01*
G03X1687886Y97718I-150J-132D01*
G02X1688081Y100017I-1010J1243D01*
G37*
G36*
G01X1659322Y99975D02*
G03X1659840Y99785I359J177D01*
G02X1659108Y97957I560J-1285D01*
G03X1658601Y98177I-369J-155D01*
G02X1659322Y99975I-447J1223D01*
G37*
G36*
G01X1695030Y133752D02*
G02X1693493Y134716I-1405J-532D01*
G03X1693831Y135256I-36J398D01*
G02X1694394Y137032I1405J532D01*
G03Y137694I-224J331D01*
G02X1696078I842J1244D01*
G03Y137032I224J-331D01*
G02X1695368Y134292I-842J-1244D01*
G03X1695030Y133752I36J-398D01*
G37*
G36*
G01X1679335Y129709D02*
G02X1678917Y128429I1067J-1057D01*
G03X1678254Y128668I-396J-59D01*
G02X1678660Y129908I-868J971D01*
G03X1679335Y129709I391J83D01*
G37*
G36*
G01X1727611Y123133D02*
G02X1727597Y124391I-1147J616D01*
G03X1728297Y124399I348J197D01*
G02X1728311Y123141I1147J-616D01*
G03X1727611Y123133I-348J-197D01*
G37*
G36*
G01X1724472Y101104D02*
G02X1724436Y102361I-1158J596D01*
G03X1725136Y102381I344J203D01*
G02X1725172Y101124I1158J-596D01*
G03X1724472Y101104I-344J-203D01*
G37*
G36*
G01X1789525Y487418D02*
X1784524D01*
G02X1783609Y490132I1J1512D01*
G03X1783623Y490756I-243J318D01*
G02X1785697Y491061I902J1074D01*
G03X1786032Y490442I335J-219D01*
G01X1788018D01*
G03X1788353Y491061I0J400D01*
G02X1790427Y490756I1172J769D01*
G03X1790441Y490132I257J-306D01*
G02X1791036Y488940I-916J-1202D01*
G01Y488845D01*
X1791027Y488761D01*
G02X1789525Y487418I-1502J169D01*
G37*
G36*
G01X1770325Y485844D02*
X1765324D01*
G02X1764409Y488557I1J1511D01*
G03X1764423Y489181I-243J318D01*
G02X1766497Y489486I902J1074D01*
G03X1766832Y488866I334J-220D01*
G01X1768818D01*
G03X1769153Y489486I1J400D01*
G02X1771227Y489181I1172J769D01*
G03X1771241Y488557I257J-306D01*
G02X1771836Y487365I-916J-1202D01*
G01Y487270D01*
X1771827Y487186D01*
G02X1770325Y485844I-1502J169D01*
G37*
G36*
G01X1672146Y482573D02*
G03Y482027I292J-273D01*
G02X1669954I-1096J-1027D01*
G03Y482573I-292J273D01*
G02X1672146I1096J1027D01*
G37*
G36*
G01X1653282Y353673D02*
G03Y353127I292J-273D01*
G02X1651090I-1096J-1027D01*
G03Y353673I-292J273D01*
G02X1653282I1096J1027D01*
G37*
G36*
G01X1643659Y343997D02*
G03X1643715Y343465I324J-235D01*
G02X1641496Y343229I-1003J-1118D01*
G03X1641440Y343761I-324J235D01*
G02X1643659Y343997I1003J1118D01*
G37*
G36*
G01X1654032Y320258D02*
G03X1654016Y319697I277J-289D01*
G02X1651966I-1025J-956D01*
G03X1651950Y320258I-293J272D01*
G02Y322424I1041J1083D01*
G03X1651966Y322985I-277J289D01*
G02X1652044Y324975I1025J956D01*
G03X1652066Y325543I-270J295D01*
G02X1652015Y327399I1025J957D01*
G03X1651978Y327950I-307J256D01*
G02Y330168I1013J1109D01*
G03X1652015Y330719I-270J295D01*
G02X1654094Y330638I1076J899D01*
G03X1654088Y330085I286J-280D01*
G02Y328033I-1097J-1026D01*
G03X1654094Y327480I292J-273D01*
G02X1654038Y325466I-1003J-980D01*
G03X1654016Y324898I270J-295D01*
G02Y322985I-1025J-956D01*
G03X1654032Y322424I293J-272D01*
G02Y320258I-1041J-1083D01*
G37*
G36*
G01X1640545Y311748D02*
G03Y311222I302J-263D01*
G02X1638281I-1132J-987D01*
G03Y311748I-302J263D01*
G02X1640545I1132J987D01*
G37*
G36*
G01X1642231Y235551D02*
G03X1642727Y235263I388J97D01*
G02X1641746Y233572I379J-1350D01*
G03X1641250Y233860I-388J-97D01*
G02X1642231Y235551I-379J1350D01*
G37*
G36*
G01X1759555Y494724D02*
G02X1757206Y494340I-1055J-924D01*
G03X1756837Y494894I-369J154D01*
G01X1753575D01*
G02X1753353Y494911I4J1512D01*
G03X1753142Y494630I-29J-198D01*
G02X1750938Y492996I-1274J-585D01*
G03X1750389Y492979I-266J-299D01*
G02X1748054Y494373I-993J990D01*
G03X1747671Y494888I-383J115D01*
G01X1743124D01*
G02X1742025Y495363I1J1512D01*
G03X1741438Y495358I-291J-274D01*
G02X1741366Y497316I-1038J942D01*
G03X1741952Y497353I276J290D01*
G02X1743125Y497912I1174J-953D01*
G01X1748125D01*
G02X1749636Y496410I-1J-1512D01*
G01Y496315D01*
X1749627Y496231D01*
G02X1749531Y495845I-1502J169D01*
G03X1749790Y495314I372J-147D01*
G02X1750326Y495018I-393J-1345D01*
G03X1750875Y495035I266J299D01*
G02X1751775Y495444I993J-990D01*
G03X1752131Y495961I-26J399D01*
G02X1753575Y497918I1445J445D01*
G01X1758575D01*
G02X1760086Y496416I-1J-1512D01*
G01Y496321D01*
X1760077Y496237D01*
G02X1759588Y495284I-1502J169D01*
G03X1759555Y494724I268J-297D01*
G37*
G36*
G01X1749794Y485734D02*
G02X1748003Y486268I-1194J-734D01*
G03X1748139Y486887I-171J362D01*
G02X1749300Y489366I1161J968D01*
G01X1754300D01*
G02X1755812Y487865I0J-1512D01*
G01Y487770D01*
X1755802Y487686D01*
G02X1755461Y486887I-1502J169D01*
G03X1755597Y486268I307J-257D01*
G02X1753806Y485734I-597J-1268D01*
G03X1753465Y486344I-341J210D01*
G01X1750135D01*
G03X1749794Y485734I0J-400D01*
G37*
G36*
G01X1743363Y486323D02*
G02X1741661Y485656I-463J-1323D01*
G03X1741308Y486244I-353J188D01*
G01X1736899D01*
G02X1735592Y486998I1J1511D01*
G03X1734969Y487087I-346J-200D01*
G02X1735180Y488858I-969J1014D01*
G03X1735806Y488798I337J216D01*
G02X1736900Y489266I1093J-1043D01*
G01X1741900D01*
G02X1743412Y487765I0J-1512D01*
G01Y487670D01*
X1743402Y487586D01*
G02X1743161Y486922I-1502J169D01*
G03X1743363Y486323I334J-221D01*
G37*
G36*
G01X1688287Y485279D02*
G02X1686668Y485250I-787J-1279D01*
G03X1686656Y485924I-222J333D01*
G02X1688430Y488335I786J1280D01*
G03X1688956I263J302D01*
G02X1690905Y488357I987J-1132D01*
G03X1691431Y488368I257J307D01*
G02X1693827Y487842I1012J-1109D01*
G03X1694520Y487764I368J156D01*
G02X1696680Y487905I1138J-819D01*
G03X1697262Y487904I291J274D01*
G02X1697209Y485901I1092J-1031D01*
G03X1696627Y485932I-306J-258D01*
G02X1694383Y486361I-969J1013D01*
G03X1693688Y486419I-364J-166D01*
G02X1691481Y486105I-1245J840D01*
G03X1690955Y486094I-257J-307D01*
G02X1688956Y486071I-1012J1109D01*
G03X1688430I-263J-302D01*
G02X1688275Y485953I-985J1133D01*
G03X1688287Y485279I222J-333D01*
G37*
G36*
G01X1642113Y359296D02*
G02X1640804Y358362I13J-1402D01*
G03X1640395Y358894I-377J133D01*
G02X1638654Y360500I-130J1606D01*
G01Y365501D01*
G02X1640396Y367106I1612J-1D01*
G03X1640803Y367646I33J399D01*
G02X1640821Y368685I1311J497D01*
G03X1640362Y369229I-369J155D01*
G02X1641443Y370091I-361J1561D01*
G03X1641872Y369523I360J-174D01*
G02X1642098Y366740I242J-1381D01*
G03X1641730Y366173I-5J-400D01*
G02X1641878Y365510I-1464J-675D01*
G01Y360415D01*
X1641868Y360330D01*
G02X1641743Y359856I-1602J169D01*
G03X1642113Y359296I367J-160D01*
G37*
G36*
G01X1651914Y358434D02*
G02X1650451Y359275I-1290J-550D01*
G03X1650756Y359857I-50J397D01*
G02X1650574Y360600I1430J744D01*
G01Y365601D01*
G02X1650714Y366255I1612J-3D01*
G03X1650378Y366817I-366J163D01*
G02X1651801Y367745I102J1398D01*
G03X1652180Y367212I377J-133D01*
G02X1653798Y365610I6J-1612D01*
G01Y360515D01*
X1653788Y360430D01*
G02X1652263Y358990I-1602J170D01*
G03X1651914Y358434I19J-399D01*
G37*
G36*
G01X1644262Y349701D02*
G02X1642472Y350032I-1112J-1009D01*
G03X1642588Y350658I-180J357D01*
G02X1644378Y350327I1112J1009D01*
G03X1644262Y349701I180J-357D01*
G37*
G36*
G01X1951554Y112456D02*
G02Y127860I0J7702D01*
G01X1958054D01*
G02Y112456I0J-7702D01*
G01X1951554D01*
G37*
G36*
G01X1935796Y241766D02*
G03Y241234I298J-266D01*
G02X1933704I-1046J-934D01*
G03Y241766I-298J266D01*
G02X1935796I1046J934D01*
G37*
G36*
G01X1927049Y232850D02*
G03X1927104Y232317I323J-236D01*
G02X1924886Y232085I-1004J-1117D01*
G03X1924831Y232618I-323J236D01*
G02X1927049Y232850I1004J1117D01*
G37*
G36*
G01X1968220Y228637D02*
G03X1967580I-320J-240D01*
G02Y230563I-1280J963D01*
G03X1968220I320J240D01*
G02Y228637I1280J-963D01*
G37*
G36*
G01X1939229Y229179D02*
G03X1939773Y229172I276J290D01*
G02X1939745Y226821I1074J-1188D01*
G03X1939201Y226828I-276J-290D01*
G02X1939229Y229179I-1074J1188D01*
G37*
G36*
G01X1944461Y222601D02*
G03X1944413Y222063I270J-295D01*
G02X1942272Y222322I-1196J-909D01*
G03X1942353Y222856I-251J311D01*
G02X1943287Y225020I1164J781D01*
G03X1943599Y225545I-66J394D01*
G02X1943753Y226770I1326J455D01*
G03X1943650Y227316I-334J220D01*
G02X1944340Y229855I813J1142D01*
G03X1944705Y230273I-34J398D01*
G02X1947162Y231265I1400J71D01*
G03X1947762Y231261I302J263D01*
G02X1953002Y229261I2238J-2000D01*
G01Y228061D01*
G02X1946998I-3002J0D01*
G01Y228611D01*
G03X1946489Y228996I-400J0D01*
G02X1946228Y228947I-388J1347D01*
G03X1945863Y228529I34J-398D01*
G02X1945635Y227689I-1400J-71D01*
G03X1945738Y227143I334J-220D01*
G02X1945155Y224618I-813J-1142D01*
G03X1944843Y224093I66J-394D01*
G02X1944461Y222601I-1326J-455D01*
G37*
G36*
G01X1944146Y216465D02*
G03X1944128Y215851I247J-315D01*
G02X1942284Y215862I-928J-1051D01*
G03X1942274Y216476I-261J303D01*
G02X1944146Y216465I943J1169D01*
G37*
G36*
G01X1945730Y150711D02*
G03X1945732Y150181I301J-264D01*
G02X1943479Y150173I-1123J-997D01*
G03X1943477Y150703I-301J264D01*
G02X1945730Y150711I1123J997D01*
G37*
G36*
G01X1965972Y148420D02*
G03X1965767Y147900I164J-365D01*
G02X1962882Y147402I-1385J-582D01*
G03X1962550Y147819I-399J23D01*
G02X1963725Y150483I250J1481D01*
G03X1964289Y150555I246J315D01*
G02X1965043Y151056I1111J-855D01*
G03X1965293Y151634I-101J387D01*
G02X1966979Y150822I1407J766D01*
G03X1966682Y150267I69J-394D01*
G02X1965972Y148420I-1282J-567D01*
G37*
G36*
G01X1963994Y142966D02*
G03X1964138Y142408I341J-210D01*
G02X1962163Y141952I-738J-1308D01*
G03X1962048Y142517I-329J227D01*
G02X1963994Y142966I752J1183D01*
G37*
G36*
G01X1952200Y142923D02*
G03X1952362Y142348I337J-215D01*
G02X1950434Y141807I-662J-1348D01*
G03X1950272Y142382I-337J215D01*
G02X1952200Y142923I662J1348D01*
G37*
G36*
G01X1928497Y122208D02*
G03X1928304Y121716I183J-356D01*
G02X1926205Y122539I-1412J-513D01*
G03X1926398Y123031I-183J356D01*
G02X1926762Y124620I1412J513D01*
G03X1926785Y125170I-278J287D01*
G02X1927868Y127657I1133J986D01*
G03X1928250Y128116I-13J400D01*
G02X1928631Y129354I1486J220D01*
G03X1928620Y129907I-294J271D01*
G02X1930875Y129891I1136J1130D01*
G03X1930856Y129338I279J-286D01*
G02X1929786Y126836I-1120J-1001D01*
G03X1929404Y126377I13J-400D01*
G02X1928966Y125080I-1486J-221D01*
G03X1928943Y124530I278J-287D01*
G02X1928497Y122208I-1133J-986D01*
G37*
G36*
G01X1907493Y116959D02*
G03X1907504Y116391I287J-279D01*
G02X1905388Y116350I-1037J-1086D01*
G03X1905377Y116918I-287J279D01*
G02X1907493Y116959I1037J1086D01*
G37*
G36*
G01X1915277Y115092D02*
G03X1915367Y114526I321J-239D01*
G02X1913343Y114258I-867J-1226D01*
G03X1913283Y114828I-307J256D01*
G02X1915277Y115092I869J1100D01*
G37*
G36*
G01X1908258Y106254D02*
G03X1908667Y105913I396J59D01*
G02X1907328Y104307I48J-1401D01*
G03X1906919Y104648I-396J-59D01*
G02X1908258Y106254I-48J1401D01*
G37*
G36*
G01X1919293Y95062D02*
G03X1919273Y94531I288J-277D01*
G02X1917030Y94617I-1160J-955D01*
G03X1917050Y95148I-288J277D01*
G02X1917117Y97133I1160J954D01*
G03X1917073Y97722I-291J274D01*
G02X1919095Y97872I929J1180D01*
G03X1919139Y97283I291J-274D01*
G02X1919293Y95062I-929J-1180D01*
G37*
G36*
G01X1908550Y92826D02*
G03X1908558Y92268I291J-275D01*
G02X1906263Y92233I-1130J-1135D01*
G03X1906255Y92791I-291J275D01*
G02X1906213Y92833I1112J1153D01*
G03X1905913Y92824I-146J-136D01*
G02X1903524Y94956I-1234J1022D01*
G03X1903537Y95497I-288J278D01*
G02X1905797Y97757I1205J1055D01*
G03X1906338Y97770I263J301D01*
G02X1908609Y95511I1110J-1155D01*
G03X1908597Y94974I290J-275D01*
G02X1908550Y92826I-1212J-1048D01*
G37*
G36*
G01X1908997Y83884D02*
G03X1909009Y83351I304J-260D01*
G02X1906918Y83302I-1024J-958D01*
G03X1906906Y83835I-304J260D01*
G02X1906885Y85729I1023J958D01*
G03X1906880Y86268I-298J267D01*
G02X1908951Y86287I1027J955D01*
G03X1908956Y85748I298J-267D01*
G02X1908997Y83884I-1027J-955D01*
G37*
G36*
G01X1903859Y80735D02*
G03X1904459Y80728I303J261D01*
G02X1904438Y78875I1042J-938D01*
G03X1903838Y78882I-303J-261D01*
G02X1903859Y80735I-1042J938D01*
G37*
G36*
G01X1895811Y72505D02*
G03X1895178Y72485I-309J-254D01*
G02X1893600Y74823I-1217J880D01*
G03X1893893Y75303I-96J388D01*
G02X1896836Y75408I1461J348D01*
G03X1897176Y74948I395J-64D01*
G02X1895811Y72505I-206J-1488D01*
G37*
G36*
G01X1967942Y73987D02*
G03X1967505Y73439I-68J-394D01*
G02X1965028Y73648I-1293J-542D01*
G03X1964910Y74197I-338J215D01*
G02X1964708Y76380I769J1172D01*
G03Y76958I-277J289D01*
G02X1964669Y78942I971J1011D01*
G03Y79496I-288J277D01*
G02Y81442I1010J973D01*
G03Y81996I-288J277D01*
G02X1966689I1010J973D01*
G03Y81442I288J-277D01*
G02X1966773Y81346I-1012J-970D01*
G03X1967085I156J125D01*
G02X1969152Y81479I1094J-877D01*
G03X1969706I277J288D01*
G02X1971689Y79496I973J-1010D01*
G03Y78942I288J-277D01*
G02X1971650Y76958I-1010J-973D01*
G03Y76380I277J-289D01*
G02X1969706Y74359I-972J-1010D01*
G03X1969152I-277J-288D01*
G02X1967942Y73987I-973J1010D01*
G37*
G36*
G01X1891096Y61818D02*
G03X1890788Y61348I84J-391D01*
G02X1889051Y62623I-1570J-318D01*
G03X1889407Y63058I-42J398D01*
G02X1891096Y61818I1396J131D01*
G37*
G36*
G01X1890330Y52676D02*
G03X1890361Y52152I317J-244D01*
G02X1888075I-1143J-1122D01*
G03X1888106Y52676I-286J280D01*
G02Y54384I1112J854D01*
G03X1888075Y54908I-317J244D01*
G02X1890361I1143J1122D01*
G03X1890330Y54384I286J-280D01*
G02Y52676I-1112J-854D01*
G37*
G36*
G01X1890361Y44908D02*
G03X1890330Y44384I286J-280D01*
G02X1888106I-1112J-854D01*
G03X1888075Y44908I-317J244D01*
G02X1890361I1143J1122D01*
G37*
G36*
G01X1857264Y39931D02*
G03X1856693Y39854I-248J-313D01*
G02X1856456Y42004I-1293J946D01*
G03X1857031Y42053I264J301D01*
G02X1859181Y42244I1167J-945D01*
G03X1859725Y42263I262J302D01*
G02X1859803Y40064I1061J-1063D01*
G03X1859259Y40045I-262J-302D01*
G02X1857264Y39931I-1061J1063D01*
G37*
G36*
G01X1854840Y35826D02*
G03X1855424Y35714I342J206D01*
G02X1855083Y33685I909J-1196D01*
G03X1854494Y33770I-333J-222D01*
G02X1854840Y35826I-1027J1230D01*
G37*
G36*
G01X1847518Y35563D02*
G03X1848044Y35562I264J301D01*
G02X1848036Y33298I983J-1135D01*
G03X1847510Y33299I-264J-301D01*
G02X1847518Y35563I-983J1135D01*
G37*
G36*
G01X1872358Y26122D02*
G03X1871990Y25570I2J-400D01*
G02X1869887Y26322I-1390J-570D01*
G03X1869952Y26982I-190J352D01*
G02X1872358Y26122I2390J2892D01*
G37*
G36*
G01X1898528Y235808D02*
G02X1898508Y234297I1288J-773D01*
G03X1897817Y234307I-348J-196D01*
G02X1897837Y235818I-1288J773D01*
G03X1898528Y235808I348J196D01*
G37*
G36*
G01X1954500Y204492D02*
X1950000D01*
G02X1946598Y207893I-1J3401D01*
G01Y210293D01*
G02X1953251Y211294I3402J0D01*
G01X1953988D01*
Y211497D01*
G02X1955411Y214032I2902J38D01*
G03X1955563Y214558I-204J344D01*
G02X1956059Y216485I1338J683D01*
G03Y217147I-224J331D01*
G02X1957743I842J1244D01*
G03Y216485I224J-331D01*
G02X1958235Y214550I-842J-1244D01*
G03X1958384Y214023I355J-184D01*
G02X1959541Y212715I-1494J-2488D01*
G03X1960200Y212606I365J163D01*
G02X1959928Y209839I1690J-1563D01*
G03X1959260Y209861I-341J-209D01*
G02X1957785Y208775I-2370J1674D01*
G02X1954500Y204492I-3285J-882D01*
G37*
G36*
G01X1953785Y196804D02*
G02X1952253Y196564I-585J-1274D01*
G03X1952138Y197228I-270J295D01*
G02X1953692Y197472I579J1386D01*
G03X1953785Y196804I260J-304D01*
G37*
G36*
G01X1945311Y191443D02*
G02X1943548Y191614I-1010J-1243D01*
G03X1943623Y192269I-188J353D01*
G02X1945363Y192100I988J1131D01*
G03X1945311Y191443I200J-346D01*
G37*
G36*
G01X1962867Y165901D02*
G02X1961207Y167137I-1395J-141D01*
G03X1961523Y167611I-75J393D01*
G02X1964688Y167794I1569J324D01*
G03X1965283Y167410I398J-36D01*
G02X1964572Y166237I690J-1220D01*
G03X1963956Y166587I-400J13D01*
G02X1963230Y166340I-864J1349D01*
G03X1962867Y165901I35J-398D01*
G37*
G36*
G01X1937459Y144811D02*
G02X1935605Y145398I-1273J-798D01*
G03X1935780Y145993I-155J369D01*
G02X1935670Y146178I1319J909D01*
G03X1935326Y146201I-179J-90D01*
G02X1935305Y148029I-1326J899D01*
G03X1935925Y147989I326J231D01*
G02X1936178Y148210I1175J-1089D01*
G03X1936181Y148862I-230J327D01*
G02X1937890Y148917I819J1138D01*
G03X1937936Y148267I254J-309D01*
G02X1937659Y145399I-836J-1367D01*
G03X1937459Y144811I139J-375D01*
G37*
G36*
G01X1947793Y140621D02*
G02X1946301Y140585I-715J-1321D01*
G03X1946285Y141279I-207J342D01*
G02X1947777Y141315I715J1321D01*
G03X1947793Y140621I207J-342D01*
G37*
G36*
G01X1942189Y136100D02*
G02X1941622Y137486I-1489J200D01*
G03X1942263Y137748I245J316D01*
G02X1942830Y136362I1489J-200D01*
G03X1942189Y136100I-245J-316D01*
G37*
G36*
G01X1945567Y98870D02*
G02X1945553Y97453I1203J-720D01*
G03X1944863Y97460I-347J-199D01*
G02X1942476Y98931I-1202J721D01*
G03X1942249Y99530I-338J215D01*
G02X1943821Y100126I388J1347D01*
G03X1944048Y99527I338J-215D01*
G02X1944877Y98877I-387J-1348D01*
G03X1945567Y98870I347J199D01*
G37*
G36*
G01X1953710Y85541D02*
G02X1952733Y83670I459J-1430D01*
G03X1952229Y83933I-382J-118D01*
G02X1950783Y84231I-459J1430D01*
G03X1950257I-263J-302D01*
G02X1948243Y84267I-987J1132D01*
G03X1947697I-273J-292D01*
G02X1945538Y86350I-1027J1096D01*
G03Y86876I-302J263D01*
G02X1945500Y88805I1132J987D01*
G03X1945479Y89331I-311J251D01*
G02X1945438Y91350I1091J1032D01*
G03Y91876I-302J263D01*
G02X1947597Y93959I1132J987D01*
G03X1948143I273J292D01*
G02X1948295Y94084I1028J-1095D01*
G03X1948387Y94641I-233J325D01*
G02X1950597Y96645I1223J872D01*
G03X1951123I263J302D01*
G02X1951407Y96840I986J-1132D01*
G03X1951491Y97488I-187J354D01*
G02X1953143Y97307I949J1032D01*
G03X1953084Y96656I200J-346D01*
G02X1953326Y96395I-973J-1145D01*
G03X1953905Y96321I324J234D01*
G02X1955848Y96295I956J-1158D01*
G03X1956374I263J302D01*
G02X1958221Y93931I986J-1133D01*
G03X1958122Y93374I229J-328D01*
G02X1955904Y91381I-1231J-861D01*
G03X1955378I-263J-302D01*
G02X1953077Y91786I-987J1132D01*
G03X1952757Y91827I-175J-97D01*
G02X1952689Y91760I-1087J1036D01*
G03Y91466I136J-147D01*
G02X1952840Y89421I-1019J-1103D01*
G03X1952861Y88895I311J-251D01*
G02X1952902Y86876I-1091J-1032D01*
G03Y86350I302J-263D01*
G02X1953206Y85804I-1132J-988D01*
G03X1953710Y85541I382J118D01*
G37*
G36*
G01X1884509Y77337D02*
G02X1881914Y75824I-1309J-737D01*
G03X1881274Y75884I-342J-207D01*
G02X1879009Y77509I-1044J936D01*
G03X1878847Y78059I-348J196D01*
G02X1880473Y80310I654J1241D01*
G03X1881027I277J288D01*
G02X1882973I973J-1010D01*
G03X1883527I277J288D01*
G02X1884778Y77926I973J-1010D01*
G03X1884509Y77337I79J-392D01*
G37*
G36*
G01X1875325Y59682D02*
G02X1875072Y61305I-1369J618D01*
G03X1875734Y61408I297J267D01*
G02X1876168Y61967I1370J-616D01*
G03X1876219Y62545I-249J313D01*
G02X1878197Y62422I1051J928D01*
G03X1878176Y61842I265J-300D01*
G02X1875987Y59785I-1073J-1051D01*
G03X1875325Y59682I-297J-267D01*
G37*
G36*
G01X1868718Y40649D02*
G02X1867307Y41146I-1099J-870D01*
G03X1867524Y41794I-89J390D01*
G02X1868956Y41290I1146J971D01*
G03X1868718Y40649I76J-393D01*
G37*
G36*
G01X1879989Y38673D02*
G02X1877849Y38514I-992J-1127D01*
G03X1877808Y39073I-306J259D01*
G02X1877880Y41387I992J1127D01*
G03Y42020I-245J317D01*
G02X1879720I920J1187D01*
G03Y41387I245J-316D01*
G02X1879948Y39232I-920J-1187D01*
G03X1879989Y38673I306J-259D01*
G37*
G36*
G01X1878297Y23808D02*
G02X1879020Y21901I3298J160D01*
G03X1878324Y21763I-312J-250D01*
G02X1877684Y23451I-1443J418D01*
G03X1878297Y23808I214J338D01*
G37*
G54D56*
X388187Y88678D03*
Y50878D03*
Y69778D03*
Y13078D03*
Y31978D03*
Y-5822D03*
Y608555D03*
Y551879D03*
Y589679D03*
Y570755D03*
Y514079D03*
Y532955D03*
X1037797Y608555D03*
Y551879D03*
Y589679D03*
Y570755D03*
Y532955D03*
Y50878D03*
Y69778D03*
Y13078D03*
Y31978D03*
Y-5822D03*
G54D24*
X1719000Y190500D03*
X1660440Y200789D03*
X1664390Y201163D03*
X1669849Y193067D03*
X1610290Y265352D03*
X1627043Y256900D03*
X1597201Y238188D03*
X1635621Y208259D03*
X1644290Y196383D03*
X1598006Y192421D03*
X1620900Y81300D03*
X1627489Y74960D03*
X1635337Y73500D03*
X1643500Y80400D03*
X1599500Y75000D03*
X1625075Y80182D03*
X1614997Y84403D03*
X1630826Y88087D03*
X1601650Y24160D03*
X1554775Y295328D03*
X1565000Y290500D03*
X1581940Y295820D03*
X1559500Y290300D03*
X1559800Y285300D03*
X1534400Y296029D03*
X1550619Y303087D03*
X1584568Y281339D03*
X1587549Y192000D03*
X1561538Y174649D03*
X1557787Y192236D03*
X1593218Y191776D03*
X1558042Y172448D03*
X1552063Y202031D03*
X1558000Y205100D03*
X1570294Y167384D03*
X1572817Y169910D03*
X1568488Y164058D03*
X1566486Y181270D03*
X1591800Y164900D03*
X1542000Y126246D03*
X1558100Y128926D03*
X1572395Y110754D03*
X1531726Y123800D03*
X1574197Y127915D03*
X1542685Y133321D03*
X1588500Y106788D03*
X1576606Y104392D03*
X1573153Y103721D03*
X1557981Y141470D03*
X1563108Y126423D03*
X1580275Y101041D03*
X1575018Y71213D03*
X1574780Y90992D03*
X1583374Y81319D03*
X1577269Y95344D03*
X1579100Y69000D03*
X1530500Y287700D03*
X1518006Y286706D03*
X1527657Y278700D03*
X1521962Y278650D03*
X1524744Y133656D03*
X1490674Y98787D03*
X1482455Y124222D03*
X1518514Y130991D03*
X1500806Y133339D03*
X1496726Y120588D03*
X1500643Y154819D03*
X1475200Y142600D03*
X1520150Y127600D03*
X1503466Y142486D03*
X1510184Y142614D03*
X1518438Y100926D03*
X1518376Y111499D03*
X1505673Y146346D03*
X1519599Y86117D03*
X1452232Y109500D03*
X1416837Y45477D03*
X1420337D03*
X1457000Y82000D03*
X1453700Y83750D03*
X1425081Y48412D03*
X1357000Y86640D03*
X1353500Y96959D03*
X1370849Y59349D03*
X1370975Y67225D03*
X1359500Y83000D03*
X1355500D03*
X1377009Y39753D03*
X1380950Y30232D03*
X1304200Y462030D03*
X1340100Y432500D03*
X1318054Y460507D03*
X1300438Y433001D03*
X1335100Y432500D03*
Y427500D03*
X1300315Y427902D03*
X1330100Y452500D03*
Y457500D03*
X1310100D03*
X1305100Y452500D03*
Y457500D03*
X1315100D03*
X1310100Y452500D03*
X1315100D03*
X1320100D03*
Y457500D03*
X1325100Y452500D03*
Y457500D03*
X1296468Y437500D03*
X1262900Y466504D03*
X1252437Y140192D03*
X1220580Y179810D03*
X1209033Y183907D03*
X739933Y447401D03*
X680200Y432100D03*
X676900Y381800D03*
X687427Y384926D03*
X683100Y392200D03*
X670600Y144900D03*
X709560Y84648D03*
X670795Y89189D03*
X697200Y79500D03*
X715130Y79574D03*
X639120Y475620D03*
X618800Y474500D03*
X611250Y476750D03*
X627000Y478300D03*
X609284Y480055D03*
X648500Y477400D03*
X623400Y476300D03*
X615300Y457900D03*
X609191Y451454D03*
X618800Y100100D03*
X609482Y124568D03*
X628673Y142718D03*
X632173Y142018D03*
X639173Y140618D03*
X635673Y141318D03*
X644055Y144493D03*
X642673Y139811D03*
X654555Y142193D03*
X651055Y142893D03*
X647555Y143643D03*
X658055Y141493D03*
X633800Y119000D03*
X608600Y103000D03*
X626040Y98281D03*
X662352Y89566D03*
X664471Y86061D03*
X595070Y447970D03*
X592216Y445152D03*
X555750Y399770D03*
X605028Y119000D03*
X548620Y112357D03*
X555313D03*
X603163Y103971D03*
X525134Y112357D03*
X531888D03*
X512024D03*
X488634D03*
X518317D03*
X494927D03*
X313637Y105725D03*
X294889Y110927D03*
X270864Y112327D03*
X277557D03*
X257478D03*
X264171D03*
X240746D03*
X234053D03*
X71050Y478670D03*
X59731Y480066D03*
X74800Y383114D03*
X61041Y351737D03*
X79100Y347000D03*
X80200Y379700D03*
X74800D03*
X65000Y383000D03*
X84300Y299000D03*
X79400Y325400D03*
X84866Y294213D03*
X77103Y283900D03*
X82050Y283951D03*
X84300Y289000D03*
X72904Y284898D03*
X84300Y310700D03*
Y305700D03*
X69125Y310625D03*
X84000Y324542D03*
X79410Y331636D03*
X91600Y278700D03*
X97200Y265000D03*
X86731Y189148D03*
X90831Y184982D03*
X104424Y110833D03*
X98420Y112198D03*
X22491Y500618D03*
X27280Y510420D03*
X14700Y517000D03*
X44050Y504383D03*
X40132Y499800D03*
X24400Y519500D03*
X25827Y-16958D03*
X602Y30502D03*
X16550Y18300D03*
X19964Y18793D03*
X43960Y20572D03*
X1681352Y196092D03*
X1676924Y196731D03*
X1550417Y362607D03*
X1552500Y358500D03*
X-19210Y162529D03*
X-17014Y455604D03*
X-13500Y486400D03*
X-14800Y526100D03*
X-18160Y522609D03*
X-19802Y476738D03*
X-19783Y481286D03*
X-16186Y519304D03*
X-12600Y578900D03*
X-14971Y540000D03*
X-17500Y574000D03*
X11925Y74867D03*
X11864Y71294D03*
X1500Y295000D03*
X2485Y498185D03*
X38389Y523748D03*
X-6650Y487800D03*
X-6200Y505400D03*
X-6676Y501800D03*
X-9900Y486400D03*
X-7360Y512000D03*
X-2083Y513704D03*
X-4350Y482100D03*
X-2500Y569500D03*
X1439Y546583D03*
X1539Y550183D03*
Y586183D03*
X1439Y582583D03*
X3600Y567300D03*
X-6566Y568363D03*
X-9283Y571324D03*
X51607Y511747D03*
X86100Y505200D03*
X124340Y197750D03*
X294899Y197409D03*
X311701Y499136D03*
X392898Y195041D03*
X396296Y197359D03*
X618430Y491550D03*
X629300Y490000D03*
X662640Y528330D03*
X612515Y498752D03*
X636500Y493924D03*
X658900Y509300D03*
X639197Y490367D03*
X670600Y150000D03*
X718546Y500283D03*
X669300Y504000D03*
X708500Y512500D03*
X690500Y523300D03*
X675500Y521900D03*
X691900Y531350D03*
Y534850D03*
X697500Y534750D03*
Y531250D03*
X743483Y492937D03*
X799300Y195600D03*
X927607Y199360D03*
X944507Y197409D03*
X961309Y499136D03*
X1027875Y193507D03*
X1007595D03*
X1042506Y195041D03*
X1045904Y197359D03*
X1054000Y199100D03*
X1269810Y154398D03*
X1259200Y168350D03*
X1310098Y150040D03*
X1287790Y156575D03*
X1310175Y154696D03*
X1287770Y501897D03*
X1299450Y484950D03*
X1401300Y149600D03*
X1388450Y331250D03*
X1381431Y284259D03*
X1394260Y351170D03*
X1389500Y360500D03*
X1390100Y457500D03*
X1370100Y452500D03*
X1375100D03*
X1352490Y515470D03*
X1346870Y515450D03*
X1352590Y519170D03*
X1346970Y519150D03*
X1347546Y476897D03*
X1347196Y472941D03*
X1354462Y474141D03*
X1350500Y475100D03*
X1399721Y537509D03*
X1390595Y549328D03*
X1375961Y569473D03*
X1376000Y565700D03*
X1382500Y575400D03*
X1396158Y537595D03*
X1380890Y615820D03*
X1385000Y602700D03*
X1386921Y620689D03*
X1390851D03*
X1375961Y600673D03*
X1375861Y597073D03*
X1375961Y593473D03*
X1468700Y163100D03*
X1458569Y192143D03*
X1446331Y197285D03*
X1422281Y221479D03*
X1408247Y206270D03*
X1422196Y218052D03*
X1452728Y243306D03*
X1452200Y254500D03*
X1464150Y235550D03*
X1447154Y251710D03*
X1444311Y324366D03*
X1452699Y404060D03*
X1457300Y373600D03*
X1464400Y390800D03*
X1450400Y354300D03*
X1409500Y538000D03*
X1420500Y549800D03*
X1420400Y538000D03*
X1429026Y541026D03*
X1428281Y546119D03*
X1432560Y561160D03*
X1436160Y561200D03*
X1428791Y535512D03*
X1423800Y534800D03*
X1425243Y562260D03*
X1469200Y610739D03*
X1496713Y174853D03*
X1470382Y188372D03*
X1472758Y216495D03*
X1513900Y218000D03*
X1519243Y191627D03*
X1487716Y218650D03*
X1497493Y162078D03*
X1493200Y162700D03*
X1510800Y193330D03*
X1512790Y240099D03*
X1484000Y257500D03*
X1470556Y256900D03*
X1484700Y251800D03*
X1503842Y245678D03*
X1504772Y259229D03*
X1496812Y273718D03*
X1491265Y226492D03*
X1483457Y244568D03*
X1501550Y293750D03*
X1520766Y341000D03*
X1505000Y340990D03*
X1510851Y340113D03*
X1504370Y330970D03*
X1470276Y330774D03*
X1496900Y293900D03*
X1470257Y321929D03*
X1483506Y326061D03*
X1514265Y355542D03*
X1517367Y349964D03*
X1511000Y350627D03*
X1502970Y350610D03*
X1478163Y354940D03*
X1523450Y612900D03*
X1519850Y613000D03*
X1487912Y611632D03*
X1484312Y611732D03*
X1504700Y611100D03*
X1483279Y619100D03*
X1543100Y184128D03*
X1563157Y258164D03*
X1542751Y240477D03*
X1542690Y236050D03*
X1541325Y245090D03*
X1545802Y233529D03*
X1558700Y252000D03*
X1568365Y247761D03*
X1570574Y341776D03*
X1554932Y332171D03*
X1573950Y338050D03*
X1588551Y341410D03*
X1548100Y342200D03*
X1560500Y350000D03*
X1557534Y353400D03*
X1532367Y356530D03*
X1550639Y350200D03*
X1587684Y362653D03*
X1590154Y354762D03*
X1586500Y354900D03*
X1566922Y359681D03*
X1589604Y585896D03*
X1581704D03*
Y590196D03*
X1589604D03*
X1550990Y586588D03*
X1554358Y587258D03*
X1587610Y579550D03*
X1558800Y599300D03*
X1560400Y611600D03*
X1564300Y599400D03*
X1564400Y605500D03*
X1561700Y602200D03*
X1556200Y602400D03*
X1554400Y599300D03*
X1564300Y611500D03*
X1579900Y606050D03*
X1586700Y620100D03*
X1540477Y620308D03*
X1545407Y598393D03*
X1579680Y610279D03*
X1534968Y597268D03*
X1573500Y619500D03*
X1577000D03*
X1625400Y327667D03*
X1602776Y331304D03*
X1620159Y332004D03*
X1609172Y339630D03*
X1602215Y363981D03*
X1621727Y395374D03*
X1612825Y405438D03*
X1622100Y400600D03*
X1629300Y385400D03*
X1621800Y381500D03*
Y386300D03*
X1595800Y405900D03*
X1630219Y446000D03*
X1621000Y440500D03*
X1621182Y427091D03*
X1603719Y412000D03*
X1639822Y453140D03*
X1617900Y409900D03*
X1639271Y491135D03*
X1639391Y513065D03*
X1649336Y511502D03*
X1649545Y515215D03*
X1622330Y592325D03*
X1713600Y513000D03*
X1709400D03*
X1681650Y510673D03*
X1687606Y500938D03*
X1681115Y525218D03*
X1716490Y506970D03*
X1655790Y476593D03*
X1680133Y535489D03*
X1710389Y577787D03*
X1699600Y578100D03*
X1710000Y604500D03*
Y600000D03*
X1701291Y602268D03*
X1727743Y592342D03*
X1732443D03*
X1742200Y552863D03*
X1724899Y584748D03*
X1767141Y555500D03*
X1756578Y586743D03*
X1724250Y588250D03*
X1730759Y548162D03*
X1722500Y562000D03*
X1754897Y578750D03*
X1767500Y559800D03*
X1727843Y597142D03*
X1732443D03*
X1735000Y621002D03*
X1764823Y613600D03*
X1770600Y600800D03*
X1764912Y618718D03*
X1814852Y519901D03*
X1837300Y472276D03*
X1815200Y501500D03*
X1794100Y521900D03*
X1831600Y529000D03*
X1833700Y497300D03*
X1812452Y538501D03*
Y533601D03*
X1807852D03*
X1807752Y538501D03*
X1808152Y591601D03*
X1812852D03*
X1781300Y537800D03*
X1837475Y573835D03*
X1816020Y571448D03*
X1812802Y578693D03*
X1810863Y560637D03*
X1816175Y567669D03*
X1816330Y545260D03*
X1816100Y576200D03*
X1829176Y584287D03*
X1831500Y544500D03*
X1782300Y555900D03*
X1778675Y592224D03*
X1812852Y596401D03*
X1808252D03*
X1794500Y612500D03*
X1791500Y606500D03*
X1805000D03*
X1788290Y612006D03*
X1784200Y593924D03*
X1859530Y516430D03*
X1842400Y516800D03*
X1841900Y498800D03*
X1900890Y477200D03*
X1864339Y509560D03*
X1863000Y480000D03*
X1859600Y476200D03*
X1876945Y471316D03*
X1847000Y487500D03*
X1860000Y495500D03*
X1842764Y528136D03*
X1870100Y561150D03*
X1844018Y586482D03*
X1840690Y557190D03*
X1878500Y553500D03*
X1858500Y540000D03*
X1858681Y568087D03*
X1900729Y569557D03*
X1864580Y537060D03*
X1878736Y533040D03*
X1868110Y536000D03*
X1900250Y533700D03*
X1895523Y586365D03*
X1869800Y557100D03*
X1878875Y565475D03*
X1847070Y537610D03*
X1882300Y565550D03*
X1848900Y590750D03*
X1845000Y590800D03*
X1875600Y588500D03*
X1840700Y563800D03*
X1854530Y533132D03*
X1896358Y595255D03*
X1957250Y512050D03*
X1937300Y508900D03*
X1956606Y526671D03*
X1956300Y515900D03*
X1959300Y518000D03*
X1908300Y514500D03*
X1942328Y508712D03*
X1963000Y573000D03*
X1951900Y534900D03*
X1963097Y551000D03*
X1934200Y573700D03*
X1935400Y583000D03*
X1945900Y549900D03*
X1923500Y579500D03*
X1948100Y538700D03*
X1923400Y583000D03*
X1926600Y559500D03*
X1923600Y565100D03*
X1923000Y568700D03*
X1958940Y538890D03*
X1961715Y555639D03*
X1961771Y591744D03*
X1962950Y566600D03*
X1962500Y578500D03*
X1958500Y535000D03*
X1907500Y545600D03*
X1907200Y551600D03*
X1932390Y590100D03*
X1923504Y592500D03*
X1911750Y592800D03*
X1914700Y594600D03*
X1963300Y612800D03*
X1938130Y601480D03*
X1967200Y521600D03*
X1964270Y511410D03*
X1968375Y509375D03*
X1964890Y534940D03*
X1965400Y619500D03*
X1460400Y353000D03*
X1459111Y356353D03*
X1463870Y367869D03*
X1611418Y422971D03*
X1603000D03*
X1621347Y415297D03*
X1630120Y418887D03*
X1630386Y413942D03*
X41000Y265350D03*
X44310Y268160D03*
X37000Y265350D03*
X33490Y267900D03*
X41000Y274647D03*
X37000Y275000D03*
X47100Y327000D03*
X87200Y152374D03*
X79670Y132300D03*
X91306Y157194D03*
X99250Y160370D03*
X61800Y191600D03*
X53400Y298100D03*
X53100Y327000D03*
Y315000D03*
X104500Y-1850D03*
X132959Y33700D03*
X163391D03*
X160431Y27899D03*
X130313D03*
X157084Y34100D03*
X153738Y27899D03*
X126580Y33700D03*
X123620Y27899D03*
X150391Y34100D03*
X147045Y27899D03*
X169770Y33700D03*
X167124Y27899D03*
X132959Y-4100D03*
X130313Y17157D03*
X163391Y-4100D03*
X160431Y17157D03*
Y-9901D03*
X130313D03*
X157084Y-3700D03*
X153738Y17157D03*
Y-9901D03*
X126580Y-4100D03*
X123620Y17157D03*
Y-9901D03*
X147045Y17157D03*
X150391Y-3700D03*
X147045Y-9901D03*
X169770Y-4100D03*
X167124Y17157D03*
Y-9901D03*
X116070Y35780D03*
X114050Y21320D03*
X116692Y-1800D03*
X116300Y-9460D03*
X132959Y71500D03*
X130313Y92757D03*
X163391Y71500D03*
X160431Y92757D03*
Y65699D03*
X130313D03*
X157084Y71900D03*
X153738Y92757D03*
Y65699D03*
X126580Y71500D03*
X123620Y92757D03*
Y65699D03*
X150391Y71900D03*
X147045Y92757D03*
Y65699D03*
X169770Y71500D03*
X167124Y92757D03*
Y65699D03*
X130313Y54957D03*
X160431D03*
X153738D03*
X123620D03*
X147045D03*
X167124D03*
X113100Y57770D03*
X193895Y34100D03*
X190549Y27899D03*
X187202Y34100D03*
X183856Y27899D03*
X206581Y33700D03*
X203935Y27899D03*
X230706Y34100D03*
X227360Y27899D03*
X200202Y33700D03*
X197242Y27899D03*
X224013Y34100D03*
X220667Y27899D03*
X234053D03*
X193895Y-3700D03*
X190549Y17157D03*
Y-9901D03*
X187202Y-3700D03*
X183856Y17157D03*
Y-9901D03*
X206581Y-4100D03*
X203935Y17157D03*
Y-9901D03*
X230706Y-3700D03*
X227360Y17157D03*
Y-9901D03*
X200202Y-4100D03*
X197242Y17157D03*
Y-9901D03*
X224013Y-3700D03*
X220667Y17157D03*
Y-9901D03*
X234053Y17157D03*
Y-9901D03*
X193895Y71900D03*
X190549Y92757D03*
Y65699D03*
X187202Y71900D03*
X183856Y92757D03*
Y65699D03*
X206581Y71500D03*
X203935Y92757D03*
Y65699D03*
X230706Y71900D03*
X227360Y92757D03*
Y65699D03*
X200202Y71500D03*
X197242Y92757D03*
Y65699D03*
X224013Y71900D03*
X220667Y92761D03*
Y65699D03*
X234053Y92757D03*
Y65699D03*
X190549Y54957D03*
X183856D03*
X203935D03*
X227360D03*
X197242D03*
X220667D03*
X234053D03*
X243392Y33700D03*
X240746Y27899D03*
X267517Y34100D03*
X264171Y27899D03*
X237013Y33700D03*
X260824Y34100D03*
X257478Y27899D03*
X280203Y33700D03*
X277557Y27899D03*
X273824Y33700D03*
X270864Y27899D03*
X294289D03*
X243392Y-4100D03*
X240746Y17157D03*
Y-9901D03*
X267517Y-3700D03*
X264171Y17157D03*
Y-9901D03*
X237013Y-4100D03*
X260824Y-3700D03*
X257478Y17157D03*
Y-9901D03*
X280203Y-4100D03*
X277557Y17157D03*
Y-9901D03*
X270864Y17157D03*
X273824Y-4100D03*
X270864Y-9901D03*
X294289Y17157D03*
Y-9901D03*
X243392Y71500D03*
X240746Y92757D03*
Y65699D03*
X267517Y71900D03*
X264171Y92757D03*
Y65699D03*
X237013Y71500D03*
X260824Y71900D03*
X257478Y92757D03*
Y65699D03*
X280203Y71500D03*
X277557Y92757D03*
Y65699D03*
X270864Y92757D03*
X273824Y71500D03*
X270864Y65699D03*
X294289Y92757D03*
Y65699D03*
X240746Y54957D03*
X264171D03*
X257478D03*
X277557D03*
X270864D03*
X273910Y49914D03*
X294289Y54957D03*
X304328Y34100D03*
X300982Y27899D03*
X297635Y34100D03*
X321061Y-7108D03*
X327754Y-1743D03*
X324407Y-9901D03*
Y-4536D03*
X314368Y-7108D03*
X311021Y-4536D03*
X304328Y-3700D03*
X300982Y17157D03*
Y-9901D03*
X297635Y-3700D03*
X334447Y-1743D03*
X331100Y-9786D03*
X354526Y-7108D03*
X354525Y-1742D03*
X351179Y-9901D03*
X347833Y-1743D03*
X344486Y-4536D03*
Y-9786D03*
X337793Y-4536D03*
X341140Y-7108D03*
X334447D03*
X317714Y-4536D03*
X321061Y92757D03*
X327754Y87392D03*
X324407Y89964D03*
Y84599D03*
X314368Y92657D03*
X311021Y84714D03*
X304328Y71900D03*
X300982Y92757D03*
Y65699D03*
X297635Y71900D03*
X334447Y87392D03*
X331100Y89964D03*
X354415Y92757D03*
Y87392D03*
X351179Y89964D03*
X347833Y87392D03*
X344486Y84714D03*
Y89964D03*
X337793Y84599D03*
X341140Y92757D03*
X334447D03*
X300982Y54957D03*
X317714Y84714D03*
X398029Y28007D03*
X408069D03*
X404722Y-9901D03*
X401375Y-1743D03*
X414761Y-7108D03*
X398029Y-9901D03*
X404722Y-4536D03*
X414761Y-1743D03*
X408068Y-7108D03*
X394682Y11792D03*
X394683Y-2200D03*
X376700Y-1300D03*
X371258Y-1858D03*
Y-9800D03*
X411415Y-4536D03*
X394682Y17157D03*
X404722Y89964D03*
X401375Y87392D03*
X414761Y92757D03*
X398029Y65807D03*
Y89964D03*
X404722Y84599D03*
X414761Y87392D03*
X408069Y65807D03*
X408068Y92757D03*
X394682Y87392D03*
Y49592D03*
X380600Y37400D03*
X384992Y81600D03*
X411415Y84714D03*
X394682Y68492D03*
X431494Y28007D03*
X460912Y33700D03*
X458266Y27899D03*
X481691D03*
X454533Y33700D03*
X451573Y27899D03*
X478344Y34100D03*
X474998Y27899D03*
X424801Y28007D03*
X438187Y-4536D03*
X431494Y-9901D03*
X444880Y-9786D03*
Y-4536D03*
X460912Y-4100D03*
X458266Y17157D03*
Y-9901D03*
X481691Y17157D03*
Y-9901D03*
X454533Y-4100D03*
X451573Y-9901D03*
X478344Y-3700D03*
X474998Y17157D03*
Y-9901D03*
X428147Y-1743D03*
X421454Y-7108D03*
X434840Y-1743D03*
X424801Y-9786D03*
X438187D03*
Y84714D03*
X431494Y65807D03*
Y89964D03*
X444880D03*
Y84714D03*
X460912Y71500D03*
X458266Y92757D03*
Y65699D03*
X481691Y92757D03*
Y65699D03*
X454533Y71500D03*
X451573Y92757D03*
Y65699D03*
X478344Y71900D03*
X474998Y92757D03*
Y65699D03*
X428147Y87392D03*
X421454Y92757D03*
X434840Y87392D03*
X424801Y65807D03*
Y89964D03*
X438187D03*
X458266Y54957D03*
X481691D03*
X474998D03*
X485037Y34100D03*
X497723Y33700D03*
X495077Y27899D03*
X521848Y34100D03*
X518502Y27899D03*
X491344Y33700D03*
X488384Y27899D03*
X515155Y34100D03*
X511809Y27899D03*
X534534Y33700D03*
X531888Y27899D03*
X528155Y33700D03*
X525195Y27899D03*
X485037Y-3700D03*
X497723Y-4100D03*
X495077Y17157D03*
Y-9901D03*
X521848Y-3700D03*
X518502Y17157D03*
Y-9901D03*
X491344Y-4100D03*
X488384Y17157D03*
Y-9901D03*
X511809Y17157D03*
X515155Y-3700D03*
X511809Y-9901D03*
X534534Y-4100D03*
X531888Y17157D03*
Y-9901D03*
X528155Y-4100D03*
X525195Y17157D03*
Y-9901D03*
X485037Y71900D03*
X497723Y71500D03*
X495077Y92757D03*
Y65699D03*
X521848Y71900D03*
X518502Y92757D03*
Y65699D03*
X491344Y71500D03*
X488384Y92757D03*
Y65699D03*
X511809Y92757D03*
X515155Y71900D03*
X511809Y65699D03*
X534534Y71500D03*
X531888Y92757D03*
Y65699D03*
X528155Y71500D03*
X525195Y92757D03*
Y65699D03*
X495077Y54957D03*
X518502D03*
X488384D03*
X491430Y49914D03*
X511809Y54957D03*
X531888D03*
X525195D03*
X528241Y49914D03*
X558659Y34100D03*
X555313Y27899D03*
X551966Y34100D03*
X548620Y27899D03*
X571345Y33700D03*
X568699Y27899D03*
X595470Y34100D03*
X592124Y27899D03*
X564966Y33700D03*
X562006Y27899D03*
X588777Y34100D03*
X585431Y27899D03*
X558659Y-3700D03*
X555313Y17157D03*
Y-9901D03*
X551966Y-3700D03*
X548620Y17157D03*
Y-9901D03*
X571345Y-4100D03*
X568699Y17157D03*
Y-9901D03*
X595470Y-3700D03*
X592124Y17157D03*
Y-9901D03*
X564966Y-4100D03*
X561868Y17019D03*
X562006Y-9901D03*
X588777Y-3700D03*
X585431Y17157D03*
Y-9901D03*
X598817Y17057D03*
X558659Y71900D03*
X555313Y92757D03*
Y65699D03*
X551966Y71900D03*
X548620Y92757D03*
Y65699D03*
X571345Y71500D03*
X568699Y92757D03*
Y65699D03*
X595470Y71900D03*
X592124Y92757D03*
Y65699D03*
X564966Y71500D03*
X562006Y92757D03*
Y65699D03*
X565266Y87374D03*
X588777Y71900D03*
X585431Y92757D03*
Y65699D03*
X555313Y54957D03*
X548620D03*
X568699D03*
X592124D03*
X562006D03*
X585431D03*
X598817Y92657D03*
X657250Y-2050D03*
X659747Y-12132D03*
X130313Y518157D03*
X160431D03*
Y528899D03*
X130313D03*
X153738Y518157D03*
Y528899D03*
X123620Y518157D03*
Y528899D03*
X147045Y518157D03*
Y528899D03*
X167124Y518157D03*
Y528899D03*
X116927Y517900D03*
X114322Y525980D03*
X132959Y534700D03*
X163391D03*
X157084Y535100D03*
X126580Y534700D03*
X150391Y535100D03*
X169770Y534700D03*
X130313Y555957D03*
X132959Y572500D03*
X160431Y555957D03*
X163391Y572500D03*
X160431Y566699D03*
X130313D03*
X153738Y555957D03*
X157084Y572900D03*
X153738Y566699D03*
X123620Y555957D03*
X126580Y572500D03*
X123620Y566699D03*
X147045Y555957D03*
X150391Y572900D03*
X147045Y566699D03*
X167124Y555957D03*
X169770Y572500D03*
X167124Y566699D03*
X114150Y585850D03*
X114509Y575658D03*
X116927Y555700D03*
X115883Y548024D03*
X132959Y610300D03*
X130313Y593757D03*
X163391Y610300D03*
X160431Y593757D03*
Y604499D03*
X130313D03*
X157084Y610700D03*
X153738Y593757D03*
Y604499D03*
X126580Y610300D03*
X123620Y593757D03*
Y604499D03*
X150391Y610700D03*
X147045Y593757D03*
Y604499D03*
X167124Y593757D03*
X169770Y610300D03*
X167124Y604499D03*
X190549Y518157D03*
Y528899D03*
X183856Y518157D03*
Y528899D03*
X203935Y518157D03*
Y528899D03*
X227360Y518157D03*
Y528899D03*
X197242Y518157D03*
Y528899D03*
X220667Y518161D03*
Y528899D03*
X234053Y518157D03*
Y528899D03*
X193895Y535100D03*
X187202D03*
X206581Y534700D03*
X230706Y535100D03*
X200202Y534700D03*
X224013Y535100D03*
X190549Y555957D03*
X193895Y572900D03*
X190549Y566699D03*
X183856Y555957D03*
X187202Y572900D03*
X183856Y566699D03*
X203935Y555957D03*
X206581Y572500D03*
X203935Y566699D03*
X227360Y555957D03*
X230706Y572900D03*
X227360Y566699D03*
X197242Y555957D03*
X200202Y572500D03*
X197242Y566699D03*
X220667Y555961D03*
X224013Y572900D03*
X220667Y566699D03*
X234053Y555957D03*
Y566699D03*
X190549Y593757D03*
X193895Y610700D03*
X190549Y604499D03*
X183856Y593757D03*
X187202Y610700D03*
X183856Y604499D03*
X206581Y610300D03*
X203935Y593757D03*
Y604499D03*
X230706Y610700D03*
X227360Y593757D03*
Y604499D03*
X197242Y593757D03*
X200202Y610300D03*
X197242Y604499D03*
X224013Y610700D03*
X220667Y593761D03*
Y604499D03*
X234053Y593757D03*
Y604499D03*
X240746Y518157D03*
Y528899D03*
X264171Y518157D03*
Y528899D03*
X257478Y518157D03*
Y528899D03*
X277557Y518157D03*
Y528899D03*
X270864Y518157D03*
Y528899D03*
X294289Y518157D03*
Y528899D03*
X243392Y534700D03*
X267517Y535100D03*
X237013Y534700D03*
X260824Y535100D03*
X280203Y534700D03*
X273824D03*
X240746Y555957D03*
X243392Y572500D03*
X240746Y566699D03*
X264171Y555957D03*
X267517Y572900D03*
X264171Y566699D03*
X237013Y572500D03*
X257478Y555957D03*
X260824Y572900D03*
X257478Y566699D03*
X277557Y555957D03*
X280203Y572500D03*
X277557Y566699D03*
X270864Y555957D03*
X273824Y572500D03*
X270864Y566699D03*
X294289Y555957D03*
Y566699D03*
X240746Y593757D03*
X243392Y610300D03*
X240746Y604499D03*
X267517Y610700D03*
X264171Y593757D03*
Y604499D03*
X237013Y610300D03*
X257478Y593757D03*
X260824Y610700D03*
X257478Y604499D03*
X280203Y610300D03*
X277557Y593757D03*
Y604499D03*
X273824Y610300D03*
X270864Y593757D03*
Y604499D03*
X294289Y593757D03*
Y604499D03*
X321061Y518157D03*
X327754Y512792D03*
X324407Y515364D03*
Y509999D03*
X314368Y518057D03*
X311021Y510114D03*
X300982Y518157D03*
Y528899D03*
X334447Y512792D03*
X331100Y515364D03*
X354526Y518157D03*
X354307Y512792D03*
X351179Y515364D03*
X347833Y512792D03*
X344486Y510114D03*
Y515364D03*
X337793Y509999D03*
X341140Y518157D03*
X334447D03*
X317714Y510114D03*
X304328Y535100D03*
X297635D03*
X300982Y555957D03*
X304328Y572900D03*
X300982Y566699D03*
X297635Y572900D03*
X321061Y607292D03*
X327754Y612457D03*
X324407Y604499D03*
Y609864D03*
X314368Y607292D03*
X311021Y609864D03*
X304328Y610700D03*
X300982Y593757D03*
Y604499D03*
X297635Y610700D03*
X334447Y612457D03*
X331100Y604614D03*
X354526Y607292D03*
X354525Y612358D03*
X351179Y604499D03*
X347833Y612357D03*
X344486Y609864D03*
Y604614D03*
X337793Y609864D03*
X341140Y607292D03*
X334447D03*
X317714Y609864D03*
X404722Y515364D03*
X401375Y512792D03*
X414761Y518157D03*
X398029Y529007D03*
Y515364D03*
X404722Y509999D03*
X414761Y512792D03*
X408068Y518157D03*
X408069Y529007D03*
X394682Y512792D03*
X411415Y510114D03*
X394587Y529026D03*
X394595Y537058D03*
X398029Y566807D03*
X408069D03*
X394682Y550592D03*
Y588392D03*
X376892Y581127D03*
X370596Y585614D03*
X394682Y569492D03*
X404722Y604499D03*
X401376Y612658D03*
X414761Y607292D03*
X398029Y604499D03*
X404722Y609864D03*
X414761Y612657D03*
X408068Y607292D03*
X394682Y612657D03*
X378600Y606200D03*
X371312Y604709D03*
X411415Y609864D03*
X394682Y607292D03*
X438187Y510114D03*
X431494Y515364D03*
X444880D03*
Y510114D03*
X458266Y518157D03*
Y528899D03*
X481691Y518157D03*
Y528899D03*
X451573Y518157D03*
Y528899D03*
X474998Y518157D03*
Y528899D03*
X428147Y512792D03*
X421454Y518157D03*
X434840Y512792D03*
X424801Y515364D03*
X438187D03*
X460912Y534700D03*
X454533D03*
X478344Y535100D03*
X431494Y566807D03*
X458266Y555957D03*
X460912Y572500D03*
X458266Y566699D03*
X481691Y555957D03*
Y566699D03*
X451573Y555957D03*
X454533Y572500D03*
X451573Y566699D03*
X474998Y555957D03*
X478344Y572900D03*
X474998Y566699D03*
X424801Y566807D03*
X438187Y609864D03*
X431494Y604499D03*
X444880Y604614D03*
Y609864D03*
X458266Y593757D03*
X460912Y610300D03*
X458266Y604499D03*
X481691Y593757D03*
Y604499D03*
X454533Y610300D03*
X451573Y593757D03*
Y604499D03*
X474998Y593757D03*
Y604499D03*
X428147Y612657D03*
X421454Y607292D03*
X434840Y612657D03*
X424801Y604614D03*
X438187D03*
X447766Y612659D03*
X495077Y518157D03*
Y528899D03*
X518502Y518157D03*
Y528899D03*
X488384Y518157D03*
Y528899D03*
X511809Y518157D03*
Y528899D03*
X531888Y518157D03*
Y528899D03*
X525195Y518157D03*
Y528899D03*
X485037Y535100D03*
X497723Y534700D03*
X521848Y535100D03*
X491344Y534700D03*
X515155Y535100D03*
X534534Y534700D03*
X528155D03*
X485037Y572900D03*
X495077Y555957D03*
X497723Y572500D03*
X495077Y566699D03*
X518502Y555957D03*
X521848Y572900D03*
X518502Y566699D03*
X488384Y555957D03*
X491344Y572500D03*
X488384Y566699D03*
X511809Y555957D03*
X515155Y572900D03*
X511809Y566699D03*
X531888Y555957D03*
X534534Y572500D03*
X531888Y566699D03*
X525195Y555957D03*
X528155Y572500D03*
X525195Y566699D03*
X485037Y610700D03*
X495077Y593757D03*
X498092Y611200D03*
X495077Y604499D03*
X521848Y610700D03*
X518502Y593757D03*
Y604499D03*
X488384Y593757D03*
X491724Y611668D03*
X488384Y604499D03*
X515155Y610700D03*
X511809Y593757D03*
Y604499D03*
X534534Y610300D03*
X531888Y593757D03*
Y604499D03*
X528155Y610300D03*
X525195Y593757D03*
Y604499D03*
X555313Y518157D03*
Y528899D03*
X548620Y518157D03*
Y528899D03*
X568699Y518157D03*
Y528899D03*
X592124Y518157D03*
Y528899D03*
X562006Y518157D03*
Y528899D03*
X565266Y512774D03*
X585431Y518157D03*
Y528899D03*
X598817Y518057D03*
X558659Y535100D03*
X551966D03*
X571345Y534700D03*
X595470Y535100D03*
X564966Y534700D03*
X588777Y535100D03*
X555313Y555957D03*
X558659Y572900D03*
X555313Y566699D03*
X548620Y555957D03*
X551966Y572900D03*
X548620Y566699D03*
X568699Y555957D03*
X571345Y572500D03*
X568699Y566699D03*
X592124Y555957D03*
X595470Y572900D03*
X592124Y566699D03*
X562006Y555957D03*
X564966Y572500D03*
X565266Y550574D03*
X562006Y566699D03*
X585431Y555957D03*
X588777Y572900D03*
X585431Y566699D03*
X565052Y588714D03*
X558659Y610700D03*
X555313Y593757D03*
Y604499D03*
X551966Y610700D03*
X548620Y593757D03*
Y604499D03*
X571345Y610300D03*
X568699Y593757D03*
Y604499D03*
X592124Y593757D03*
X595470Y610700D03*
X592124Y604499D03*
X564966Y610300D03*
X562006Y593757D03*
Y604499D03*
X585431Y593757D03*
X588777Y610700D03*
X585431Y604499D03*
X598817Y593657D03*
X660217Y576734D03*
X665000Y598500D03*
X274619Y271509D03*
X294899D03*
Y267609D03*
X291519Y273460D03*
X277999D03*
X355737Y252009D03*
X348978D03*
X321938D03*
X352357Y253960D03*
X345598D03*
X355737Y255909D03*
X348978D03*
X338838Y273460D03*
X345598Y261760D03*
X338838Y269560D03*
X332078Y273460D03*
X298279D03*
X335458Y275409D03*
X328698D03*
X338838Y277360D03*
X332078D03*
X325318D03*
X335458Y279310D03*
X328698D03*
X321938D03*
X335458Y271509D03*
X301659D03*
X328698D03*
X298279Y269560D03*
X348978Y259809D03*
X345598Y257860D03*
X352357D03*
X359117Y253960D03*
X362497Y252009D03*
X407448Y338641D03*
X394648Y338341D03*
X430089Y338428D03*
X426494Y338361D03*
X288139Y322209D03*
X291519Y324160D03*
X294899Y326109D03*
Y330009D03*
X415634Y239596D03*
Y243496D03*
X419214Y245447D03*
X418084Y253546D03*
X452865Y270081D03*
X465100Y280300D03*
X434983Y255497D03*
X438363Y257446D03*
X421464Y255497D03*
X431604Y257446D03*
X441743Y259397D03*
X455263Y267197D03*
X436113Y247396D03*
X446253Y249347D03*
X442873Y251296D03*
X439493Y249347D03*
X442873Y247396D03*
X439493Y245447D03*
X446253Y253247D03*
X466533Y261047D03*
X463153Y262996D03*
X477792Y276646D03*
Y280547D03*
X469913Y282496D03*
X474413Y274696D03*
X469913Y278596D03*
X466533Y268847D03*
X422594Y247396D03*
X459773Y264947D03*
X469913Y266896D03*
Y262996D03*
X473292Y261047D03*
X469913Y259096D03*
X481172Y282496D03*
Y333196D03*
Y298096D03*
X469913D03*
Y301996D03*
X481172Y305896D03*
X477792Y284447D03*
Y296147D03*
Y300047D03*
Y292247D03*
X481172Y294196D03*
X469913D03*
Y290296D03*
X463800Y289500D03*
X466100Y300021D03*
X481172Y286396D03*
Y348796D03*
X511592Y222047D03*
X514972Y220096D03*
X518352Y222047D03*
X521731Y216196D03*
X531871Y218147D03*
X542011Y208396D03*
X528491Y204496D03*
X538631Y202247D03*
X484552Y272747D03*
Y276646D03*
X501452Y270796D03*
X511592Y268847D03*
X514972Y255196D03*
X501452D03*
Y251296D03*
X521731Y270796D03*
X514972Y282496D03*
X521731D03*
X508212D03*
X494692D03*
X491312Y280547D03*
X486812Y261047D03*
X483432Y262996D03*
X498072Y280547D03*
X514972Y274696D03*
X518352Y257147D03*
X508212Y274696D03*
X504832Y268847D03*
X491312Y272747D03*
X511592D03*
X504832Y276647D03*
X498072Y245447D03*
X494692Y223996D03*
X504832Y225947D03*
X484552Y280547D03*
X518352Y233746D03*
X531871Y241547D03*
Y249347D03*
X528491Y223996D03*
X531871Y237647D03*
X535251Y223996D03*
X542011D03*
X528491Y270796D03*
Y278596D03*
X542011Y270796D03*
X535251Y255196D03*
X531871Y264947D03*
X494692Y266896D03*
X504832Y257147D03*
X508212Y251296D03*
X504832Y249347D03*
X508212Y247396D03*
X518352Y264947D03*
X508212Y243496D03*
X521731D03*
X528491Y262996D03*
Y266896D03*
X498072Y249347D03*
X521731Y278596D03*
X498072Y276647D03*
X491312D03*
X511592D03*
X504832Y272747D03*
X498072Y253247D03*
Y257147D03*
X518352Y280547D03*
X525111Y276646D03*
X504832Y280547D03*
X511592D03*
X518352Y276646D03*
X498072Y272747D03*
X531871Y253247D03*
X528491Y251296D03*
X525111Y241547D03*
X528491Y239596D03*
X501452Y262996D03*
X504832Y261047D03*
X501452Y278596D03*
X498072Y261047D03*
X494692Y259096D03*
X521731Y262996D03*
X525111Y264947D03*
X494692Y274696D03*
X487932Y313696D03*
X491312Y315647D03*
X484552Y319546D03*
Y331247D03*
X491312Y288347D03*
Y284447D03*
X498072D03*
Y288347D03*
X501452Y286396D03*
X494692Y290296D03*
X498072Y292247D03*
X504832D03*
X518352Y284447D03*
X504832Y288347D03*
Y284447D03*
X508212Y286396D03*
X531871Y315647D03*
X487932Y286396D03*
Y290296D03*
X484552Y288347D03*
Y296147D03*
X504832Y327347D03*
X508212Y321496D03*
X521731D03*
X484552Y284447D03*
X487932Y305896D03*
X491312Y303947D03*
X501452Y305896D03*
X494692Y298096D03*
X498072Y307847D03*
X484552Y303947D03*
X487932Y294196D03*
X491312Y296147D03*
X494692Y301996D03*
X487932D03*
X501452Y309797D03*
X487932Y298096D03*
X511592Y311747D03*
X508212Y309797D03*
X511592Y300047D03*
Y303947D03*
X542011Y309797D03*
X538631Y307847D03*
Y303947D03*
Y300047D03*
X535251Y298096D03*
X542011Y305896D03*
X535251D03*
X542011Y301996D03*
X538631Y296147D03*
X531871D03*
X535251Y313696D03*
X484552Y311747D03*
Y315647D03*
X511592Y288347D03*
Y292245D03*
X491312Y323446D03*
X528491Y305896D03*
X518352Y311747D03*
X504832D03*
X508212Y305896D03*
Y301996D03*
X504832Y303947D03*
Y300045D03*
X518352Y303947D03*
X514972Y305896D03*
Y309797D03*
X528491Y301996D03*
Y309797D03*
X525111Y311747D03*
Y307847D03*
Y303947D03*
X521731Y305896D03*
Y309797D03*
X518352Y307847D03*
X514972Y313696D03*
X528491D03*
X521731D03*
X494692Y317596D03*
X487932Y321496D03*
X484552Y327347D03*
X487932Y325396D03*
X558911Y218147D03*
X552151Y237647D03*
X555531Y231797D03*
X548771Y227896D03*
X552151Y245447D03*
X548771Y251296D03*
X545391Y237647D03*
X548771Y282496D03*
Y270796D03*
Y262996D03*
X545391Y276646D03*
X548771Y290296D03*
Y294196D03*
Y301996D03*
Y298096D03*
X644750Y175650D03*
X660600Y170000D03*
Y175000D03*
X464273Y342947D03*
X471033Y339047D03*
Y342947D03*
X460893Y344896D03*
X469913Y309797D03*
Y313696D03*
Y317596D03*
X471033Y346847D03*
X464273D03*
X542011Y317596D03*
X504832Y370247D03*
X508212Y376096D03*
X501452Y372197D03*
X498072Y370247D03*
X504832Y397546D03*
Y393647D03*
X511592D03*
X501452Y387796D03*
X511592Y385847D03*
X518352D03*
Y381947D03*
Y378047D03*
X508212Y395597D03*
X504832Y389747D03*
X508212Y391696D03*
X504832Y385847D03*
X511592Y381947D03*
X514972Y383896D03*
X521731Y379996D03*
X518352Y374146D03*
Y405347D03*
X525111D03*
Y401447D03*
X528491Y395597D03*
X535251Y399496D03*
X531871Y393647D03*
X538631Y389747D03*
Y385847D03*
X518352Y401447D03*
X521731Y403396D03*
X528491Y399496D03*
X531871Y397546D03*
X535251Y395597D03*
Y391696D03*
Y387796D03*
X542011Y383896D03*
Y391696D03*
Y395597D03*
Y387796D03*
X525111Y370247D03*
X531871D03*
X525111Y362447D03*
X528491Y360496D03*
Y356596D03*
X535251Y352696D03*
X525111Y378047D03*
Y374146D03*
Y366347D03*
X528491Y368296D03*
X521731Y364396D03*
X525111Y358547D03*
X531871Y354647D03*
Y350747D03*
X521731Y376096D03*
X528491Y372197D03*
X542011Y379996D03*
X535251Y376096D03*
X548771Y321496D03*
X545391Y323446D03*
X552151Y319547D03*
Y315647D03*
Y311747D03*
X559211Y331103D03*
X555531Y329296D03*
X559211Y323446D03*
X555531Y321496D03*
X548771Y317596D03*
X555831Y313696D03*
X552151Y307847D03*
X559211Y327347D03*
X552151D03*
X555531Y325396D03*
X555831Y317446D03*
X545391Y389747D03*
Y393647D03*
Y378047D03*
X552151Y374146D03*
X545391D03*
X548771Y364396D03*
Y360496D03*
Y356596D03*
Y383896D03*
Y376096D03*
Y372196D03*
X545391Y370247D03*
Y362447D03*
X552151Y358547D03*
X548771Y352696D03*
X545391Y381947D03*
X548771Y379996D03*
X552151Y366347D03*
Y370247D03*
X563500Y360500D03*
X555531Y372197D03*
X562591Y348796D03*
X633410Y269610D03*
Y274610D03*
X651235Y249165D03*
X641665Y281139D03*
X643100Y253700D03*
X649800Y252600D03*
X652700Y270600D03*
X617235Y247735D03*
X614456Y244956D03*
X628950Y293550D03*
X665396Y23000D03*
X724837Y13852D03*
X714300Y-1900D03*
X680200Y13100D03*
X719400Y14300D03*
X679936Y18406D03*
X729600Y17991D03*
X734256D03*
X913779Y112327D03*
X907086D03*
X927165D03*
X920472D03*
X944497Y110927D03*
X963245Y105725D03*
X1144535Y112357D03*
X1138242D03*
X1167925D03*
X1161632D03*
X1181496D03*
X1204921D03*
X1174742D03*
X1198228D03*
X1270350Y98300D03*
X1264550Y114670D03*
X1261030Y105350D03*
X1275470Y99390D03*
X1257800Y120800D03*
X1336850Y76450D03*
X1336900Y61600D03*
X1343260Y53770D03*
X1327500Y51547D03*
X1327452Y55544D03*
X1336500Y81100D03*
X1337400Y72000D03*
X1323000Y83000D03*
X1328500Y92500D03*
X1301770Y101300D03*
X1400616Y13795D03*
X1477100Y2400D03*
X1522600Y-6500D03*
X1481600Y5300D03*
X1501900Y-9124D03*
X1506300Y-6600D03*
X1521092Y21665D03*
X1520700Y7100D03*
X1513700Y7082D03*
X1549600Y-10800D03*
X1590431Y-6702D03*
X1544882Y-6900D03*
X1540000Y3400D03*
X1545111Y24172D03*
X1580398Y-600D03*
Y5400D03*
X1571500Y-1406D03*
X1545250Y88360D03*
X1541520Y79387D03*
X1556810Y71760D03*
X1617500Y-14500D03*
X1638550Y7200D03*
X1598602Y3437D03*
X1692300Y56900D03*
X1658600Y44700D03*
X1708610Y85121D03*
X1696870Y86093D03*
X1707268Y77668D03*
X1704824Y90049D03*
X1715837Y246178D03*
X1664453Y308557D03*
X1660834Y404934D03*
X1660890Y397300D03*
X1673074Y453185D03*
X1678303Y442765D03*
X1749085Y9177D03*
X1771707Y86500D03*
X1767250Y94500D03*
Y89500D03*
X1766333Y59116D03*
X1775000Y53500D03*
X1757772Y90174D03*
X1720651Y246141D03*
X1746900Y249804D03*
X1751900Y249700D03*
X1724181Y246159D03*
X1730996Y442804D03*
X1813913Y2287D03*
X1790078Y11860D03*
X1795078Y11900D03*
X1829636Y26680D03*
X1831000Y-16300D03*
X1828874Y-13520D03*
X1815150Y26650D03*
X1779750Y36530D03*
X1791500Y26918D03*
X1808100Y21800D03*
X1786865Y22375D03*
X1823600Y8800D03*
X1797700Y21018D03*
X1837500Y35700D03*
X1838850Y13160D03*
X1836700Y-18900D03*
X1804800Y-1500D03*
X1816723Y9781D03*
X1826414Y35486D03*
X1803300Y39900D03*
X1812352Y36949D03*
X1810100Y114700D03*
X1803509Y128500D03*
X1807818Y124179D03*
X1815026Y121478D03*
X1808313Y111705D03*
X1807509Y128500D03*
X1814900Y116900D03*
X1796500Y120000D03*
X1815348Y143437D03*
X1809810Y155858D03*
X1800792Y122691D03*
X1824990Y103620D03*
X1807166Y147401D03*
X1800420Y148240D03*
X1821261Y170012D03*
X1836900Y165800D03*
X1834103Y176021D03*
X1836932Y170486D03*
X1816125Y169492D03*
X1834400Y216900D03*
X1785500Y168000D03*
X1826662Y232191D03*
X1831700Y252272D03*
X1900256Y-14760D03*
X1882999Y7383D03*
X1843107Y97988D03*
X1885700Y141200D03*
X1897536Y120510D03*
X1867280Y135406D03*
X1881165Y105561D03*
X1857849Y148079D03*
X1872254Y138618D03*
X1857919Y156123D03*
X1864904Y114735D03*
X1897507Y124450D03*
X1893238Y208042D03*
X1863650Y189750D03*
X1877880Y203780D03*
X1896710Y194380D03*
X1882452Y195888D03*
X1901100Y194200D03*
X1889400Y191200D03*
X1886200Y161000D03*
X1875700Y184800D03*
X1876700Y207600D03*
X1862000Y177500D03*
X1884000Y188100D03*
X1884400Y183700D03*
X1891880Y204370D03*
X1856874Y219443D03*
X1850723Y219250D03*
X1865100Y174600D03*
X1877517Y217988D03*
X1885000Y227500D03*
X1844444Y224035D03*
X1878100Y450200D03*
X1916078Y-16368D03*
X1927000Y152200D03*
X1903150Y217250D03*
X1917024Y193600D03*
X1929700Y163400D03*
X1921500Y193600D03*
X1903917Y201472D03*
X1925000Y192000D03*
X1918489Y212513D03*
X1930500Y209464D03*
X1918143Y219848D03*
X1927064Y207564D03*
X1937430Y464785D03*
X1939845Y445055D03*
X1938300Y486250D03*
X1919510Y475100D03*
Y479200D03*
X1957212Y479521D03*
X1957063Y474769D03*
X1928620Y482710D03*
X718200Y581000D03*
X717612Y598554D03*
X779921Y518157D03*
Y528899D03*
X773228Y518157D03*
Y528899D03*
X766535Y517900D03*
X782567Y534700D03*
X776188D03*
X779921Y555957D03*
X782567Y572500D03*
X779921Y566699D03*
X773228Y555957D03*
X776188Y572500D03*
X773228Y566699D03*
X764117Y575658D03*
X765100Y537110D03*
X766535Y555700D03*
X782567Y610300D03*
X779921Y593757D03*
Y604499D03*
X776188Y610300D03*
X773228Y593757D03*
Y604499D03*
X840157Y518157D03*
Y528899D03*
X810039Y518157D03*
Y528899D03*
X833464Y518157D03*
Y528899D03*
X846850Y518157D03*
Y528899D03*
X803346Y518157D03*
Y528899D03*
X796653Y518157D03*
Y528899D03*
X816732Y518157D03*
Y528899D03*
X843503Y535100D03*
X812999Y534700D03*
X836810Y535100D03*
X849810Y534700D03*
X806692Y535100D03*
X799999D03*
X819378Y534700D03*
X840157Y555957D03*
X843503Y572900D03*
X840157Y566699D03*
X810039Y555957D03*
X812999Y572500D03*
X810039Y566699D03*
X833464Y555957D03*
X836810Y572900D03*
X833464Y566699D03*
X846850Y555957D03*
X849810Y572500D03*
X846850Y566699D03*
X803346Y555957D03*
X806692Y572900D03*
X803346Y566699D03*
X796653Y555957D03*
X799999Y572900D03*
X796653Y566699D03*
X816732Y555957D03*
X819378Y572500D03*
X816732Y566699D03*
X840157Y593757D03*
X843503Y610700D03*
X840157Y604499D03*
X812999Y610300D03*
X810039Y593757D03*
Y604499D03*
X833464Y593757D03*
X836810Y610700D03*
X833464Y604499D03*
X846850Y593757D03*
X849810Y610300D03*
X846850Y604499D03*
X806692Y610700D03*
X803346Y593757D03*
Y604499D03*
X799999Y610700D03*
X796653Y593757D03*
Y604499D03*
X816732Y593757D03*
X819378Y610300D03*
X816732Y604499D03*
X853543Y518157D03*
Y528899D03*
X876968Y518157D03*
Y528899D03*
X870275Y518161D03*
Y528899D03*
X890354Y518157D03*
Y528899D03*
X913779Y518157D03*
Y528899D03*
X883661Y518157D03*
Y528899D03*
X907086Y518157D03*
Y528899D03*
X856189Y534700D03*
X880314Y535100D03*
X873621D03*
X893000Y534700D03*
X886621D03*
X910432Y535100D03*
X853543Y555957D03*
X856189Y572500D03*
X853543Y566699D03*
X876968Y555957D03*
X880314Y572900D03*
X876968Y566699D03*
X870275Y555961D03*
X873621Y572900D03*
X870275Y566699D03*
X893000Y572500D03*
X890354Y555957D03*
Y566699D03*
X913779Y555957D03*
Y566699D03*
X886621Y572500D03*
X883661Y555957D03*
Y566699D03*
X910432Y572900D03*
X907086Y555957D03*
Y566699D03*
X853543Y593757D03*
X856189Y610300D03*
X853543Y604499D03*
X876968Y593757D03*
X880314Y610700D03*
X876968Y604499D03*
X870275Y593761D03*
X873621Y610700D03*
X870275Y604499D03*
X893000Y610300D03*
X890354Y593757D03*
Y604499D03*
X913779Y593757D03*
Y604499D03*
X886621Y610300D03*
X883661Y593757D03*
Y604499D03*
X907086Y593757D03*
X910432Y610700D03*
X907086Y604499D03*
X970669Y518157D03*
X974015Y515364D03*
Y509999D03*
X963976Y518057D03*
X960629Y510114D03*
X927165Y518157D03*
Y528899D03*
X950590Y518157D03*
Y528899D03*
X920472Y518157D03*
Y528899D03*
X943897Y518157D03*
Y528899D03*
X967322Y510114D03*
X917125Y535100D03*
X929811Y534700D03*
X953936Y535100D03*
X923432Y534700D03*
X947243Y535100D03*
X917125Y572900D03*
X929811Y572500D03*
X927165Y555957D03*
Y566699D03*
X953936Y572900D03*
X950590Y555957D03*
Y566699D03*
X923432Y572500D03*
X920472Y555957D03*
Y566699D03*
X947243Y572900D03*
X943897Y555957D03*
Y566699D03*
X970669Y607292D03*
X974015Y604499D03*
Y609864D03*
X963976Y607292D03*
X960629Y609864D03*
X917125Y610700D03*
X929811Y610300D03*
X927165Y593757D03*
Y604499D03*
X953936Y610700D03*
X950590Y593757D03*
Y604499D03*
X923432Y610300D03*
X920472Y593757D03*
Y604499D03*
X947243Y610700D03*
X943897Y593757D03*
Y604499D03*
X967322Y609864D03*
X977362Y512792D03*
X984055D03*
X980708Y515364D03*
X1004134Y518157D03*
X1003915Y512792D03*
X1000787Y515364D03*
X997441Y512792D03*
X994094Y510114D03*
Y515364D03*
X987401Y509999D03*
X990748Y518157D03*
X984055D03*
X1026500Y581000D03*
X1019800Y555800D03*
X977362Y612457D03*
X984055D03*
X980708Y604614D03*
X1004134Y607292D03*
X1004133Y612358D03*
X1000787Y604499D03*
X997441Y612357D03*
X994094Y609864D03*
Y604614D03*
X987401Y609864D03*
X990748Y607292D03*
X984055D03*
X1020700Y604600D03*
X1029777Y613581D03*
X1054330Y515364D03*
X1050983Y512792D03*
X1087795Y510114D03*
X1064369Y518157D03*
X1081102Y515364D03*
X1094488D03*
Y510114D03*
X1047637Y529007D03*
Y515364D03*
X1054330Y509999D03*
X1077755Y512792D03*
X1064369D03*
X1071062Y518157D03*
X1057677Y529007D03*
X1057676Y518157D03*
X1084448Y512792D03*
X1074409Y515364D03*
X1087795D03*
X1044290Y512792D03*
X1061023Y510114D03*
X1044195Y529026D03*
X1044203Y537058D03*
X1081102Y566807D03*
X1047637D03*
X1057677D03*
X1074409D03*
X1044290Y550592D03*
Y588392D03*
Y569492D03*
X1054330Y604499D03*
X1050984Y612658D03*
X1087795Y609864D03*
X1064369Y607292D03*
X1081102Y604499D03*
X1094488Y604614D03*
Y609864D03*
X1047637Y604499D03*
X1054330Y609864D03*
X1077755Y612657D03*
X1064369D03*
X1071062Y607292D03*
X1057676D03*
X1084448Y612657D03*
X1074409Y604614D03*
X1087795D03*
X1074409Y593642D03*
X1044291Y612658D03*
X1097374Y612659D03*
X1061023Y609864D03*
X1044290Y607292D03*
X1107874Y518157D03*
Y528899D03*
X1131299Y518157D03*
Y528899D03*
X1101181Y518157D03*
Y528899D03*
X1124606Y518157D03*
Y528899D03*
X1144685Y518157D03*
Y528899D03*
X1137992Y518157D03*
Y528899D03*
X1110520Y534700D03*
X1134645Y535100D03*
X1104141Y534700D03*
X1127952Y535100D03*
X1147331Y534700D03*
X1140952D03*
X1107874Y555957D03*
X1110520Y572500D03*
X1107874Y566699D03*
X1131299Y555957D03*
X1134645Y572900D03*
X1131299Y566699D03*
X1101181Y555957D03*
X1104141Y572500D03*
X1101181Y566699D03*
X1124606Y555957D03*
X1127952Y572900D03*
X1124606Y566699D03*
X1147331Y572500D03*
X1144685Y555957D03*
Y566699D03*
X1140952Y572500D03*
X1137992Y555957D03*
Y566699D03*
X1110520Y610300D03*
X1107874Y593757D03*
Y604499D03*
X1134645Y610700D03*
X1131299Y593757D03*
Y604499D03*
X1101181Y593757D03*
X1104141Y610300D03*
X1101181Y604499D03*
X1124606Y593757D03*
X1127952Y610700D03*
X1124606Y604499D03*
X1147700Y611200D03*
X1144685Y593757D03*
Y604499D03*
X1137992Y593757D03*
X1141332Y611668D03*
X1137992Y604499D03*
X1168110Y518157D03*
Y528899D03*
X1161417Y518157D03*
Y528899D03*
X1181496Y518157D03*
Y528899D03*
X1204921Y518157D03*
Y528899D03*
X1174803Y518157D03*
Y528899D03*
X1198228Y518157D03*
Y528899D03*
X1218307Y518157D03*
Y528899D03*
X1211614Y518157D03*
X1214874Y512774D03*
X1211614Y528899D03*
X1171456Y535100D03*
X1164763D03*
X1184142Y534700D03*
X1208267Y535100D03*
X1177763Y534700D03*
X1201574Y535100D03*
X1220953Y534700D03*
X1214574D03*
X1171456Y572900D03*
X1168110Y555957D03*
Y566699D03*
X1164763Y572900D03*
X1161417Y555957D03*
Y566699D03*
X1184142Y572500D03*
X1181496Y555957D03*
Y566699D03*
X1208267Y572900D03*
X1204921Y555957D03*
Y566699D03*
X1177763Y572500D03*
X1174803Y555957D03*
Y566699D03*
X1201574Y572900D03*
X1198228Y555957D03*
Y566699D03*
X1218307Y555957D03*
X1220953Y572500D03*
X1218307Y566699D03*
X1211614Y555957D03*
X1214574Y572500D03*
X1214874Y550574D03*
X1211614Y566699D03*
X1214660Y588714D03*
X1168110Y593757D03*
X1171456Y610700D03*
X1168110Y604499D03*
X1161417Y593757D03*
X1164763Y610700D03*
X1161417Y604499D03*
X1181496Y593757D03*
X1184142Y610300D03*
X1181496Y604499D03*
X1208267Y610700D03*
X1204921Y593757D03*
Y604499D03*
X1174803Y593757D03*
X1177763Y610300D03*
X1174803Y604499D03*
X1198228Y593757D03*
X1201574Y610700D03*
X1198228Y604499D03*
X1218307Y593757D03*
X1220953Y610300D03*
X1218307Y604499D03*
X1211614Y593757D03*
X1214574Y610300D03*
X1211614Y604499D03*
X1241732Y518157D03*
Y528899D03*
X1235039Y518157D03*
Y528899D03*
X1278573Y519596D03*
X1248425Y518057D03*
X1245078Y535100D03*
X1238385D03*
X1241732Y555957D03*
X1245078Y572900D03*
X1241732Y566699D03*
X1238385Y572900D03*
X1235039Y555957D03*
Y566699D03*
X1251771Y547957D03*
Y585757D03*
Y566699D03*
X1255120Y555144D03*
X1241732Y593757D03*
X1245078Y610700D03*
X1241732Y604499D03*
X1238385Y610700D03*
X1235039Y593757D03*
Y604499D03*
X1248425Y593657D03*
X1308500Y540784D03*
X1318500Y539900D03*
X1305500Y542500D03*
X782567Y33700D03*
X779921Y27899D03*
X776188Y33700D03*
X773228Y27899D03*
X782567Y-4100D03*
X779921Y17157D03*
Y-9901D03*
X776188Y-4100D03*
X773228Y17157D03*
Y-9901D03*
X763500Y23940D03*
X765900Y35800D03*
X765400Y-9800D03*
X766300Y-1800D03*
X755000Y17255D03*
X782567Y71500D03*
X779921Y65699D03*
X776188Y71500D03*
X773228Y65699D03*
X779921Y54957D03*
X773228D03*
X843503Y34100D03*
X840157Y27899D03*
X812999Y33700D03*
X810039Y27899D03*
X836810Y34100D03*
X833464Y27899D03*
X849810Y33700D03*
X846850Y27899D03*
X806692Y34100D03*
X803346Y27899D03*
X799999Y34100D03*
X796653Y27899D03*
X819378Y33700D03*
X816732Y27899D03*
X843503Y-3700D03*
X840157Y17157D03*
Y-9901D03*
X812999Y-4100D03*
X810039Y17157D03*
Y-9901D03*
X833464Y17157D03*
X836810Y-3700D03*
X833464Y-9901D03*
X849810Y-4100D03*
X846850Y17157D03*
Y-9901D03*
X806692Y-3700D03*
X803346Y17157D03*
Y-9901D03*
X799999Y-3700D03*
X796653Y17157D03*
Y-9901D03*
X816732Y17157D03*
X819378Y-4100D03*
X816732Y-9901D03*
X843503Y71900D03*
X840157Y65699D03*
X812999Y71500D03*
X810039Y65699D03*
X836810Y71900D03*
X833464Y65699D03*
X849810Y71500D03*
X846850Y65699D03*
X806692Y71900D03*
X803346Y65699D03*
X799999Y71900D03*
X796653Y65699D03*
X819378Y71500D03*
X816732Y65699D03*
X840157Y54957D03*
X810039D03*
X833464D03*
X846850D03*
X803346D03*
X796653D03*
X816732D03*
X856189Y33700D03*
X853543Y27899D03*
X880314Y34100D03*
X876968Y27899D03*
X873621Y34100D03*
X870275Y27899D03*
X893000Y33700D03*
X890354Y27899D03*
X913779D03*
X886621Y33700D03*
X883661Y27899D03*
X910432Y34100D03*
X907086Y27899D03*
X856189Y-4100D03*
X853543Y17157D03*
Y-9901D03*
X880314Y-3700D03*
X876968Y17157D03*
Y-9901D03*
X873621Y-3700D03*
X870275Y17157D03*
Y-9901D03*
X893000Y-4100D03*
X890354Y17157D03*
Y-9901D03*
X913779Y17157D03*
Y-9901D03*
X883661Y17157D03*
X886621Y-4100D03*
X883661Y-9901D03*
X907086Y17157D03*
X910432Y-3700D03*
X907086Y-9901D03*
X856189Y71500D03*
X853543Y65699D03*
X880314Y71900D03*
X876968Y65699D03*
X873621Y71900D03*
X870275Y65699D03*
X893000Y71500D03*
X890354Y65699D03*
X913779D03*
X886621Y71500D03*
X883661Y65699D03*
X910432Y71900D03*
X907086Y65699D03*
X853543Y54957D03*
X876968D03*
X870275D03*
X890354D03*
X913779D03*
X883661D03*
X907086D03*
X917125Y34100D03*
X929811Y33700D03*
X927165Y27899D03*
X953936Y34100D03*
X950590Y27899D03*
X923432Y33700D03*
X920472Y27899D03*
X947243Y34100D03*
X943897Y27899D03*
X970669Y-7108D03*
X974015Y-9901D03*
Y-4536D03*
X963976Y-7108D03*
X960629Y-4536D03*
X917125Y-3700D03*
X929811Y-4100D03*
X927165Y17157D03*
Y-9901D03*
X953936Y-3700D03*
X950590Y17157D03*
Y-9901D03*
X923432Y-4100D03*
X920472Y17157D03*
Y-9901D03*
X947243Y-3700D03*
X943897Y17157D03*
Y-9901D03*
X967322Y-4536D03*
X974015Y89964D03*
Y84599D03*
X960629Y84714D03*
X917125Y71900D03*
X929811Y71500D03*
X927165Y65699D03*
X953936Y71900D03*
X950590Y65699D03*
X923432Y71500D03*
X920472Y65699D03*
X947243Y71900D03*
X943897Y65699D03*
X927165Y54957D03*
X950590D03*
X920472D03*
X923518Y49914D03*
X943897Y54957D03*
X967322Y84714D03*
X977362Y-1743D03*
X984055D03*
X980708Y-9786D03*
X1004134Y-7108D03*
X1004133Y-1742D03*
X1000787Y-9901D03*
X997441Y-1743D03*
X994094Y-4536D03*
Y-9786D03*
X987401Y-4536D03*
X990748Y-7108D03*
X984055D03*
X1020866Y-1858D03*
X1027202Y-11005D03*
X977362Y87392D03*
X984055D03*
X980708Y89964D03*
X1004023Y87392D03*
X1000787Y89964D03*
X997441Y87392D03*
X994094Y84714D03*
Y89964D03*
X987401Y84599D03*
X1020650Y46900D03*
X1030300Y63200D03*
X1081102Y28007D03*
X1047637D03*
X1057677D03*
X1074409D03*
X1054330Y-9901D03*
X1050983Y-1743D03*
X1087795Y-4536D03*
X1064369Y-7108D03*
X1081102Y-9901D03*
X1094488Y-9786D03*
Y-4536D03*
X1047637Y-9901D03*
X1054330Y-4536D03*
X1077755Y-1743D03*
X1064369D03*
X1071062Y-7108D03*
X1057676D03*
X1084448Y-1743D03*
X1074409Y-9786D03*
X1087795D03*
X1044290Y11792D03*
X1044291Y-2200D03*
X1061023Y-4536D03*
X1054330Y89964D03*
X1050983Y87392D03*
X1087795Y84714D03*
X1081102Y65807D03*
Y89964D03*
X1094488D03*
Y84714D03*
X1047637Y65807D03*
Y89964D03*
X1054330Y84599D03*
X1077755Y87392D03*
X1064369D03*
X1057677Y65807D03*
X1084448Y87392D03*
X1074409Y65807D03*
Y89964D03*
X1087795D03*
X1044290Y87392D03*
Y49592D03*
X1061023Y84714D03*
X1044290Y68964D03*
X1110520Y33700D03*
X1107874Y27899D03*
X1134645Y34100D03*
X1131299Y27899D03*
X1104141Y33700D03*
X1101181Y27899D03*
X1127952Y34100D03*
X1124606Y27899D03*
X1147331Y33700D03*
X1144685Y27899D03*
X1140952Y33700D03*
X1137992Y27899D03*
X1110520Y-4100D03*
X1107874Y17157D03*
Y-9901D03*
X1134645Y-3700D03*
X1131299Y17157D03*
Y-9901D03*
X1104141Y-4100D03*
X1101181Y-9901D03*
X1127952Y-3700D03*
X1124606Y17157D03*
Y-9901D03*
X1147331Y-4100D03*
X1144685Y17157D03*
Y-9901D03*
X1140952Y-4100D03*
X1137992Y17157D03*
Y-9901D03*
X1110520Y71500D03*
X1107874Y65699D03*
X1134645Y71900D03*
X1131299Y65699D03*
X1104141Y71500D03*
X1101181Y65699D03*
X1127952Y71900D03*
X1124606Y65699D03*
X1147331Y71500D03*
X1144685Y65699D03*
X1140952Y71500D03*
X1137992Y65699D03*
X1107874Y54957D03*
X1131299D03*
X1124606D03*
X1144685D03*
X1137992D03*
X1141038Y49914D03*
X1171456Y34100D03*
X1168110Y27899D03*
X1164763Y34100D03*
X1161417Y27899D03*
X1184142Y33700D03*
X1181496Y27899D03*
X1208267Y34100D03*
X1204921Y27899D03*
X1177763Y33700D03*
X1174803Y27899D03*
X1201574Y34100D03*
X1198228Y27899D03*
X1220953Y33700D03*
X1218307Y27899D03*
X1214574Y33700D03*
X1211614Y27899D03*
X1171456Y-3700D03*
X1168110Y17157D03*
Y-9901D03*
X1164763Y-3700D03*
X1161417Y17157D03*
Y-9901D03*
X1184142Y-4100D03*
X1181496Y17157D03*
Y-9901D03*
X1204921Y17157D03*
X1208267Y-3700D03*
X1204921Y-9901D03*
X1177763Y-4100D03*
X1174803Y17157D03*
Y-9901D03*
X1198228Y17157D03*
X1201574Y-3700D03*
X1198228Y-9901D03*
X1220953Y-4100D03*
X1218307Y17157D03*
Y-9901D03*
X1214574Y-4100D03*
X1211614Y17157D03*
Y-9901D03*
X1171456Y71900D03*
X1168110Y65699D03*
X1164763Y71900D03*
X1161417Y65699D03*
X1184142Y71500D03*
X1181496Y65699D03*
X1208267Y71900D03*
X1204921Y65699D03*
X1177763Y71500D03*
X1174803Y65699D03*
X1201574Y71900D03*
X1198228Y65699D03*
X1220953Y71500D03*
X1218307Y65699D03*
X1214574Y71500D03*
X1214874Y87374D03*
X1211614Y65699D03*
X1168110Y54957D03*
X1161417D03*
X1181496D03*
X1204921D03*
X1174803D03*
X1177849Y49914D03*
X1198228Y54957D03*
X1218307D03*
X1211614D03*
X1245078Y34100D03*
X1241732Y27899D03*
X1238385Y34100D03*
X1235039Y27899D03*
X1245078Y-3700D03*
X1241732Y17157D03*
Y-9901D03*
X1238385Y-3700D03*
X1235039Y17157D03*
Y-9901D03*
X1248425Y17057D03*
X1265157Y9157D03*
X1276346Y-10250D03*
X1245078Y71900D03*
X1241732Y65699D03*
X1238385Y71900D03*
X1235039Y65699D03*
X1241732Y54957D03*
X1235039D03*
X1293600Y-17000D03*
X1293816Y-13533D03*
X1292692Y1008D03*
X1296908Y36900D03*
X1287700Y-16700D03*
X1303774Y-18842D03*
X1301219Y89141D03*
X1304500Y40066D03*
X1308400Y79600D03*
X913787Y273460D03*
X917467Y271509D03*
X971546Y252009D03*
X944507Y267609D03*
X947887Y269560D03*
X951267Y271509D03*
X947887Y273460D03*
X941127D03*
X927607D03*
X974926Y277360D03*
X971546Y279310D03*
X944507Y271509D03*
X924227D03*
X1005345Y252009D03*
X998586D03*
X1008725Y253960D03*
X1001965D03*
X995206D03*
X1005345Y255909D03*
X998586D03*
X1001965Y257860D03*
X995206D03*
X998586Y259809D03*
X995206Y261760D03*
X988446Y269560D03*
X985066Y271509D03*
X978306D03*
X988446Y273460D03*
X981686D03*
X985066Y275409D03*
X978306D03*
X988446Y277360D03*
X981686D03*
X985066Y279310D03*
X978306D03*
X1012105Y252009D03*
X1044256Y338341D03*
X1076435Y343595D03*
X840871Y391380D03*
X837272Y391420D03*
X947887Y320260D03*
X941127D03*
X944507Y326110D03*
Y330009D03*
X1065242Y239596D03*
Y243496D03*
X1068822Y245447D03*
X1067692Y254000D03*
X1071072Y255728D03*
X1087971Y257800D03*
X1091351Y259600D03*
X1094731Y261500D03*
X1098111Y263400D03*
X1084591Y255497D03*
X1081212Y257600D03*
X1092481Y247396D03*
X1089101Y245447D03*
X1085721Y247396D03*
X1089101Y249347D03*
X1092481Y251296D03*
X1095861Y249347D03*
Y253247D03*
X1072202Y247396D03*
X1129660Y210346D03*
X1133040Y212296D03*
X1134160Y272747D03*
Y276646D03*
X1151060Y270796D03*
Y255196D03*
Y251296D03*
X1154440Y280547D03*
X1157820Y282496D03*
X1144300D03*
X1140920Y280547D03*
X1136420Y261047D03*
X1133040Y262996D03*
X1147680Y280547D03*
X1157820Y274696D03*
X1154440Y268847D03*
X1140920Y272747D03*
X1114340Y280560D03*
X1154440Y276647D03*
X1101491Y265400D03*
X1119521Y282496D03*
X1116141Y268847D03*
X1112761Y262996D03*
X1116141Y261047D03*
X1119521Y278596D03*
X1144300Y223996D03*
X1154440Y225947D03*
X1147680Y245447D03*
X1127400Y280547D03*
Y276646D03*
X1134160Y280547D03*
X1144300Y266896D03*
X1154440Y257147D03*
X1157820Y251296D03*
X1154440Y249347D03*
X1157820Y247396D03*
X1147680Y249347D03*
Y276647D03*
X1140920D03*
X1161200Y276646D03*
X1154440Y272747D03*
X1147680Y253247D03*
Y257147D03*
X1109381Y264947D03*
X1161200Y280547D03*
X1130780Y282496D03*
X1119521Y266896D03*
Y262996D03*
X1122900Y261047D03*
X1119521Y259096D03*
X1157820Y243496D03*
X1147680Y272747D03*
X1151060Y278596D03*
X1133040Y239596D03*
X1147680Y261047D03*
X1144300Y259096D03*
X1151060Y262996D03*
X1154440Y261047D03*
X1144300Y274696D03*
X1137540Y313696D03*
X1140920Y315647D03*
X1134160Y319547D03*
X1130780Y317596D03*
Y333196D03*
X1134160Y331247D03*
X1140920Y288347D03*
Y284447D03*
X1147680D03*
Y288347D03*
X1151060Y286396D03*
X1144300Y290296D03*
X1147680Y292247D03*
X1154440D03*
Y288347D03*
Y284447D03*
X1157820Y286396D03*
X1137540D03*
X1119521Y301996D03*
Y298096D03*
Y294196D03*
Y290296D03*
X1127400Y284447D03*
Y300047D03*
X1130780Y294196D03*
X1127400Y296147D03*
Y292247D03*
X1130780Y298096D03*
Y305896D03*
X1137540Y290296D03*
X1134160Y296147D03*
Y288347D03*
Y284447D03*
X1130780Y286396D03*
X1134160Y311747D03*
Y315647D03*
X1161200Y288347D03*
Y292247D03*
X1140920Y323446D03*
X1147680Y307847D03*
X1144300Y298096D03*
X1137540Y301996D03*
X1140920Y303947D03*
X1137540Y305896D03*
X1140920Y296147D03*
X1137540Y294196D03*
X1119521Y309797D03*
Y313696D03*
Y317596D03*
X1127400Y311747D03*
X1144300Y317596D03*
X1137540Y321496D03*
X1134160Y327347D03*
X1137540Y325396D03*
X1130780Y348796D03*
X1208519Y218147D03*
X1167960Y222047D03*
X1164580Y220096D03*
X1161200Y222047D03*
X1171339Y216196D03*
X1181479Y218147D03*
X1191619Y208397D03*
X1161200Y268847D03*
X1164580Y255196D03*
X1171339Y270796D03*
X1164580Y282496D03*
X1167960Y280547D03*
X1171339Y282496D03*
X1164580Y274696D03*
X1167960Y257147D03*
X1161200Y272747D03*
X1191619Y223996D03*
X1178099D03*
X1167960Y233746D03*
X1178099Y270796D03*
Y278596D03*
X1181479Y249347D03*
Y237647D03*
Y241547D03*
X1184859Y223996D03*
X1201759Y237647D03*
X1198379Y227896D03*
X1205139Y231797D03*
X1201759Y245447D03*
X1194999Y237647D03*
X1198379Y251296D03*
X1181479Y264947D03*
X1184859Y255196D03*
X1191619Y270796D03*
X1198379Y262996D03*
X1194999Y276646D03*
X1198379Y282496D03*
Y270796D03*
X1178099Y266896D03*
X1171339Y243496D03*
X1174719Y241547D03*
X1178099Y239596D03*
X1171339Y278596D03*
X1178099Y262996D03*
X1174719Y276646D03*
X1167960D03*
X1181479Y253247D03*
X1178099Y251296D03*
X1171339Y262996D03*
X1174719Y264947D03*
X1208519Y229847D03*
X1167960Y284447D03*
X1283720Y223870D03*
X1315130Y164870D03*
X1315180Y169950D03*
X1326474Y216500D03*
X1338224Y209051D03*
X1310061Y165235D03*
X1345050Y272350D03*
X1300444Y267919D03*
X1309462Y240229D03*
X1288800Y233900D03*
X1338700Y284700D03*
X1345700Y285300D03*
X1348569Y208960D03*
X1367789Y209216D03*
X1384671Y214832D03*
X1113500Y323400D03*
X1120641Y339047D03*
X1113881Y342947D03*
X1120641D03*
X1110501Y344896D03*
X1109200Y325100D03*
X1161200Y362447D03*
X1157820Y364396D03*
X1154440Y370246D03*
X1157820Y376096D03*
X1151060Y372196D03*
X1147680Y378047D03*
X1144300Y379996D03*
Y387796D03*
X1161200Y358547D03*
Y366347D03*
X1157820Y368296D03*
Y372196D03*
X1154440Y374146D03*
X1151060Y376096D03*
X1147680Y381947D03*
X1144300Y383896D03*
X1161200Y354647D03*
X1107121Y350747D03*
X1113881Y346847D03*
X1147680Y370247D03*
Y374146D03*
X1120641Y346847D03*
X1161200Y389747D03*
X1154440Y397546D03*
Y393647D03*
X1151060Y387796D03*
X1157820Y395597D03*
X1154440Y389747D03*
X1157820Y391696D03*
X1154440Y385847D03*
X1161201Y401447D03*
X1157820Y383896D03*
X1156699Y401447D03*
X1201759Y331247D03*
Y335147D03*
Y342947D03*
X1198379Y344896D03*
Y333196D03*
X1201759Y339047D03*
X1205139Y340996D03*
X1181479Y331247D03*
X1198379Y321496D03*
X1194999Y323446D03*
X1174719D03*
X1181479D03*
X1174719Y327347D03*
X1178099Y333196D03*
X1171339Y329296D03*
X1167960Y335147D03*
X1171339Y340996D03*
X1178099Y321496D03*
Y325396D03*
Y329296D03*
X1174719Y331247D03*
X1171339Y333196D03*
Y337096D03*
X1184859Y344896D03*
X1191619D03*
Y340996D03*
Y337096D03*
X1188239Y331247D03*
X1194999Y327347D03*
X1188239D03*
X1184859Y340996D03*
X1188239Y342947D03*
X1194999Y339047D03*
X1191619Y333196D03*
Y329296D03*
Y325396D03*
X1188239Y323446D03*
X1201759Y346847D03*
X1164580Y368296D03*
X1167960Y350747D03*
Y354647D03*
X1164580Y360496D03*
Y364396D03*
X1167960Y346847D03*
X1171339Y352696D03*
X1184859Y348796D03*
X1188239Y346847D03*
X1178099Y387796D03*
X1171339D03*
Y391696D03*
X1167960Y393647D03*
X1164580Y395597D03*
X1178099Y379996D03*
Y383896D03*
X1174719Y385847D03*
X1171339Y383896D03*
X1174719Y389747D03*
X1171339Y395596D03*
X1164580Y391696D03*
Y387796D03*
X1178099Y376096D03*
X1181479Y381947D03*
X1188239Y354647D03*
Y358547D03*
Y362447D03*
X1181479D03*
Y366347D03*
X1184859Y372197D03*
Y376096D03*
Y379996D03*
X1188239Y350747D03*
X1191619Y356596D03*
X1184859Y360496D03*
X1181479Y358547D03*
X1184859Y364396D03*
Y368296D03*
X1188239Y374146D03*
X1181479Y378047D03*
X1174719Y370247D03*
X1181479D03*
X1171339Y364396D03*
X1178099Y360496D03*
Y356596D03*
X1184859Y352696D03*
X1161200Y393647D03*
Y385847D03*
X1167960D03*
Y381947D03*
Y378047D03*
X1174719D03*
Y374146D03*
Y366347D03*
X1178099Y368296D03*
X1174719Y362447D03*
Y358547D03*
X1181479Y354647D03*
Y350747D03*
X1161200Y381947D03*
X1164580Y383896D03*
X1171339Y379996D03*
X1167960Y374146D03*
X1171339Y376096D03*
X1178099Y372197D03*
X1167960Y405347D03*
X1194999Y378047D03*
X1201759Y374146D03*
X1194999D03*
X1198379Y364396D03*
Y360496D03*
Y356596D03*
X1174719Y405347D03*
Y401447D03*
X1178099Y395596D03*
X1184859Y399496D03*
X1181479Y393647D03*
X1188239Y389747D03*
Y385847D03*
X1191619Y379996D03*
X1198379Y383896D03*
X1167960Y401447D03*
X1198379Y376096D03*
Y372197D03*
X1194999Y370247D03*
Y362447D03*
X1201759Y358547D03*
X1198379Y352696D03*
X1171339Y403396D03*
X1178099Y399496D03*
X1181479Y397546D03*
X1184859Y395596D03*
Y391696D03*
Y387796D03*
X1191619Y383896D03*
X1194999Y381947D03*
X1198379Y379996D03*
X1164580Y376096D03*
X1194999Y350747D03*
X1198379Y348796D03*
X1249230Y402022D03*
X1157820Y309797D03*
X1181479Y315647D03*
X1161200Y311747D03*
X1198379Y294196D03*
X1191619Y313696D03*
Y309797D03*
X1188239Y307847D03*
Y303947D03*
Y300047D03*
X1184859Y298096D03*
X1194999Y311747D03*
X1191619Y305896D03*
X1184859D03*
X1191619Y301996D03*
X1188239Y296147D03*
X1181479D03*
X1184859Y313696D03*
X1188239Y315647D03*
X1331650Y317250D03*
X1335250Y344250D03*
X1319310Y300795D03*
X1302768Y296942D03*
X1331720Y334810D03*
X1326300Y341309D03*
X1316600Y305500D03*
X1302203Y314439D03*
X1342570Y368220D03*
X1364300Y338300D03*
X1370200Y338400D03*
Y343900D03*
X1358300Y344200D03*
X1358500Y338400D03*
X1363700Y321600D03*
X1367200D03*
X1359200Y322200D03*
X1353672Y299605D03*
X1347892Y299741D03*
X1370300Y350200D03*
X1364100D03*
X1358400Y350100D03*
X1374300Y377885D03*
Y381485D03*
X1378200Y346900D03*
X1385100Y447500D03*
X1389900Y447400D03*
X1395100Y432500D03*
Y447500D03*
Y427500D03*
X1529734Y319714D03*
X1538450Y314300D03*
X1585479Y316610D03*
X1581834Y318591D03*
X1589476Y322953D03*
X1582800Y312100D03*
X1548273Y313227D03*
X1590212Y315425D03*
X1551250Y320303D03*
X1688207Y168972D03*
X1691207Y139891D03*
X1709000Y127200D03*
X1681586Y141438D03*
X1693586Y142438D03*
X1757689Y123850D03*
X1637281Y260922D03*
Y254322D03*
X1637269Y264421D03*
X1638086Y319664D03*
X1638063Y326504D03*
X1639040Y316343D03*
X1638991Y352037D03*
X1676800Y483800D03*
X1681500Y482000D03*
X1705767Y482434D03*
X1701617Y482706D03*
X1875100Y51300D03*
X1878000Y73950D03*
X1848208Y49427D03*
X1898102Y107325D03*
X1892274Y235080D03*
X1918352Y89300D03*
X1923300Y94300D03*
X1926890Y73106D03*
X1920300Y68300D03*
X1917600Y66000D03*
X1948472Y80362D03*
X1946500Y104974D03*
X1937900Y153600D03*
X1934256Y99459D03*
X1934544Y127957D03*
X1952726Y102950D03*
X1932998Y119438D03*
X1923329Y99475D03*
X1923837Y118800D03*
X1937728Y99441D03*
X1957334Y201269D03*
X1939300Y204300D03*
X1940647Y161600D03*
X1943500Y209500D03*
X1938400Y178200D03*
X1939200Y194300D03*
X1950981Y191218D03*
X1963300Y191000D03*
X1967580Y104721D03*
G54D49*
X1646756Y595039D03*
X1694000D03*
G54D48*
X1646756Y565118D03*
Y580079D03*
Y610000D03*
X1694000Y565118D03*
Y580079D03*
Y610000D03*
G54D25*
X1713000Y185000D03*
X1600552Y261281D03*
X1598028Y256422D03*
X1591865Y237407D03*
X1566858Y175192D03*
X1561925Y192675D03*
X1573121Y120649D03*
X1502000Y147500D03*
X1490057Y85165D03*
X1490821Y73750D03*
X629359Y469583D03*
X641107Y471989D03*
X628589Y463649D03*
X85609Y385234D03*
X5120Y276058D03*
X2269Y273532D03*
X162800Y195600D03*
X1644856Y604930D03*
X1640921Y605334D03*
X1836396Y481349D03*
X251213Y646784D03*
Y652784D03*
X261125Y646784D03*
Y652784D03*
X389473Y646508D03*
Y652508D03*
X379561Y646508D03*
Y652508D03*
X448593Y652514D03*
Y646514D03*
X438681D03*
Y652514D03*
X567029Y652238D03*
Y646238D03*
X576941D03*
Y652238D03*
X951795Y652234D03*
Y646234D03*
X941883D03*
Y652234D03*
X1196198Y652206D03*
Y646206D03*
X1206110D03*
Y652206D03*
X1265293Y652264D03*
Y646264D03*
X1255381D03*
Y652264D03*
X1509696Y652236D03*
Y646236D03*
X1519608D03*
Y652236D03*
X58000Y206500D03*
X56900Y197800D03*
X50500Y205696D03*
X61256Y186000D03*
X122044Y162340D03*
X98149Y399769D03*
X102456Y393756D03*
X114084Y399937D03*
X267859Y271509D03*
X264179Y273460D03*
X298279Y324160D03*
X710800Y7100D03*
X705250Y8600D03*
X1709184Y88811D03*
X1687741Y466988D03*
X1759093Y9310D03*
X1761872Y-7220D03*
X1734875Y9238D03*
X1758000Y250000D03*
X1789356Y38286D03*
X1828390Y165600D03*
X1832000Y165800D03*
X1852654Y164624D03*
X1847654D03*
X1919230Y483430D03*
X1919000Y487210D03*
X773419Y270414D03*
X753098Y338316D03*
X744698Y332816D03*
X757500Y374000D03*
X814849Y205001D03*
X1032102Y278904D03*
X1089702D03*
X1714189Y159550D03*
X1696907Y99077D03*
X1680139Y99073D03*
X1708250Y164950D03*
X1736689Y159550D03*
X1732189D03*
X1718689D03*
X1723189D03*
X1727689D03*
X1741189D03*
X1745689D03*
X1750189D03*
X1758650Y158650D03*
X1765015Y119100D03*
X1776828Y155211D03*
X1768886Y156173D03*
X1788000Y129000D03*
X1787373Y120188D03*
X1847797Y26331D03*
X1847564Y21636D03*
X1850600Y41348D03*
X1908400Y101010D03*
X1949389Y152083D03*
X1944550Y176450D03*
X1950981Y168064D03*
G54D35*
X-10850Y30800D03*
X-3560Y34620D03*
X1379025Y-9799D03*
X761580Y220160D03*
G54D33*
X82779Y202300D03*
X72936D03*
X1912406Y518328D03*
X1904532D03*
G54D32*
X60512Y467244D03*
X50512D03*
X20512D03*
X1884100Y493000D03*
X1894100D03*
X1891086Y592105D03*
Y612105D03*
Y602105D03*
X1904100Y493000D03*
G54D60*
X1713503Y-15000D03*
X1779504D03*
G54D45*
X-10236Y116969D03*
X-4725D03*
X23228Y124843D03*
X17716D03*
X-10236Y132717D03*
X-4725D03*
X6299D03*
X11811D03*
X17716Y140591D03*
X23228D03*
X-10236Y373110D03*
X-4725D03*
X23228Y380984D03*
X17716D03*
X-10236Y388858D03*
X-4725D03*
X6299D03*
X11811D03*
X17716Y396732D03*
X23228D03*
G54D28*
X1392264Y23976D03*
G54D27*
X1610591Y165885D03*
X1616890Y162735D03*
X1608731Y180819D03*
X1616891Y165885D03*
X1613741D03*
X1610591Y162735D03*
X1600490Y167459D03*
X1607441Y162735D03*
X1613741D03*
X1601142Y172185D03*
X1594565Y148720D03*
X1645237Y109191D03*
X1610591Y115491D03*
Y128089D03*
X1616890Y159585D03*
X1604292Y134388D03*
X1607441Y137538D03*
X1648387Y109191D03*
Y112341D03*
X1629489D03*
X1642084Y115494D03*
X1629487Y109280D03*
X1629400Y106131D03*
X1607239Y131358D03*
X1604292Y137538D03*
X1607441Y121790D03*
Y124939D03*
X1626300Y112300D03*
X1626339Y109191D03*
X1613741Y128089D03*
X1626339Y115491D03*
X1613741Y156436D03*
Y150137D03*
X1607441Y106042D03*
X1645237Y112341D03*
X1610591Y146987D03*
X1607441Y143837D03*
X1608000Y99400D03*
X1613741Y134389D03*
X1613690Y124990D03*
X1613741Y140688D03*
X1610591Y134389D03*
X1595390Y151778D03*
X1600900Y131900D03*
X1607441Y153286D03*
X1613741Y137538D03*
Y159585D03*
X1610591Y150137D03*
Y124939D03*
Y137538D03*
Y140688D03*
X1607441Y134389D03*
X1645237Y115491D03*
X1616900Y143880D03*
X1616890Y118641D03*
X1613741Y106042D03*
X1607441Y156436D03*
X1610591Y153286D03*
X1604169Y156407D03*
X1610591Y156436D03*
X1600490Y158010D03*
X1596427Y157975D03*
X1600148Y151711D03*
X1600182Y148562D03*
X1607401Y146947D03*
X1604292Y150137D03*
X1610591Y159585D03*
X1600148Y142262D03*
X1610645Y143783D03*
X1613741Y118640D03*
X1616891Y128089D03*
X1607441Y112341D03*
X1610591Y118640D03*
X1607441Y115491D03*
X1610591Y112341D03*
X1648387Y115491D03*
X1613741Y153286D03*
X1616848Y115449D03*
X1616890Y112341D03*
X1632638Y115491D03*
Y112341D03*
X1632615Y109215D03*
X1629489Y115491D03*
X1610591Y121790D03*
X1613741D03*
X1632574Y106107D03*
X1613741Y146987D03*
X1616891Y150137D03*
X1607442Y159585D03*
X1638938Y109192D03*
X1620040Y106042D03*
X1607441Y118640D03*
X1613741Y115491D03*
X1602717Y102240D03*
X1616891Y124939D03*
Y134389D03*
X1616893Y140782D03*
X1616891Y146987D03*
X1616900Y153200D03*
X1638250Y125750D03*
X1645378Y128378D03*
X1638938Y153286D03*
X1629489Y131239D03*
Y143837D03*
Y137538D03*
X1635788Y131239D03*
Y143837D03*
Y137538D03*
X1629489Y150136D03*
X1638937Y137538D03*
Y143837D03*
Y131239D03*
X1648430Y150163D03*
X1648387Y159585D03*
X1651536D03*
X1629489Y153286D03*
X1651536Y156435D03*
X1638938Y159585D03*
X1629489D03*
X1635788D03*
X1642087D03*
X1654638Y159685D03*
X1623200Y153100D03*
X1654686Y150138D03*
Y153288D03*
X1626364Y121765D03*
X1626313Y153312D03*
X1642087Y153286D03*
X1632638D03*
X1632639Y124940D03*
X1648393Y153280D03*
X1626339Y124940D03*
X1645237Y159585D03*
X1626339D03*
X1623189D03*
X1654686Y156436D03*
X1648386Y156435D03*
X1627998Y172854D03*
X1645237Y165884D03*
X1626339Y162735D03*
X1623276Y165798D03*
X1629489Y162735D03*
X1624966Y172936D03*
X1629489Y165884D03*
X1645151Y162649D03*
X1642101Y162749D03*
X1651536Y165884D03*
X1654685Y162735D03*
X1638938D03*
X1635788Y165885D03*
X1642088D03*
X1638938Y165884D03*
X1651536Y162735D03*
X1648320Y172690D03*
X1648326Y162674D03*
X1648386Y165885D03*
X1623250Y162611D03*
X1626339Y165884D03*
X1635788Y162735D03*
X1643662Y172609D03*
X1667284Y150136D03*
X1657835D03*
X1660985Y159585D03*
Y156435D03*
Y150137D03*
X1657836Y153288D03*
X1664135Y153286D03*
X1664134Y156436D03*
X1667348Y156500D03*
X1657835Y159585D03*
X1668213Y172608D03*
X1657835Y165884D03*
Y162735D03*
X1665063Y172608D03*
X1660985Y165885D03*
Y162735D03*
X1651536Y121790D03*
X1654678Y137530D03*
X1654686Y109191D03*
X1654673Y118628D03*
X1654685Y112341D03*
Y140687D03*
X1654686Y124940D03*
Y134389D03*
X1654685Y131239D03*
X1651536Y128089D03*
X1651532Y137534D03*
X1674685Y134217D03*
X1678127Y117293D03*
X1673883Y124308D03*
X1657835Y134389D03*
X1664134Y140688D03*
X1667284Y128089D03*
Y121790D03*
X1657835Y124940D03*
X1667284Y137537D03*
X1671000Y103000D03*
X1657835Y115491D03*
Y109191D03*
X1660985D03*
X1670434Y115491D03*
X1667284D03*
X1660985D03*
X1664135Y118640D03*
X1657835Y112341D03*
X1660985D03*
X1667238Y112387D03*
X1660986Y137538D03*
X1664136D03*
X1664135Y121790D03*
X1660985Y128089D03*
Y121790D03*
X1657835D03*
X1667284Y131239D03*
X1664135Y128089D03*
X1660985Y131239D03*
Y124939D03*
X1677386Y132788D03*
X1676886Y120038D03*
Y123188D03*
X1657836Y137538D03*
Y140688D03*
X1660985D03*
X1714114Y148950D03*
X1664135Y112341D03*
Y115491D03*
X1660985Y118640D03*
X1657835D03*
X1742214Y98550D03*
X1720164Y97550D03*
X1723314Y98550D03*
X1742212Y117451D03*
X1717014Y108000D03*
Y139500D03*
X1739064Y114300D03*
X1742214Y111150D03*
X1745364Y120600D03*
X1742214Y126900D03*
X1751800Y141700D03*
X1720164Y126800D03*
Y133200D03*
Y120600D03*
X1723314Y117450D03*
Y111150D03*
X1720164D03*
X1731903Y133712D03*
X1745364Y145800D03*
X1752889Y146250D03*
X1754189Y124250D03*
X1752389Y132250D03*
X1752189Y136750D03*
X1755089Y150750D03*
X1745364Y114300D03*
X1742214Y101700D03*
X1739064Y108000D03*
X1735914Y139500D03*
X1723314Y142650D03*
X1735989Y133250D03*
X1739064Y145800D03*
X1728789Y136250D03*
X1723264Y145850D03*
X1735989Y149050D03*
X1726539Y139450D03*
X1734989Y142750D03*
X1720164Y139500D03*
X1739064Y142650D03*
X1720164Y145800D03*
X1742214D03*
X1726464D03*
X1739064Y139500D03*
X1723314D03*
X1739064Y136350D03*
Y126900D03*
X1723314Y130050D03*
Y126900D03*
X1726464Y133200D03*
Y111150D03*
X1739064Y120600D03*
X1735914Y104850D03*
X1723314D03*
X1720164Y108000D03*
X1735914D03*
X1723314D03*
X1739064Y123750D03*
X1726464Y120600D03*
X1742214D03*
X1723314Y120601D03*
X1735912Y123750D03*
X1720164Y104850D03*
X1739064Y117450D03*
X1735914D03*
X1731789Y139450D03*
X1717014Y142650D03*
X1739064Y130050D03*
X1746189Y153250D03*
X1723314Y133200D03*
X1742214Y142650D03*
X1746189Y134777D03*
X1742214Y130050D03*
X1745500Y104500D03*
G54D59*
X1627642Y-14488D03*
X1647327Y-315D03*
X1667012Y-14488D03*
G54D52*
X1892720Y525415D03*
X1900595D03*
X1894689Y518328D03*
X1908469Y525415D03*
X1916343D03*
X1924217D03*
X1922248Y518328D03*
G54D26*
X1705666Y198055D03*
X1667140Y182300D03*
X1663400Y179475D03*
X1660800Y181900D03*
X1708350Y175050D03*
X1714528Y190189D03*
X1622000Y279495D03*
X1617498Y273433D03*
X1627024Y253387D03*
X1600810Y266006D03*
X1608489Y252095D03*
X1595291Y166423D03*
X1602185Y180709D03*
X1615362Y213507D03*
X1603300Y185100D03*
X1651000Y178628D03*
X1604401Y213500D03*
X1605250Y197250D03*
X1620036Y196186D03*
X1618500Y181680D03*
X1643887Y181841D03*
X1613741Y112341D03*
X1648000Y100597D03*
X1600000Y104243D03*
X1598449Y120760D03*
X1598300Y116477D03*
X1593241Y134295D03*
X1621100Y69600D03*
X1628788Y97800D03*
X1632000Y73500D03*
X1632020Y97871D03*
X1602000Y84500D03*
X1596900D03*
X1597987Y79500D03*
X1597867Y93900D03*
X1640900Y66900D03*
X1632006Y94500D03*
X1596050Y75400D03*
X1599000Y61500D03*
X1637700Y67400D03*
X1635900Y83000D03*
X1602840Y37382D03*
X1603138Y65890D03*
X1595943Y71522D03*
X1610450Y37300D03*
X1605184Y61044D03*
X1625451Y84288D03*
X1632000Y83000D03*
X1606730Y84230D03*
X1608500Y72688D03*
X1595335Y98135D03*
X1597800Y24300D03*
X1620050Y35550D03*
X1537500Y292800D03*
X1532850Y303950D03*
X1550800Y296200D03*
X1554800Y290600D03*
X1552900Y281700D03*
X1591174Y225017D03*
X1544000Y266500D03*
X1541000Y269500D03*
X1547000Y269400D03*
X1553500Y165400D03*
X1557979Y188844D03*
X1571501Y180031D03*
X1552051Y172053D03*
X1557634Y175948D03*
X1583600Y207495D03*
X1590569Y152464D03*
X1576506Y143416D03*
X1591950Y158250D03*
X1582500Y109900D03*
X1553500Y157000D03*
X1588176Y157600D03*
X1578000Y113000D03*
X1558189Y107067D03*
X1554800Y129100D03*
X1592715Y70817D03*
X1583621Y87213D03*
X1582923Y37216D03*
X1592200Y37700D03*
X1573473Y37216D03*
X1511900Y287500D03*
X1474717Y110370D03*
X1524284Y112773D03*
X1490178Y112315D03*
X1476761Y152725D03*
X1473354Y153246D03*
X1523719Y149488D03*
X1488350Y149450D03*
X1470862Y38209D03*
X1511700Y84600D03*
X1470414Y34830D03*
X1479863D03*
X1497711Y34427D03*
X1489311Y34830D03*
X1452648Y103788D03*
X1469747Y148276D03*
X1413721Y36749D03*
X1442067Y34830D03*
X1423170Y36635D03*
X1432619Y34830D03*
X1451516D03*
X1460965D03*
X1350100Y442500D03*
X1371500Y101000D03*
X1388100Y108500D03*
X1381359Y108496D03*
X1384600Y108500D03*
X1394253Y116989D03*
X1357700Y104950D03*
X1352200D03*
Y108400D03*
X1357700D03*
X1372300Y86400D03*
X1360700Y86550D03*
X1351488Y74000D03*
X1363500Y77400D03*
X1358500Y74500D03*
X1365855Y46972D03*
X1375500Y76000D03*
X1364700Y86550D03*
X1366100Y82500D03*
X1370100D03*
X1363040Y66660D03*
X1362900Y60500D03*
X1380500Y50500D03*
Y54500D03*
X1363170Y54280D03*
X1402700Y51100D03*
X1351190Y54710D03*
X1357000Y60500D03*
X1356760Y66660D03*
X1356950Y54370D03*
X1388627Y35032D03*
X1360400Y10600D03*
X1345100Y437500D03*
Y442500D03*
X1340100D03*
Y447500D03*
Y452500D03*
Y457500D03*
X1325100Y442500D03*
X1315100D03*
X1320100D03*
X1310100D03*
X1305100D03*
X1330100D03*
X1335100D03*
Y447500D03*
Y452500D03*
Y457500D03*
X1330100Y427500D03*
Y432500D03*
X1315100D03*
Y427500D03*
X1310100Y432500D03*
Y427500D03*
X1305181Y427834D03*
X1325100Y432500D03*
Y427500D03*
X1320100Y432500D03*
Y427500D03*
X1305100Y432500D03*
X1301000Y460900D03*
X1300100Y442500D03*
X1306900Y131744D03*
X1252000Y145300D03*
X1237704Y148423D03*
X749640Y431797D03*
X728940Y457806D03*
X690600Y437500D03*
Y432500D03*
X685600D03*
X691240Y390039D03*
X686619Y392600D03*
X675600Y144900D03*
X698300Y85300D03*
X701500Y85500D03*
X716894Y84047D03*
X720572Y88700D03*
X713830Y82730D03*
X697500Y45000D03*
Y48500D03*
X678020Y69870D03*
X692000Y48500D03*
Y45000D03*
X623660Y466746D03*
X648690Y125590D03*
X654558Y115101D03*
X651920Y125750D03*
X630000Y126572D03*
X584076Y443828D03*
X559212Y393647D03*
X605300Y124600D03*
X555313Y104314D03*
X548620D03*
X531738D03*
X525134D03*
X518467D03*
X495077D03*
X488634D03*
X512024D03*
X240596Y104284D03*
X277407D03*
X257478D03*
X270864D03*
X264171D03*
X234053D03*
X72603Y474072D03*
X62600Y375100D03*
X61914Y368731D03*
X60400Y355750D03*
X77300Y390600D03*
X70900Y358300D03*
X82100Y368300D03*
X70600Y368400D03*
X82037Y358542D03*
X76300Y358400D03*
X76500Y368300D03*
X88600Y302997D03*
X93400Y296000D03*
X93500Y285000D03*
X84000Y316083D03*
X76800Y303400D03*
X76900Y292600D03*
X76800Y298000D03*
X71500D03*
X93500Y289000D03*
X70700Y330349D03*
X84000Y272500D03*
X79300Y272300D03*
X83300Y267400D03*
X73500Y191500D03*
X77650Y178150D03*
X70980Y97166D03*
X76106Y89337D03*
X81861Y93392D03*
X52500Y67200D03*
X51090Y8080D03*
X47800Y487600D03*
X21000Y495800D03*
X26780Y488910D03*
X13700Y498500D03*
X13600Y504300D03*
X13300Y509600D03*
X24591Y479139D03*
X10443Y490649D03*
X11500Y43400D03*
X11539Y39927D03*
X30600Y-12000D03*
X45700Y40D03*
X40994Y-7148D03*
X33628Y131D03*
X45429Y-4669D03*
X33370Y5185D03*
X45670D03*
X39530Y5205D03*
X1469000Y345850D03*
X-17084Y467626D03*
X-17200Y510800D03*
X-17300Y530800D03*
X-17397Y564242D03*
X-1190Y53240D03*
X-1000Y81500D03*
X1382Y68100D03*
X-1470Y63910D03*
X37037Y138425D03*
X7995Y285385D03*
X-6104Y461190D03*
X-9600Y526100D03*
X-6712Y515731D03*
X-10200Y558200D03*
X0Y566800D03*
X46560Y581000D03*
Y577500D03*
X-3100Y533991D03*
X-10947Y544117D03*
X-4300Y558400D03*
X-4100Y554400D03*
X-9287Y531604D03*
X-9291Y535201D03*
X46500Y595190D03*
X43210Y595180D03*
X284759Y199360D03*
X291519D03*
X301648Y194841D03*
X298279Y199360D03*
X334328Y199108D03*
X625430Y490100D03*
X632113Y496892D03*
X649600Y492400D03*
X660500Y492000D03*
X664610Y512810D03*
X653800Y496600D03*
X715550Y158880D03*
X715505Y155076D03*
X705550Y158880D03*
X710550D03*
X720700Y154750D03*
X725650Y155000D03*
X675600Y150000D03*
X704500Y512850D03*
X680000Y511800D03*
X686200Y511700D03*
X700500Y512850D03*
X726040Y506080D03*
X730600Y154984D03*
X740650Y158800D03*
X740718Y150957D03*
X746000Y150500D03*
X738648Y492050D03*
X798337Y181216D03*
X799620Y186547D03*
X804470Y186814D03*
X934367Y199360D03*
X951256Y194841D03*
X967036Y193507D03*
X947887Y199360D03*
X941127D03*
X983936Y199108D03*
X1071072Y199583D03*
X1091351Y199841D03*
X1084591Y198931D03*
X1111631Y198327D03*
X1104871Y198050D03*
X1220167Y194407D03*
X1241712Y187710D03*
X1267800Y161800D03*
X1271400Y161900D03*
X1263300Y169450D03*
X1277978Y491571D03*
X1262843Y497553D03*
X1335100Y155000D03*
X1330100Y150000D03*
X1340100D03*
Y155000D03*
X1345100Y150000D03*
X1335100D03*
X1330100Y155000D03*
X1345100D03*
X1344761Y498282D03*
X1340986Y511187D03*
X1341050Y498275D03*
X1355100Y155000D03*
Y150000D03*
X1360100Y155000D03*
Y150000D03*
X1350100Y155000D03*
Y150000D03*
X1385100Y155000D03*
X1375100D03*
X1365100D03*
X1380100D03*
Y150000D03*
X1385100D03*
X1365100D03*
X1375100D03*
X1370100Y155000D03*
Y150000D03*
X1396933Y215763D03*
X1399852Y252353D03*
X1407274Y245652D03*
X1396470Y330014D03*
X1392400Y330800D03*
X1400400Y335400D03*
X1392144Y364617D03*
X1389450Y372250D03*
X1392805Y360466D03*
X1394760Y394720D03*
X1365100Y452500D03*
X1380100D03*
X1362560Y463478D03*
X1377492Y516892D03*
X1369757Y517465D03*
X1395581Y525357D03*
X1403027Y520231D03*
X1355800Y508500D03*
X1395242Y520301D03*
X1396035Y514863D03*
X1400830Y564090D03*
X1400288Y570099D03*
X1404420Y576330D03*
X1379053Y581864D03*
X1375600Y589700D03*
X1387050Y615350D03*
X1449847Y202322D03*
X1442251Y180818D03*
X1418300Y199900D03*
X1440150Y175550D03*
X1440124Y166180D03*
X1458908Y187699D03*
X1447999Y205645D03*
X1464200Y231400D03*
X1430365Y262624D03*
X1448500Y257700D03*
X1426905Y267045D03*
X1433057Y257388D03*
X1467040Y260357D03*
X1466006Y265300D03*
X1461400Y264700D03*
X1426658Y274252D03*
X1461348Y244350D03*
X1440910Y316693D03*
X1458400Y318500D03*
X1408250Y333000D03*
X1463610Y321329D03*
X1443500Y327900D03*
X1462776Y318200D03*
X1466970Y320235D03*
X1412220Y388360D03*
X1459033Y395334D03*
X1446700Y387900D03*
X1413735Y391302D03*
X1413400Y361300D03*
X1435479Y423107D03*
X1448800Y416500D03*
X1439000Y423000D03*
X1414107Y447267D03*
X1410850Y564210D03*
X1410340Y570370D03*
X1468101Y573963D03*
X1413600Y531300D03*
X1419600Y531500D03*
X1410950Y589670D03*
X1426870Y530800D03*
X1499800Y199300D03*
X1523400Y217900D03*
X1483523Y181100D03*
X1517328Y186208D03*
X1527500Y167726D03*
X1511100Y186275D03*
X1492597Y172636D03*
X1488900Y172576D03*
X1477388Y172988D03*
X1497237Y217281D03*
X1512700Y205100D03*
X1488300Y161700D03*
X1512525Y208944D03*
X1492136Y199125D03*
X1512500Y199837D03*
X1510638Y166240D03*
X1516872Y208863D03*
X1515060Y192443D03*
X1507524Y218600D03*
X1479500Y238500D03*
X1491700Y241661D03*
X1491407Y258353D03*
X1528460Y244371D03*
X1523470Y242580D03*
X1530200Y257200D03*
X1525650Y248700D03*
X1470950Y229669D03*
X1526150Y234300D03*
X1486926Y247834D03*
X1496030Y267665D03*
X1516549Y234278D03*
X1516613Y240656D03*
X1486574Y267127D03*
X1492753Y273724D03*
X1492697Y267303D03*
X1474520Y251740D03*
X1482400Y248000D03*
X1487500Y244500D03*
X1505946Y254432D03*
X1519300Y245196D03*
X1469829Y266909D03*
X1523580Y237960D03*
X1520413Y239498D03*
X1489546Y279902D03*
X1472500Y341074D03*
X1521817Y330937D03*
X1526000Y341000D03*
X1530033Y340799D03*
X1487426Y330100D03*
X1517600Y320940D03*
X1473231Y320250D03*
X1499723Y300106D03*
X1497179Y306372D03*
X1508455Y313041D03*
X1523935Y318901D03*
X1493400Y300800D03*
X1484100Y330115D03*
X1482550Y333600D03*
X1487000Y333300D03*
X1499987Y288487D03*
X1496628Y288440D03*
X1497509Y303120D03*
X1518060Y317520D03*
X1493268Y293943D03*
X1495300Y297300D03*
X1493290Y287984D03*
X1478524Y318900D03*
X1493500Y304400D03*
X1514100Y321792D03*
X1472680Y380630D03*
X1482000Y399035D03*
X1503125Y377514D03*
X1491425D03*
X1526525D03*
X1514825D03*
X1510925Y404554D03*
X1487525D03*
X1491425D03*
X1503125D03*
X1482000Y406909D03*
X1524575Y401174D03*
X1514825Y397794D03*
X1508975Y394414D03*
X1503125Y397794D03*
X1491425D03*
X1497275Y394414D03*
Y387654D03*
X1491425Y384274D03*
X1497275Y380894D03*
X1503125Y391034D03*
Y384274D03*
X1508975Y380894D03*
Y387654D03*
X1514825Y391034D03*
X1520675Y380894D03*
Y387654D03*
X1514825Y384274D03*
X1526525Y391034D03*
Y384274D03*
X1491425Y391034D03*
X1483950Y401650D03*
X1508975Y401174D03*
X1497275D03*
X1519626Y365817D03*
X1473255Y376254D03*
X1482000Y387224D03*
Y383287D03*
X1478500Y365500D03*
X1474500D03*
X1507025Y391034D03*
X1493375Y380894D03*
X1505075D03*
X1501175Y394414D03*
X1499225Y391034D03*
Y384274D03*
X1487525Y397794D03*
X1493375Y394414D03*
X1489475D03*
X1487525Y384274D03*
X1489475Y387654D03*
X1499225Y377514D03*
X1495325Y391034D03*
X1493375Y387654D03*
X1505075Y394414D03*
X1501175Y387654D03*
X1495325Y377514D03*
X1524575Y394414D03*
X1530425Y384274D03*
X1487525Y377514D03*
X1472940Y384030D03*
X1473255Y372654D03*
X1505075Y387654D03*
Y401174D03*
X1501175D03*
X1507025Y404554D03*
X1522625Y391034D03*
X1495325Y397794D03*
X1499225D03*
Y404554D03*
X1493375Y401174D03*
X1489475D03*
X1507025Y384274D03*
X1501175Y380894D03*
X1528475D03*
X1522625Y397794D03*
X1528475Y401174D03*
Y387654D03*
X1529829Y362655D03*
X1516775Y380894D03*
X1526659Y397500D03*
X1528475Y394414D03*
X1524575Y380894D03*
X1522476Y361907D03*
X1507025Y377514D03*
X1520675Y394414D03*
X1522625Y377514D03*
X1530425D03*
X1518725Y397794D03*
Y391034D03*
Y384274D03*
X1510925Y397794D03*
X1512875Y401174D03*
Y394414D03*
X1530425Y391034D03*
X1514925Y358844D03*
X1495325Y384274D03*
X1483868Y390233D03*
X1520675Y401174D03*
X1516775D03*
Y394414D03*
X1510925Y377514D03*
X1512875Y380894D03*
X1515328Y363389D03*
X1518725Y377514D03*
X1522625Y384274D03*
X1510925Y391034D03*
X1516775Y387654D03*
X1512875D03*
X1510925Y384274D03*
X1530425Y397794D03*
X1489475Y380894D03*
X1524575Y387654D03*
X1503878Y364717D03*
X1501175Y407934D03*
X1485250Y408017D03*
X1505075Y407934D03*
X1497273Y407610D03*
X1489475Y407934D03*
X1493375D03*
X1470353Y592128D03*
X1518900Y619800D03*
X1531565Y176645D03*
X1535000Y207200D03*
X1545023Y161675D03*
X1563440Y250955D03*
X1582699Y252646D03*
X1537972Y236000D03*
X1531935Y224160D03*
X1568120Y251710D03*
X1571876Y255800D03*
X1586400Y392900D03*
X1591912Y391052D03*
X1567475Y380894D03*
Y387654D03*
X1582420Y377830D03*
X1582350Y374567D03*
X1582124Y381164D03*
X1573000Y391161D03*
X1571366Y401154D03*
X1582000Y396250D03*
X1567475Y394414D03*
X1582500Y369600D03*
X1573521Y365500D03*
X1538225Y377514D03*
X1549925D03*
X1546025Y404554D03*
X1534325D03*
X1538225D03*
X1542125D03*
X1555775Y380894D03*
Y387654D03*
X1549925Y384274D03*
Y391034D03*
X1561625Y384274D03*
Y391034D03*
Y377514D03*
X1555775Y401174D03*
X1561625Y397794D03*
X1549925D03*
X1555775Y394414D03*
X1544075D03*
X1538225Y397794D03*
Y391034D03*
X1544075Y387654D03*
Y380894D03*
X1538225Y384274D03*
X1532375Y394414D03*
Y387654D03*
Y380894D03*
X1553825Y377514D03*
X1533589Y366361D03*
X1553825Y391034D03*
X1546025D03*
X1581822Y365770D03*
X1569584Y378002D03*
X1563575Y394414D03*
X1557725Y397794D03*
X1571375Y387654D03*
X1569425Y397794D03*
X1563575Y401174D03*
X1569425Y391034D03*
X1553825Y397794D03*
X1542300Y376717D03*
X1546025Y397794D03*
X1551875Y394414D03*
Y387654D03*
X1549950Y404490D03*
X1565525Y384274D03*
X1557725Y377514D03*
X1559675Y401174D03*
X1542125Y397794D03*
X1565525Y391034D03*
X1547975Y394414D03*
X1540175Y387654D03*
Y380894D03*
Y401174D03*
X1547975Y387654D03*
X1536275Y401174D03*
Y387654D03*
X1534325Y384274D03*
X1536275Y380894D03*
X1534325Y397794D03*
X1540175Y394414D03*
X1534325Y391034D03*
X1582600Y389300D03*
X1559675Y387654D03*
Y394414D03*
X1551875Y380894D03*
X1557725Y391034D03*
X1536275Y394414D03*
X1557725Y404554D03*
X1563575Y387654D03*
X1567475Y401174D03*
X1551875D03*
X1565525Y397794D03*
Y377514D03*
X1559675Y380894D03*
X1571375Y394414D03*
X1532375Y401174D03*
X1563575Y380894D03*
X1534325Y377514D03*
X1551875Y407934D03*
X1544150Y409900D03*
X1536275Y407934D03*
X1555775D03*
X1545000Y591100D03*
X1592934Y592396D03*
X1565389Y585721D03*
X1535565Y591658D03*
X1563827Y621376D03*
X1554800Y620910D03*
X1572950Y593950D03*
X1608764Y322440D03*
X1608850Y343835D03*
X1607443Y398649D03*
X1613474Y391105D03*
X1620447Y373926D03*
X1619889Y352841D03*
X1603307Y393224D03*
X1609271Y348166D03*
X1613452Y387098D03*
X1603650Y415469D03*
X1639750Y445477D03*
X1630150Y427663D03*
X1639774Y439486D03*
X1640625Y429460D03*
X1646700Y480300D03*
X1626518Y528029D03*
X1627622Y524928D03*
X1631975Y527700D03*
X1644800Y532800D03*
X1636848Y533794D03*
X1638674Y556178D03*
X1654100Y615790D03*
X1653970Y607340D03*
X1615862Y605507D03*
X1594110Y611510D03*
X1699900Y512300D03*
X1667277Y535221D03*
X1698600Y584800D03*
X1709183Y588700D03*
X1722000Y513000D03*
X1756417Y563840D03*
X1728245Y585244D03*
X1767455Y571695D03*
X1730814Y568814D03*
X1749000Y552863D03*
X1718000Y587723D03*
X1753807Y548183D03*
X1757478Y548192D03*
X1764300Y570900D03*
X1750739Y618718D03*
X1724092Y618700D03*
X1772158Y610960D03*
X1746052Y614796D03*
X1750399Y603201D03*
X1739714Y604967D03*
X1716950Y603450D03*
X1804000Y498176D03*
X1810350Y525650D03*
X1809700Y506875D03*
X1820400Y501100D03*
X1837200Y525700D03*
X1813500Y526500D03*
X1816584Y530542D03*
X1825900Y523500D03*
X1795200Y525700D03*
X1781510Y546362D03*
X1786500Y562200D03*
X1828700Y540252D03*
X1786900Y552500D03*
X1806200Y582900D03*
X1828700Y569474D03*
X1828875Y563674D03*
X1828824Y557663D03*
X1807958Y565690D03*
X1829051Y591299D03*
X1809600Y582800D03*
X1811100Y586800D03*
X1816458Y587480D03*
X1793100Y578500D03*
X1780394Y561076D03*
X1837534Y579322D03*
X1792805Y574675D03*
X1832500Y539500D03*
X1829000Y536315D03*
X1832200Y567760D03*
X1839126Y583354D03*
X1811500Y603500D03*
X1779000Y598900D03*
X1782700Y610900D03*
X1795000Y599600D03*
X1791323Y594030D03*
X1872908Y471338D03*
X1877518Y527560D03*
X1852340Y509140D03*
X1870138Y485732D03*
X1877407Y479046D03*
X1857450Y473654D03*
X1855206Y471112D03*
X1889800Y580200D03*
X1844100Y551000D03*
X1878450Y548650D03*
X1870892Y583245D03*
X1874825Y564125D03*
X1861080Y537090D03*
X1878000Y539000D03*
X1858528Y544528D03*
X1875850Y567200D03*
X1866800Y588000D03*
X1885100Y584300D03*
X1955790Y499790D03*
X1952500Y508000D03*
X1963500Y521000D03*
X1955400Y530500D03*
X1905010Y479410D03*
X1957100Y502990D03*
X1906050Y569100D03*
X1923600Y554200D03*
X1915593Y576807D03*
X1961500Y561700D03*
Y582700D03*
X1953500Y551900D03*
X1905000Y533900D03*
X1906200Y607800D03*
X1916050Y604450D03*
X1924000Y611391D03*
X1927000Y614500D03*
X1464124Y353776D03*
X1456000Y360700D03*
X1467597Y363000D03*
X1453900Y353350D03*
X1453251Y356676D03*
X1634500Y418500D03*
X85250Y127680D03*
X77730Y126860D03*
X53500Y307300D03*
X58400Y314600D03*
X53000Y323500D03*
X52804Y333247D03*
X61300Y328600D03*
X48550Y301650D03*
X53250Y302800D03*
X105892Y8700D03*
X106200Y26500D03*
X93500Y-18000D03*
X87091Y-16391D03*
X106000Y17260D03*
X102100Y73800D03*
X105892Y45290D03*
X108385Y84291D03*
X109057Y92774D03*
X105898Y55194D03*
X160431Y-1801D03*
X153738Y9114D03*
X150391Y-7851D03*
X163391D03*
X157084D03*
X153738Y-1751D03*
X160431Y9114D03*
X120273Y16839D03*
X147045Y9114D03*
X130163D03*
X123620D03*
X126580Y-7851D03*
X132959Y-7700D03*
X120273Y-9901D03*
X123620Y-1801D03*
X130313Y-1751D03*
X147045D03*
X167124D03*
X169770Y-7700D03*
X166974Y9114D03*
X169770Y30100D03*
X167124Y36049D03*
X120273Y27899D03*
X123620Y35983D03*
X130313D03*
X126580Y29949D03*
X132959Y30100D03*
X147045Y36049D03*
X153738D03*
X157084Y29949D03*
X163391D03*
X160431Y35999D03*
X150391Y29949D03*
X120273Y9157D03*
X166974Y84714D03*
Y73849D03*
Y46914D03*
X169770Y67900D03*
X157084Y67749D03*
X163391D03*
X130313Y73849D03*
X123620Y73799D03*
X126580Y67749D03*
X132959Y67900D03*
X123620Y46914D03*
X147045D03*
X120273Y54839D03*
Y92500D03*
X160431Y84714D03*
X153738D03*
X123620D03*
X147045D03*
X130163D03*
Y46914D03*
X120273Y66000D03*
X147045Y73849D03*
X153738D03*
X160431Y73799D03*
X150391Y67749D03*
X160431Y46914D03*
X153738D03*
X119892Y84700D03*
X120273Y46957D03*
X183856Y-1751D03*
Y9114D03*
Y36049D03*
X190549Y9114D03*
X197242D03*
X193895Y-7851D03*
X187202D03*
X200202D03*
X190549Y-1751D03*
X197242Y-1801D03*
X203935Y-1751D03*
X206581Y-7700D03*
X203785Y9114D03*
X200202Y29949D03*
X187202D03*
X193895D03*
X203935Y36049D03*
X206581Y30100D03*
X220667Y-1751D03*
X227360D03*
X234053Y-1801D03*
X230706Y-7851D03*
X224013D03*
X220667Y9114D03*
X234053D03*
X227360D03*
X224013Y29949D03*
X230706D03*
X234053Y35999D03*
X220667Y36049D03*
X227360D03*
X197242Y35999D03*
X190549Y36049D03*
X183856Y84714D03*
Y73849D03*
Y46914D03*
X193895Y67749D03*
X200202D03*
X187202D03*
X203785Y46914D03*
X190549D03*
X197242D03*
X206581Y67900D03*
X197242Y73799D03*
X203935Y73849D03*
X190549D03*
Y84714D03*
X197242D03*
X203785D03*
X220667Y46914D03*
X224013Y67749D03*
X230706D03*
X227360Y46914D03*
X234053Y73799D03*
X220667Y73849D03*
Y84714D03*
X227360D03*
Y73849D03*
X234053Y84714D03*
Y46914D03*
X270864Y-1801D03*
X240746Y-1751D03*
X264171D03*
X257478D03*
X243392Y-7700D03*
X260824Y-7851D03*
X237013D03*
X267517D03*
X264171Y9114D03*
X240596D03*
X270864D03*
X257478D03*
X267517Y29949D03*
X243392Y30100D03*
X257478Y36049D03*
X240746D03*
X264171D03*
X260824Y29949D03*
X237013D03*
X294289Y-1751D03*
X273824Y-7851D03*
X280203Y-7700D03*
X294289Y9114D03*
X277407D03*
X277557Y-1751D03*
X273824Y29949D03*
X280203Y30100D03*
X277557Y36049D03*
X294289D03*
X270864Y35999D03*
X257478Y46914D03*
X240596D03*
X243392Y67900D03*
X267517Y67749D03*
X270864Y46914D03*
X237013Y67749D03*
X260824D03*
X264171Y46914D03*
Y84714D03*
X257478D03*
X240746Y73849D03*
X257478D03*
X264171D03*
X270864Y84714D03*
X240596D03*
X270864Y73799D03*
X273824Y67749D03*
X280203Y67900D03*
X294289Y46914D03*
X277407D03*
Y84714D03*
X294289D03*
X277407Y73849D03*
X294289D03*
X297635Y-7851D03*
X304328D03*
X300982Y-1751D03*
Y9114D03*
X307675Y-1843D03*
Y9300D03*
X304328Y29949D03*
X307992Y13200D03*
X300982Y36049D03*
X321192Y13200D03*
X321334Y32100D03*
X308092D03*
X307675Y35957D03*
X297635Y29949D03*
X334292Y13200D03*
Y32100D03*
X308157Y-7180D03*
X307675Y17057D03*
Y28014D03*
X321061D03*
X327754Y35957D03*
X324407Y28014D03*
Y35957D03*
X314368Y28014D03*
X311021Y35957D03*
X334447D03*
X331100Y28014D03*
X354525Y28022D03*
X354526Y35957D03*
X351179Y28022D03*
X347833Y35957D03*
X344486D03*
Y28022D03*
X337793Y35957D03*
X341140Y28022D03*
X334446Y28014D03*
X321061Y17057D03*
X327754Y9114D03*
X324407Y17057D03*
Y9114D03*
X314368Y17057D03*
X311021Y9114D03*
X334446D03*
X331100Y17057D03*
X354526D03*
X354525Y9122D03*
X351179Y17057D03*
X347833Y9122D03*
X344486D03*
Y17057D03*
X337793Y9114D03*
X341140Y17057D03*
X334447D03*
X317714Y35957D03*
Y9114D03*
X307950Y50729D03*
X321192Y51000D03*
X304328Y67749D03*
X297635D03*
X300982Y46914D03*
X321334Y69900D03*
X307592Y73800D03*
X300982Y84714D03*
X334292Y51000D03*
Y69900D03*
X308166Y87394D03*
X300982Y73849D03*
X307675Y54857D03*
Y92657D03*
X321061Y65814D03*
X327754Y73757D03*
X324407Y65814D03*
Y73757D03*
X314368Y65814D03*
X334447Y73757D03*
X331100Y65814D03*
X354525Y65822D03*
X354526Y73757D03*
X351179Y65822D03*
X347833Y73757D03*
X344486D03*
Y65822D03*
X337793Y73757D03*
X341140Y65822D03*
X334446Y65814D03*
X321061Y54857D03*
X327754Y46914D03*
X324407Y54857D03*
Y46914D03*
X314368Y54857D03*
X311021Y46914D03*
X334446D03*
X331100Y54857D03*
X354526D03*
X354525Y46922D03*
X351179Y54857D03*
X347833Y46922D03*
X344486D03*
Y54857D03*
X337793Y46914D03*
X341140Y54857D03*
X334447D03*
X317714Y73757D03*
Y46914D03*
X380200Y-1200D03*
X394192Y-9700D03*
X408184Y32100D03*
Y13200D03*
X404723Y28022D03*
X401377Y35957D03*
X364565Y28014D03*
X361218D03*
X414762Y28021D03*
X404723Y35957D03*
X414763D03*
X394684D03*
X404723Y17057D03*
X401376Y9121D03*
X414762Y17058D03*
X398029Y17042D03*
X404722Y9121D03*
X414763Y9122D03*
X408069Y17042D03*
X411415Y36058D03*
X411416Y9122D03*
X371042Y46900D03*
X380792Y56500D03*
X408184Y51000D03*
Y69900D03*
X394492Y54700D03*
X404723Y65822D03*
X401377Y73757D03*
X414763Y65822D03*
X404723Y73757D03*
X414763D03*
X404723Y54857D03*
X401377Y46922D03*
X414763Y54857D03*
X398029Y54842D03*
X404723Y46922D03*
X414763D03*
X408069Y54842D03*
X411416Y73757D03*
Y46922D03*
X447744Y-7180D03*
X451573Y-1801D03*
Y9114D03*
X448226Y28100D03*
X433508Y32100D03*
X448292Y31900D03*
X421368Y32100D03*
X433508Y13200D03*
X421368D03*
X458266Y-1751D03*
X460912Y-7700D03*
X454533Y-7851D03*
X474998Y-1751D03*
X481691D03*
X478344Y-7851D03*
X481691Y9114D03*
X474998D03*
X478344Y29949D03*
X474998Y36049D03*
X460912Y30100D03*
X458266Y36049D03*
X481691D03*
X454533Y29949D03*
X458116Y9114D03*
X421455Y9121D03*
X421454Y-1817D03*
X438189Y35957D03*
X444880Y28022D03*
X444882Y35957D03*
X428149D03*
X421456Y28022D03*
X434842Y35957D03*
X438189Y28022D03*
X438187Y9120D03*
X431494Y17042D03*
X444880Y17059D03*
Y9122D03*
X428147Y9120D03*
X421456Y17057D03*
X434840Y9120D03*
X424801Y17042D03*
X438187Y17059D03*
X448492Y51000D03*
X421368D03*
X433508D03*
Y69900D03*
X421368D03*
X474998Y46914D03*
X454533Y67749D03*
X481691Y46914D03*
X460912Y67900D03*
X458116Y84714D03*
X474998Y73849D03*
X481691Y84714D03*
Y73849D03*
X458266D03*
X474998Y84714D03*
X478344Y67749D03*
X458116Y46914D03*
X448692Y89900D03*
X421455Y46921D03*
X421456Y73757D03*
X438189D03*
X444880Y65822D03*
X428149Y73757D03*
X421456Y65822D03*
X434842Y73757D03*
X438189Y65822D03*
Y46922D03*
X431494Y54842D03*
X444880Y54859D03*
Y46922D03*
X428149D03*
X421456Y54857D03*
X434842Y46922D03*
X424801Y54842D03*
X438187Y54859D03*
X511809Y-1751D03*
X495077D03*
X488384Y-1801D03*
X485037Y-7851D03*
X491344D03*
X497723Y-7700D03*
X494927Y9114D03*
X488384D03*
Y35999D03*
X497723Y30100D03*
X495077Y36049D03*
X485037Y29949D03*
X491344D03*
X515155Y-7851D03*
X518502Y-1751D03*
X521848Y-7851D03*
X531888Y-1751D03*
X525195Y-1801D03*
X528155Y-7851D03*
X534534Y-7700D03*
X518502Y9114D03*
X531738D03*
X525195D03*
X518502Y36049D03*
X531888D03*
X534534Y30100D03*
X525195Y35999D03*
X515155Y29949D03*
X528155D03*
X521848D03*
X511809Y36049D03*
Y9114D03*
X497723Y67900D03*
X511809Y46914D03*
X491344Y67749D03*
X494927Y46914D03*
X488384D03*
X511809Y84714D03*
X494927D03*
X488384D03*
Y73799D03*
X495077Y73849D03*
X518502Y46914D03*
X521848Y67749D03*
X531738Y46914D03*
X515155Y67749D03*
X534534Y67900D03*
X528155Y67749D03*
X525195Y46914D03*
X518502Y73849D03*
Y84714D03*
X531738D03*
X525195D03*
X531888Y73849D03*
X525195Y73799D03*
X511809Y73849D03*
X485037Y67749D03*
X562006Y9114D03*
X568549D03*
X555313D03*
X548620D03*
X571345Y-7700D03*
X551966Y-7851D03*
X564966D03*
X558659D03*
X562006Y-1801D03*
X558659Y29949D03*
X548620Y36049D03*
X551966Y29949D03*
X564966D03*
X568699Y36049D03*
X555313D03*
X562006Y35999D03*
X571345Y30100D03*
X588777Y-7851D03*
X598817Y-9901D03*
X595470Y-7851D03*
X592124Y-1751D03*
X598817D03*
X585431D03*
X602163Y-9901D03*
X598817Y9157D03*
X592124Y9114D03*
X585431D03*
X588777Y29949D03*
X585431Y36049D03*
X592124D03*
X595470Y29949D03*
X598817Y27899D03*
Y36049D03*
X602163Y16999D03*
X548620Y-1751D03*
X568699D03*
X555313D03*
X562006Y46914D03*
X548620D03*
X551966Y67749D03*
X564966D03*
X571345Y67900D03*
X548620Y84714D03*
X568549D03*
X555313D03*
X562006D03*
X548620Y73849D03*
X562006Y73799D03*
X555313Y73849D03*
X585431Y46914D03*
X598817Y46957D03*
Y65699D03*
X595470Y67749D03*
X588777D03*
X602163Y65699D03*
X592124Y84714D03*
X585431D03*
X598817Y84757D03*
X585431Y73849D03*
X598817D03*
X592124D03*
X602163Y92599D03*
X592124Y46914D03*
X568699Y73849D03*
X555313Y46914D03*
X568549D03*
X558659Y67749D03*
X620092Y13078D03*
X620192Y31978D03*
Y-5822D03*
X647317Y-1310D03*
X660676Y-2600D03*
X107750Y238730D03*
X108000Y249330D03*
X110180Y280920D03*
X110670Y344500D03*
X109960Y313190D03*
X110397Y402603D03*
X109640Y376070D03*
X109500Y370000D03*
X103100Y411800D03*
X112904Y237218D03*
X113100Y269163D03*
X118800Y298400D03*
X113100Y333106D03*
X113000Y304000D03*
X122361Y342649D03*
X119300Y400900D03*
X118220Y360500D03*
X105958Y518550D03*
X106392Y527413D03*
Y537000D03*
X105392Y574800D03*
X105412Y556580D03*
X105392Y566000D03*
X82459Y618932D03*
X105352Y594770D03*
X106192Y604600D03*
X130163Y510114D03*
X147045D03*
X120273Y517900D03*
X120210Y529200D03*
X123620Y510114D03*
X166974D03*
X160431D03*
X153738D03*
X119892Y510100D03*
X130163Y547914D03*
X123620D03*
X147045Y537049D03*
Y547914D03*
X130313Y537049D03*
X132959Y531100D03*
X126580Y530949D03*
X123620Y536999D03*
Y574799D03*
X130313Y574849D03*
X120092Y566900D03*
X147045Y585714D03*
X120273Y555700D03*
X130163Y585714D03*
X123620D03*
X150391Y530949D03*
X166974Y537049D03*
X163391Y530949D03*
X160431Y536999D03*
X166974Y547914D03*
X160431D03*
X157084Y530949D03*
X153738Y537049D03*
Y547914D03*
X169770Y531100D03*
X160431Y585714D03*
X166974D03*
X153738D03*
Y574849D03*
X157084Y568749D03*
X169770Y568900D03*
X160431Y574799D03*
X166974Y574849D03*
X163391Y568749D03*
X150391D03*
X147045Y574849D03*
X126580Y568749D03*
X132959Y568900D03*
X119892Y536983D03*
Y547900D03*
Y574700D03*
Y585700D03*
X147045Y612649D03*
X123620Y612599D03*
X130313Y612649D03*
X160431Y612599D03*
X166974Y612649D03*
X153738D03*
X132959Y606700D03*
X126580Y606549D03*
X120092Y604900D03*
X150391Y606549D03*
X163391D03*
X169770Y606700D03*
X157084Y606549D03*
X119892Y612583D03*
X197242Y510114D03*
X203785D03*
X190549D03*
X183856D03*
X220667D03*
X227360D03*
X234053D03*
X183856Y547914D03*
X190549D03*
X203785D03*
X197242D03*
X190549Y537049D03*
X183856D03*
X187202Y530949D03*
X193895D03*
X197242Y536999D03*
X203935Y537049D03*
X200202Y530949D03*
X206581Y531100D03*
X197242Y574799D03*
X190549Y585714D03*
X183856D03*
X197242D03*
X203785D03*
X234053Y536999D03*
X224013Y530949D03*
X220667Y537049D03*
X230706Y530949D03*
X227360Y537049D03*
X234053Y547914D03*
X220667D03*
X227360D03*
X220667Y585714D03*
X234053D03*
X227360D03*
Y574849D03*
X230706Y568749D03*
X220667Y574849D03*
X224013Y568749D03*
X234053Y574799D03*
X206581Y568900D03*
X183856Y574849D03*
X190549D03*
X193895Y568749D03*
X187202D03*
X200202D03*
X203935Y574849D03*
X234053Y612599D03*
X227360Y612649D03*
X220667D03*
X203935D03*
X197242Y612599D03*
X190549Y612649D03*
X183856D03*
X187202Y606549D03*
X193895D03*
X200202D03*
X206581Y606700D03*
X224013Y606549D03*
X230706D03*
X264171Y510114D03*
X257478D03*
X270864D03*
X240596D03*
X277407D03*
X294289D03*
X257478Y537049D03*
X237013Y530949D03*
X243392Y531100D03*
X240746Y537049D03*
X270864Y547914D03*
X267517Y530949D03*
X270864Y536999D03*
X264171Y547914D03*
X257478D03*
X240596D03*
X264171Y537049D03*
X260824Y530949D03*
X270864Y585714D03*
X264171D03*
X257478D03*
X240596D03*
X277407Y537049D03*
X273824Y530949D03*
X294289Y547914D03*
X280203Y531100D03*
X294289Y537049D03*
X277407Y547914D03*
Y585714D03*
X294289D03*
Y574849D03*
X277407D03*
X280203Y568900D03*
X273824Y568749D03*
X243392Y568900D03*
X260824Y568749D03*
X257478Y574849D03*
X264171D03*
X237013Y568749D03*
X240746Y574849D03*
X267517Y568749D03*
X270864Y574799D03*
X240746Y612649D03*
X257478D03*
X260824Y606549D03*
X237013D03*
X243392Y606700D03*
X264171Y612449D03*
X267517Y606549D03*
X270864Y612399D03*
X273824Y606549D03*
X294289Y612249D03*
X280203Y606700D03*
X277407Y612449D03*
X308166Y512794D03*
X300982Y510114D03*
X307675Y518057D03*
X308198Y528863D03*
X321061Y529014D03*
X324407D03*
X331100D03*
X354525Y529022D03*
X351179D03*
X344486D03*
X341140D03*
X334446Y529014D03*
X307675Y548200D03*
X300982Y547914D03*
X307675Y536957D03*
X304328Y530949D03*
X300982Y537049D03*
X297635Y530949D03*
X307992Y533100D03*
X321334D03*
X321123Y552000D03*
X308100D03*
X307992Y570900D03*
X321334D03*
X321192Y589800D03*
X307675Y574757D03*
X300982Y574849D03*
Y585714D03*
X334292Y533100D03*
Y552000D03*
Y570900D03*
Y589800D03*
X297635Y568749D03*
X304328D03*
X307675Y555857D03*
X307984Y566743D03*
X327754Y536957D03*
X324407D03*
X311021D03*
X334447D03*
X354526D03*
X347833D03*
X344486D03*
X337793D03*
X321061Y566814D03*
Y555857D03*
X327754Y547914D03*
Y574757D03*
X324407Y555857D03*
Y566814D03*
Y547914D03*
Y574757D03*
X314368Y566814D03*
X311021Y574757D03*
X314368Y555857D03*
X311021Y547914D03*
X334446D03*
X334447Y574757D03*
X331100Y555857D03*
Y566814D03*
X354526Y555857D03*
X354525Y566822D03*
Y547922D03*
X354526Y574757D03*
X351179Y555857D03*
Y566822D03*
X347833Y547922D03*
Y574757D03*
X344486Y547922D03*
Y574757D03*
Y566822D03*
Y555857D03*
X337793Y547914D03*
Y574757D03*
X341140Y555857D03*
Y566822D03*
X334447Y555857D03*
X334446Y566814D03*
X327754Y585714D03*
X324407D03*
X311021D03*
X334446D03*
X354525Y585722D03*
X347833D03*
X344486D03*
X337793Y585714D03*
X317714Y536957D03*
Y547914D03*
Y574757D03*
Y585714D03*
X304328Y606549D03*
X297635D03*
X300982Y612249D03*
X307675Y611600D03*
X308157Y607220D03*
X321061Y593657D03*
X324407D03*
X314368D03*
X331100D03*
X354526D03*
X351179D03*
X344486D03*
X341140D03*
X334447D03*
X363760Y529293D03*
X404723Y529022D03*
X376785Y538305D03*
X376892Y577500D03*
X408184Y533100D03*
Y552000D03*
Y589800D03*
Y570900D03*
X401377Y536957D03*
X404723D03*
X414763D03*
X404723Y566822D03*
Y555857D03*
X401376Y547922D03*
X401377Y574757D03*
X414763Y566822D03*
Y555857D03*
X398029Y555842D03*
X404723Y547922D03*
Y574757D03*
X414763D03*
Y547922D03*
X408069Y555842D03*
X394684Y574757D03*
X401377Y585722D03*
X404723D03*
X414763D03*
X411416Y536957D03*
X411415Y547921D03*
X411416Y574757D03*
Y585722D03*
X404723Y593657D03*
X414763D03*
X398029Y593642D03*
X408069D03*
X451573Y510114D03*
X474998D03*
X458116D03*
X481691D03*
X421456Y529022D03*
X451573Y547914D03*
X448510Y549843D03*
X448692Y553100D03*
X421368Y533100D03*
X434395Y532904D03*
X433508Y552000D03*
X421368D03*
X420634Y589800D03*
X433508Y570900D03*
X421368D03*
X433500Y589800D03*
X451573Y585714D03*
Y574799D03*
X458116Y547914D03*
X454533Y530949D03*
X460912Y531100D03*
X458266Y537049D03*
X474998D03*
X481691Y547914D03*
X474998D03*
X478344Y530949D03*
X481691Y537049D03*
Y585714D03*
X474998D03*
X458116D03*
X454533Y568749D03*
X460912Y568900D03*
X458266Y574849D03*
X474998D03*
X478344Y568749D03*
X481691Y574849D03*
X448291Y574773D03*
X448226Y569200D03*
X421456Y547922D03*
Y585722D03*
X438189Y536957D03*
X444882D03*
X428149D03*
X434842D03*
X438189Y547922D03*
Y574757D03*
X444880Y566822D03*
X444882Y574757D03*
X431494Y555842D03*
X444880Y555859D03*
Y547922D03*
X428149D03*
Y574757D03*
X421456Y555857D03*
Y566822D03*
X434842Y547922D03*
Y574757D03*
X438189Y566822D03*
X424801Y555842D03*
X438187Y555859D03*
X438189Y585722D03*
X444880D03*
X428149D03*
X434842D03*
X474998Y612649D03*
X458266D03*
X451573Y612599D03*
X447744Y607220D03*
X478344Y606549D03*
X460912Y606700D03*
X454533Y606549D03*
X421454Y612560D03*
X431494Y593642D03*
X444880Y593659D03*
X421456Y593657D03*
X424801Y593642D03*
X438187Y593659D03*
X511809Y510114D03*
X494927D03*
X488384D03*
X531738D03*
X525195D03*
X518502D03*
X511809Y547914D03*
Y537049D03*
X494927Y547914D03*
X488384D03*
X491344Y530949D03*
X488384Y536999D03*
X495077Y537049D03*
X497723Y531100D03*
X485037Y530949D03*
X488384Y585714D03*
X511809D03*
X494927D03*
X515155Y530949D03*
X534534Y531100D03*
X531888Y537049D03*
X528155Y530949D03*
X525195Y536999D03*
Y547914D03*
X531738D03*
X518502D03*
Y537049D03*
X521848Y530949D03*
X518502Y585714D03*
X531738D03*
X525195D03*
X531888Y574849D03*
X528155Y568749D03*
X525195Y574799D03*
X534534Y568900D03*
X521848Y568749D03*
X518502Y574849D03*
X515155Y568749D03*
X495077Y574849D03*
X488384Y574799D03*
X497723Y568900D03*
X491344Y568749D03*
X511809Y574849D03*
X485037Y568749D03*
X525195Y612599D03*
X518502Y612649D03*
X531888D03*
X495077D03*
X488384Y612599D03*
X511809Y612649D03*
X491344Y606549D03*
X497723Y606700D03*
X485037Y607230D03*
X515155Y606549D03*
X521848D03*
X534534Y606700D03*
X528155Y606549D03*
X555313Y510114D03*
X548620D03*
X568549D03*
X562006D03*
X598817Y510157D03*
Y528899D03*
X602163Y517999D03*
Y528899D03*
X592124Y510114D03*
X585431D03*
X548620Y547914D03*
Y537049D03*
X551966Y530949D03*
X558659D03*
X555313Y537049D03*
X562006Y536999D03*
X564966Y530949D03*
X568699Y537049D03*
X571345Y531100D03*
X555313Y547914D03*
X568549D03*
X562006D03*
X555313Y585714D03*
X568549D03*
X562006D03*
X548620D03*
X598817Y547957D03*
X592124Y547914D03*
X595470Y530949D03*
X592124Y537049D03*
X588777Y530949D03*
X598817Y537049D03*
X585431Y547914D03*
Y537049D03*
Y585714D03*
X598817Y585757D03*
Y566699D03*
X592124Y585714D03*
Y574849D03*
X588777Y568749D03*
X595470D03*
X598817Y574849D03*
X585431D03*
X548620D03*
X551966Y568749D03*
X568699Y574849D03*
X558659Y568749D03*
X555313Y574849D03*
X562006Y574799D03*
X564966Y568749D03*
X571345Y568900D03*
X585431Y612649D03*
X592124D03*
X598817D03*
X555313D03*
X562006Y612599D03*
X568699Y612649D03*
X548620D03*
X571345Y606700D03*
X558659Y606549D03*
X564966D03*
X551966D03*
X598817Y604499D03*
X595470Y606549D03*
X588777D03*
X602163Y593599D03*
Y604499D03*
X662000Y589000D03*
X620033Y608878D03*
X660230Y598170D03*
X274619Y205210D03*
X271239Y207159D03*
X277999Y218860D03*
X281379Y216909D03*
X284759Y218860D03*
X294899Y216909D03*
Y220809D03*
X288139D03*
X284759Y211060D03*
X294899Y205210D03*
Y209109D03*
X281379Y205210D03*
Y209109D03*
X291519Y211060D03*
X288139Y213009D03*
Y205210D03*
Y209109D03*
X267859D03*
X274619D03*
X281379Y228610D03*
X288139Y224709D03*
X284759Y230559D03*
X288139Y228610D03*
X277999Y222760D03*
X264092Y242260D03*
X271239D03*
X277999Y226660D03*
X281379Y224709D03*
X284759Y222760D03*
X277999Y238360D03*
X281379Y236409D03*
X277999Y242260D03*
X284759Y238360D03*
X288139Y244209D03*
Y240309D03*
X281379Y244209D03*
X284759Y242260D03*
X294899Y232509D03*
Y236409D03*
Y240309D03*
X342218Y205210D03*
X298279Y214960D03*
X308418Y216909D03*
Y220809D03*
X305039Y214960D03*
X301659Y213009D03*
Y216909D03*
Y220809D03*
X345598Y207159D03*
X342218Y209109D03*
X348978Y205210D03*
Y216909D03*
X352357Y218860D03*
X345598D03*
X342218Y213009D03*
X338838Y214960D03*
X359117Y211060D03*
Y218860D03*
X355737Y216909D03*
Y213009D03*
X338838Y218860D03*
X345598Y214960D03*
X352357D03*
X355737Y205210D03*
X342218Y216909D03*
X335458Y220809D03*
X338838Y207158D03*
X345598Y211060D03*
X348978Y213009D03*
X338838Y230560D03*
X298279Y222760D03*
X305039D03*
X328698Y236409D03*
X301659Y224709D03*
X328698Y240309D03*
Y244209D03*
X325318Y238360D03*
X335458Y240309D03*
Y244209D03*
X321938Y240309D03*
Y244209D03*
X332078Y238360D03*
X342218Y224709D03*
X345598Y230559D03*
X338838Y222760D03*
X352357D03*
X348978Y224709D03*
X355737D03*
X348978Y228610D03*
X352357Y230559D03*
X348978Y236409D03*
Y240309D03*
X352357Y234460D03*
X345598Y242260D03*
Y234460D03*
X342218Y240309D03*
Y228610D03*
Y236409D03*
X298279Y230559D03*
X301659Y244209D03*
X305039Y242260D03*
X301659Y232509D03*
X311798Y230559D03*
X318558Y234460D03*
Y222760D03*
X321938Y224709D03*
X311798Y234460D03*
X315178Y236409D03*
Y224709D03*
X321938Y228610D03*
X298279Y242260D03*
X305039Y238360D03*
X311798Y226660D03*
X305039Y234460D03*
X321938Y232509D03*
X298279Y238360D03*
X315178Y228610D03*
X301659Y236409D03*
X318558Y230559D03*
X359117D03*
X355737Y228610D03*
Y236409D03*
X352357Y242260D03*
X355737Y240309D03*
X342218Y244209D03*
Y232509D03*
X355737Y244209D03*
X348978D03*
X345598Y226660D03*
X352357D03*
X348978Y232509D03*
X355737D03*
X345598Y222760D03*
X332078D03*
X328698Y224709D03*
X332078Y226660D03*
X335458Y228610D03*
X328698D03*
X332078Y230560D03*
X335458Y232510D03*
X311798Y242260D03*
X315178Y244209D03*
X372637Y207159D03*
X399676D03*
X372637Y211060D03*
X392916D03*
X389537Y213009D03*
X396296D03*
X369257D03*
X396296Y216909D03*
X376017D03*
X365877Y218860D03*
X372637D03*
X362497Y216909D03*
X382777Y213009D03*
X399676Y218860D03*
X386157Y211060D03*
X379397Y207159D03*
X369257Y216909D03*
X382777D03*
X379397Y218860D03*
X392916D03*
X362497Y213009D03*
X386157Y218860D03*
X389537Y216909D03*
X376017Y213009D03*
X386157Y207159D03*
X365877Y214960D03*
X372637D03*
X379397D03*
X359117D03*
X376017Y205211D03*
X362497Y205210D03*
X386157Y214960D03*
X392916D03*
X399676D03*
Y211060D03*
X396296Y244209D03*
Y240309D03*
X376017Y224709D03*
X372637Y222760D03*
X365877D03*
X369257Y224709D03*
X362497D03*
X386157Y222760D03*
X396296Y228610D03*
X389537Y224709D03*
X399676Y222760D03*
X382777Y224709D03*
X379397Y222760D03*
X359117D03*
X392916D03*
X396296Y224709D03*
X379397Y230559D03*
X365877Y242260D03*
X372637Y234460D03*
X365877D03*
X372637Y230559D03*
X365877D03*
X369257Y236409D03*
X362497D03*
X369257Y228610D03*
X362497D03*
X382777D03*
X389537Y236409D03*
X399676Y230559D03*
Y234460D03*
X382777Y236409D03*
X392916Y230559D03*
X376017Y236409D03*
X369257Y240309D03*
X376017D03*
X386157Y230559D03*
X372637Y242260D03*
X379397Y234460D03*
X399676Y238360D03*
X359117Y242260D03*
X362497Y240309D03*
X359117Y234460D03*
X386157D03*
X392916D03*
X389537Y228610D03*
X396296Y236409D03*
X376017Y228610D03*
X386157Y226660D03*
X389537Y232509D03*
X369257Y244209D03*
X362497D03*
X372637Y226660D03*
X365877D03*
X369257Y232509D03*
X362497D03*
X379397Y226660D03*
X382777Y232509D03*
X376017D03*
X359117Y226660D03*
X392916D03*
X396296Y232509D03*
X399676Y226660D03*
Y242260D03*
X389537Y240309D03*
X382777D03*
X392916Y242260D03*
X386157D03*
X379397D03*
X389537Y244209D03*
X382777D03*
X376017D03*
X392916Y246160D03*
X386157D03*
X399676D03*
X271239Y269560D03*
Y273460D03*
Y265660D03*
X267859Y263709D03*
Y259809D03*
X264179Y265660D03*
X267859Y252009D03*
X264179Y253960D03*
X281379Y252009D03*
X274619D03*
X277999Y253960D03*
X284759D03*
X291519D03*
X284759Y265660D03*
X291519D03*
Y277360D03*
X281379Y275409D03*
Y271509D03*
X284759Y277360D03*
Y273460D03*
X288139Y275409D03*
Y271509D03*
X277999Y277360D03*
X274619Y255909D03*
Y259809D03*
X277999Y269560D03*
X274619Y275409D03*
Y267609D03*
Y263709D03*
X288139Y255909D03*
X291519Y269560D03*
Y257860D03*
Y261760D03*
X294899Y275409D03*
Y263709D03*
X281379Y259809D03*
X288139Y252009D03*
X264179Y257860D03*
X271239D03*
X264179Y261760D03*
X271239D03*
Y253960D03*
X267859Y255909D03*
X281379Y267609D03*
X288139Y263709D03*
X277999Y257860D03*
X281379Y255909D03*
X284759Y269560D03*
X288139Y267609D03*
X277999Y261760D03*
X284759Y257860D03*
X288139Y259809D03*
X277999Y265660D03*
X284759Y261760D03*
X281379Y263709D03*
X294899Y252009D03*
Y255909D03*
Y259809D03*
X271239Y328060D03*
X264179D03*
X291519Y285160D03*
Y292959D03*
X284759Y285160D03*
X277999Y308560D03*
Y300760D03*
Y292959D03*
Y285160D03*
X291519Y308560D03*
X284759D03*
Y300760D03*
X291519D03*
X284759Y292959D03*
X281379Y318309D03*
X274619Y326110D03*
Y322209D03*
X277999Y320260D03*
Y316360D03*
X308418Y252009D03*
X298279Y253960D03*
X325318D03*
X308418Y275409D03*
X301659D03*
X308418Y255909D03*
X321938Y283209D03*
Y275409D03*
X315178Y279310D03*
X318558Y277360D03*
X315178Y283209D03*
X318558Y281260D03*
X311798Y261760D03*
X321938Y259809D03*
X301659D03*
X308418Y263709D03*
X325318Y269560D03*
X305039D03*
X318558D03*
X328698Y267609D03*
Y283209D03*
Y259809D03*
X332078Y269560D03*
Y281260D03*
X321938Y255909D03*
X308418Y259809D03*
X325318Y281260D03*
Y273460D03*
Y265660D03*
X301659Y267609D03*
X321938Y263709D03*
X298279Y265660D03*
X305039Y273460D03*
Y277360D03*
X311798D03*
Y269560D03*
X305039Y265660D03*
X298279Y277360D03*
X328698Y252009D03*
X338838Y253960D03*
X335458Y252009D03*
X338838Y265660D03*
X335458Y259809D03*
Y267609D03*
X338838Y281260D03*
X335458Y283209D03*
X345598Y265660D03*
X348978Y263709D03*
X355737Y259809D03*
X352357Y261760D03*
X345598Y273460D03*
Y269560D03*
X342218Y263709D03*
Y271509D03*
Y259809D03*
Y255909D03*
Y267609D03*
Y283209D03*
Y279310D03*
Y275409D03*
X298279Y261760D03*
X305039Y257860D03*
X328698Y255909D03*
Y263709D03*
X338838Y257860D03*
Y261760D03*
X325318Y257860D03*
Y261760D03*
X335458Y255909D03*
Y263709D03*
X301659D03*
X305039Y261760D03*
X301659Y252009D03*
X305039Y253960D03*
X332078D03*
X315178Y263709D03*
X332078Y265660D03*
X315178Y275409D03*
X301659Y255909D03*
X332078Y257860D03*
X315178Y267609D03*
X332078Y261760D03*
X315178Y271509D03*
X298279Y257860D03*
X311798Y265660D03*
Y273460D03*
X321938Y267609D03*
Y271509D03*
X308418Y267609D03*
Y271509D03*
X318558Y265660D03*
Y273460D03*
X342218Y252009D03*
X311798Y292959D03*
X305039D03*
X318558D03*
X311798Y285160D03*
X332078Y300760D03*
Y292959D03*
X298279Y308560D03*
X315178Y310509D03*
X305039Y308560D03*
X311798D03*
X305039Y300760D03*
X325318D03*
X311798D03*
X298279D03*
X318558D03*
X325318Y292959D03*
X305039Y285160D03*
X298279D03*
Y292959D03*
X338838Y300760D03*
Y292959D03*
X342218Y310509D03*
Y314409D03*
Y318309D03*
X345598Y320260D03*
Y324160D03*
X365877Y253960D03*
X362497Y255909D03*
X359117Y257860D03*
X369257Y252009D03*
X441743Y348497D03*
X445123Y346546D03*
X267859Y333909D03*
Y341709D03*
X264179Y339760D03*
Y343660D03*
X291519Y328060D03*
X284759Y343660D03*
X288139Y341709D03*
X274619D03*
X277999Y343660D03*
X274619Y333909D03*
Y337809D03*
X284759Y324160D03*
X294899Y333909D03*
X281379Y337809D03*
X291519Y343660D03*
Y339760D03*
Y335860D03*
X294899Y322209D03*
X284759Y331960D03*
X291519D03*
X288139Y326110D03*
X271239Y335860D03*
X264179D03*
X271239Y343660D03*
Y339760D03*
X267859Y345609D03*
Y337809D03*
X288139Y333909D03*
X281379Y330009D03*
Y341709D03*
X277999Y339760D03*
X288139Y330009D03*
X284759Y328060D03*
Y339760D03*
X277999Y335860D03*
Y331960D03*
X284759Y335860D03*
X281379Y333909D03*
X288139Y337809D03*
X294899Y341709D03*
Y337809D03*
X271239Y355360D03*
X267859Y349509D03*
Y353409D03*
X267559Y361209D03*
X264179Y355360D03*
X284759Y351460D03*
X281379Y345609D03*
X274619Y361209D03*
Y345609D03*
X277999Y347560D03*
X274619Y353409D03*
Y357309D03*
Y349509D03*
X288139Y345609D03*
X264179Y351460D03*
X271239D03*
X264179Y347560D03*
X271239D03*
X284759D03*
X277999Y355360D03*
X281379Y349509D03*
X277999Y351460D03*
X281379Y353409D03*
X308418Y333909D03*
Y341709D03*
X325318Y335860D03*
X301659Y337809D03*
X315178Y330009D03*
X301659D03*
X308418Y337809D03*
X305039Y331960D03*
X298279Y343660D03*
Y328060D03*
Y331960D03*
X311798Y324160D03*
X308418Y330009D03*
X315178Y322209D03*
X321938D03*
X305039Y328060D03*
X321938Y330009D03*
Y337809D03*
X328698Y330009D03*
Y326110D03*
Y333909D03*
X325318Y324160D03*
X318558Y320260D03*
X332078Y331960D03*
X308418Y326110D03*
X335458Y330009D03*
X305039Y339760D03*
X298279Y335860D03*
X332078D03*
X305039D03*
X301659Y333909D03*
X318558Y328060D03*
Y335860D03*
X301659Y341709D03*
X298279Y339760D03*
X335458Y333909D03*
X318558Y324160D03*
Y331960D03*
X305039Y343660D03*
X315178Y326110D03*
Y333909D03*
X325318Y328060D03*
Y331960D03*
X311798Y328060D03*
Y331960D03*
X321938Y326110D03*
Y333909D03*
X288139Y372909D03*
X281379Y369010D03*
Y380709D03*
X277999Y378760D03*
X288139Y369010D03*
X284759Y367060D03*
Y378760D03*
X277999Y374860D03*
X294899Y376809D03*
Y380709D03*
X284759Y374860D03*
X277999Y370959D03*
X288139Y376809D03*
X281379Y372909D03*
X284759Y386560D03*
Y394359D03*
X294899Y388509D03*
Y392410D03*
X281379Y388509D03*
Y392410D03*
X291519Y386560D03*
Y394359D03*
X288139Y388509D03*
Y396309D03*
Y357309D03*
Y384609D03*
Y392410D03*
X294899Y361209D03*
Y365109D03*
Y357309D03*
X274619Y400209D03*
X281379D03*
X271239Y394359D03*
X267859Y392410D03*
X294899Y400209D03*
X271239Y398260D03*
X277999D03*
X274619Y396309D03*
X332078Y343660D03*
X338838D03*
X355737Y345609D03*
X352357Y343660D03*
X342218Y384609D03*
X341892Y396301D03*
X345598Y386560D03*
X298279Y374860D03*
Y382660D03*
X308418Y376809D03*
Y380709D03*
X305039Y374860D03*
Y382660D03*
X301659Y376809D03*
X328698Y353409D03*
X301659Y384609D03*
X328698Y361209D03*
X301659Y372909D03*
X328698Y349509D03*
X301659Y380709D03*
X328698Y357309D03*
X325318Y351460D03*
Y359260D03*
X335458Y353409D03*
Y357309D03*
X321938Y353409D03*
Y357309D03*
X332078Y351460D03*
Y359260D03*
X348978Y388509D03*
X342218Y380709D03*
X351192Y402800D03*
X345598Y378760D03*
X348978Y380709D03*
X345598Y367060D03*
X348978Y372909D03*
X342218D03*
X338838Y374860D03*
Y370959D03*
Y378760D03*
X352357D03*
Y374860D03*
X359117Y386560D03*
X355737Y380709D03*
X359117Y374860D03*
X355737Y372909D03*
X348978Y369010D03*
X352357Y367060D03*
X355737Y384609D03*
X345598Y355360D03*
X348978Y357309D03*
X345598Y351460D03*
X348978Y361209D03*
X345598Y363160D03*
X342218Y357309D03*
Y369010D03*
Y361209D03*
X301659Y365109D03*
X298279Y367060D03*
X305039Y355360D03*
X301659Y353409D03*
X318558Y363160D03*
X311798Y367060D03*
X321938Y372909D03*
X318558Y374860D03*
X315178Y361209D03*
X311798Y363160D03*
X321938Y369010D03*
X315178Y372909D03*
X305039Y359260D03*
X298279Y355360D03*
X301659Y361209D03*
X318558Y367060D03*
X311798Y370959D03*
X335458Y345609D03*
X305039Y363160D03*
X321938Y365109D03*
X298279Y359260D03*
X315178Y369010D03*
X352357Y351460D03*
Y363160D03*
X359117D03*
X355737Y361209D03*
Y369010D03*
X352357Y355360D03*
X355737Y357309D03*
X359117Y351460D03*
X345598Y370959D03*
X355737Y353409D03*
X348978D03*
X342218Y365109D03*
Y353409D03*
X338838Y367060D03*
X348978Y365109D03*
X355737D03*
X352357Y370959D03*
X338838Y382660D03*
X357987Y402800D03*
X345598Y382660D03*
X352357D03*
X348978Y392410D03*
X355737D03*
X315178Y353409D03*
X348978Y345609D03*
X311798Y355360D03*
Y351460D03*
X342218Y349509D03*
X345598Y347560D03*
X315178Y384609D03*
X348978D03*
X315178Y380709D03*
X335458Y376809D03*
X332078Y374860D03*
X345598D03*
X328698Y372909D03*
X332078Y370959D03*
X328698Y369010D03*
X335458D03*
X332078Y367060D03*
X335458Y365109D03*
X338838Y363160D03*
X352357Y347560D03*
X392916Y355360D03*
X396296Y357309D03*
X389537D03*
X372637Y390460D03*
X396296Y384609D03*
X372637Y386560D03*
X392916D03*
X389537Y384609D03*
X399676Y390460D03*
X376017Y372909D03*
X369257Y384609D03*
X396296Y380709D03*
X369257Y372909D03*
X362497D03*
X372637Y378760D03*
X362497Y380709D03*
X372637Y374860D03*
X365877D03*
X376017Y380709D03*
X365877Y378760D03*
X382777Y384609D03*
X386157Y374860D03*
X399676Y378760D03*
X396296Y369010D03*
X386157Y386560D03*
X389537Y372909D03*
X403056Y380709D03*
X399676Y374860D03*
X379397Y386560D03*
X369257Y380709D03*
X382777D03*
Y372909D03*
X379397Y378760D03*
Y374860D03*
X392916Y378760D03*
X362497Y384609D03*
X359117Y378760D03*
X386157D03*
X392916Y374860D03*
X389537Y380709D03*
X396296Y372909D03*
X376017Y384609D03*
X379397Y367060D03*
X365877Y355360D03*
X403056Y361209D03*
X369257Y369010D03*
X362497D03*
X369257Y361209D03*
X362497D03*
X372637Y367060D03*
X365877D03*
X372637Y363160D03*
X365877D03*
X382777Y369010D03*
X389537Y361209D03*
X399676Y367060D03*
Y363160D03*
X382777Y361209D03*
X392916Y367060D03*
X403056Y372909D03*
Y369010D03*
X376017Y361209D03*
X369257Y357309D03*
X376017D03*
X386157Y367060D03*
X372637Y355360D03*
X379397Y363160D03*
X399676Y359260D03*
X359117Y355360D03*
X362497Y357309D03*
X359117Y367060D03*
X386157Y363160D03*
X392916D03*
X389537Y369010D03*
X396296Y361209D03*
X376017Y369010D03*
X379397Y370959D03*
X372637D03*
X365877D03*
X359117D03*
X386157D03*
X362497Y353409D03*
X376017D03*
X369257D03*
X389537Y365109D03*
X382777D03*
X369257D03*
X362497D03*
X376017D03*
X390657Y394359D03*
X391787Y402800D03*
X369257Y392410D03*
X362497D03*
X379397Y382660D03*
X372637D03*
X365877D03*
X359117D03*
X379397Y390460D03*
X378267Y402800D03*
X376017Y392410D03*
X386157Y382660D03*
X392916Y370959D03*
X399676D03*
X396296Y365109D03*
X403056D03*
Y357309D03*
X392916Y382660D03*
Y390460D03*
X399676Y382660D03*
X406568Y402471D03*
X403056Y392410D03*
X411431Y359351D03*
X403056Y353409D03*
X399676Y355360D03*
X365877Y351460D03*
X372637D03*
X362497Y349509D03*
X382777Y353409D03*
X386157Y355360D03*
X403056Y396309D03*
X411086Y394359D03*
Y390460D03*
X399676Y386560D03*
X411086D03*
Y382660D03*
Y378760D03*
X398546Y402900D03*
X382777Y357309D03*
X379397Y355360D03*
X402892Y400400D03*
X359117Y347560D03*
X443993Y381947D03*
Y389747D03*
X440613Y383896D03*
Y387796D03*
X447373Y383896D03*
Y391696D03*
Y379996D03*
Y387796D03*
X423714Y389747D03*
Y393647D03*
X433854Y383896D03*
Y387796D03*
X423714Y378047D03*
Y381947D03*
X430474D03*
Y389747D03*
X427094Y383896D03*
Y391696D03*
Y379996D03*
Y387796D03*
Y364396D03*
X423714Y370247D03*
X437233Y366347D03*
Y370247D03*
X423714Y358547D03*
Y366347D03*
X433854Y364396D03*
Y372197D03*
X443993Y362447D03*
X440613Y356596D03*
Y360496D03*
X430474Y366347D03*
X447373Y356596D03*
X430474Y370247D03*
X447373Y364396D03*
X430474Y362447D03*
Y374146D03*
X447373Y360496D03*
X430474Y358547D03*
X433854Y356596D03*
X437233Y378047D03*
X440613Y376096D03*
X443993Y374147D03*
Y370247D03*
X415634Y204496D03*
Y212296D03*
Y208397D03*
X419214Y214247D03*
X415634Y220096D03*
Y216196D03*
X419214Y218147D03*
Y222047D03*
Y249347D03*
X415634Y247396D03*
Y235696D03*
Y223996D03*
X419214Y233746D03*
Y237647D03*
Y241547D03*
X415634Y227896D03*
Y231797D03*
X419214Y225947D03*
Y229847D03*
X441743Y199841D03*
X421464Y199583D03*
X446253Y206446D03*
X425974D03*
X453013Y218147D03*
X449633Y212296D03*
Y216196D03*
X422594D03*
X436113Y212296D03*
X432733Y214247D03*
X429354Y216196D03*
X432733Y218147D03*
X425974D03*
X429354Y220096D03*
X429353Y212296D03*
X446253Y218147D03*
X442873Y216196D03*
X439493Y214247D03*
X436113Y216196D03*
X449633Y220096D03*
X453013Y214247D03*
X439493Y210346D03*
X434983Y198931D03*
X455263Y198050D03*
X480052Y214247D03*
Y206447D03*
X473292Y218147D03*
X469913Y216196D03*
X469912Y212296D03*
X475692Y199900D03*
X466533Y218147D03*
X473292Y214247D03*
X476672Y212296D03*
Y216196D03*
X469913Y220096D03*
X459773Y214247D03*
X466533Y206446D03*
X458640Y200596D03*
X456393Y216196D03*
X462023Y198327D03*
X456393Y212296D03*
X463153Y216196D03*
X436113Y220096D03*
X446253Y222047D03*
X432733D03*
X442873Y220096D03*
X456393D03*
X466533Y222047D03*
X453013D03*
X463153Y220096D03*
X476672D03*
X473292Y222047D03*
X439493Y218147D03*
X459773D03*
X480052D03*
X439493Y222047D03*
X459773D03*
X480052D03*
X425974D03*
X422594Y220096D03*
X429354Y251296D03*
X453013Y245447D03*
Y229847D03*
Y237647D03*
X449633Y251296D03*
Y247396D03*
Y227896D03*
Y223996D03*
X436113Y243496D03*
X442873D03*
X422594D03*
X425974Y245447D03*
Y249347D03*
X432733D03*
X436113Y251296D03*
X429354Y247396D03*
X422594Y251296D03*
X446253Y245447D03*
X432733D03*
X439493Y237647D03*
X446253D03*
X422594Y223996D03*
Y231797D03*
X436113D03*
X439493Y241547D03*
X436113Y223996D03*
X429354D03*
Y227896D03*
X446253Y229847D03*
X432733D03*
X425974D03*
X439493Y233746D03*
X442873Y231797D03*
Y223996D03*
X425974Y237647D03*
X432733D03*
X439493Y253247D03*
X449633Y255196D03*
Y259096D03*
X446253Y257147D03*
X442873Y255196D03*
X453013Y257147D03*
Y261047D03*
X469913Y251296D03*
X466533Y245447D03*
X473292D03*
X480052Y237647D03*
X476672Y223996D03*
X480052Y233746D03*
Y241547D03*
X476672Y243496D03*
Y251296D03*
X469913Y247396D03*
Y223996D03*
X473292Y229847D03*
X469913Y227896D03*
X466533Y229847D03*
X473292Y237647D03*
X466533D03*
X456393Y243496D03*
Y251296D03*
X459773Y233746D03*
Y241547D03*
Y237647D03*
X456393Y223996D03*
Y231797D03*
X476672D03*
X463153Y243496D03*
Y251296D03*
Y231797D03*
Y223996D03*
X476672Y259096D03*
X463153D03*
X477792Y272747D03*
X462023Y271097D03*
X458643Y269146D03*
X456393Y262996D03*
Y259096D03*
X459773Y261047D03*
X469913Y255196D03*
X473292Y257147D03*
X466533D03*
X468783Y274997D03*
X469913Y270796D03*
X466533Y264947D03*
X481172Y274696D03*
Y278596D03*
X480052Y261047D03*
X436113Y227896D03*
X446253Y225947D03*
X432733D03*
X442873Y227896D03*
X456393D03*
X466533Y225947D03*
X453013D03*
X463153Y227896D03*
X476672D03*
X473292Y225947D03*
X439493Y229847D03*
X459773D03*
X480052Y225947D03*
X439493D03*
X459773D03*
X480052Y229847D03*
X425974Y225947D03*
X422594Y227896D03*
X466533Y233746D03*
Y241547D03*
X476672Y235696D03*
Y239596D03*
X463153Y235696D03*
Y239596D03*
X473292Y233746D03*
Y241547D03*
X469913Y231797D03*
Y243496D03*
Y235696D03*
Y239596D03*
X425974Y233746D03*
Y241547D03*
X436113Y235696D03*
Y239596D03*
X422594Y235696D03*
Y239596D03*
X432733Y233746D03*
Y241547D03*
X446253Y233746D03*
Y241547D03*
X456393Y235696D03*
Y239596D03*
X442873Y235696D03*
Y239596D03*
X453013Y233746D03*
Y241547D03*
X456393Y247396D03*
Y255196D03*
X466533Y249347D03*
Y253247D03*
X453013Y249347D03*
Y253247D03*
X463153Y247396D03*
Y255196D03*
X476672Y247396D03*
Y255196D03*
X473292Y249347D03*
Y253247D03*
X429354Y231797D03*
X449633D03*
X459773Y245447D03*
X480052D03*
X429354Y243496D03*
X449633D03*
X459773Y257147D03*
X480052D03*
X429354Y235696D03*
X449633D03*
X459773Y249347D03*
X480052D03*
X429354Y239596D03*
X449633D03*
X459773Y253247D03*
X480052D03*
X481172Y301996D03*
X477792Y303947D03*
Y288347D03*
X481172Y290296D03*
Y344896D03*
Y329296D03*
Y352696D03*
X511592Y206447D03*
Y210346D03*
Y218147D03*
X486812Y214247D03*
Y218147D03*
X498072Y222047D03*
X498350Y209900D03*
X486812Y222047D03*
X501452Y212296D03*
X486812Y210346D03*
X508212Y220096D03*
Y212296D03*
X518352Y218147D03*
X521731Y220096D03*
X518352Y206445D03*
X538631Y210346D03*
Y214247D03*
Y222047D03*
Y206447D03*
X528491Y208397D03*
Y220096D03*
X531871Y222047D03*
X525111Y218147D03*
X528491Y216196D03*
X535251Y204496D03*
X525111Y206447D03*
X531871D03*
X521731Y208397D03*
X483432Y216196D03*
Y220096D03*
X525111Y222047D03*
Y210346D03*
X521731Y212296D03*
X514972Y208397D03*
Y212296D03*
X508212Y216196D03*
X501452Y220096D03*
X504832Y214247D03*
X498072Y218147D03*
Y214247D03*
X494692Y220096D03*
X542011Y216196D03*
X538631Y218147D03*
X535251Y212296D03*
X531871Y210346D03*
Y214247D03*
X525111D03*
X518352D03*
Y210345D03*
X514972Y216196D03*
X511592Y214247D03*
X504832Y222047D03*
Y218147D03*
X501452Y216196D03*
X494692Y212296D03*
Y216196D03*
X542011Y212296D03*
Y220096D03*
X535251D03*
Y208397D03*
X528491Y212296D03*
X535251Y216196D03*
X511592Y241547D03*
Y249347D03*
X486812Y245447D03*
X494692Y247396D03*
X483432Y251296D03*
X501452Y247396D03*
X508212Y239596D03*
X498072Y233746D03*
X486812D03*
Y229847D03*
X494692Y235696D03*
X504832Y229847D03*
X486812Y225947D03*
X498072D03*
X486812Y237647D03*
X504832Y241547D03*
X486812D03*
X494692Y243496D03*
X483432D03*
X504832Y245447D03*
X501452Y223996D03*
X508212Y231797D03*
Y223996D03*
X483432Y235696D03*
Y223996D03*
X494692Y251296D03*
X501452Y282496D03*
Y274696D03*
X508212Y278596D03*
X484552Y268847D03*
X494692Y255196D03*
X486812Y257147D03*
X504832Y253247D03*
X487932Y282496D03*
Y278596D03*
Y274696D03*
X494692Y278596D03*
X501452Y266896D03*
Y259096D03*
X483432D03*
X508212Y270796D03*
X494692D03*
X518352Y229847D03*
X521731Y231797D03*
Y235696D03*
Y247396D03*
X538631Y225947D03*
Y237647D03*
X528491Y247396D03*
Y243496D03*
X538631Y249347D03*
X535251Y235696D03*
X528491Y227896D03*
Y235696D03*
X535251Y247396D03*
Y251296D03*
X542011Y239596D03*
X535251D03*
X525111Y237647D03*
X542011Y247396D03*
X514972D03*
Y227896D03*
Y235696D03*
Y239596D03*
Y223996D03*
X535251Y259096D03*
X531871Y261047D03*
X514972Y270796D03*
Y278596D03*
X525111Y253247D03*
X518352D03*
X528491Y274696D03*
X531871Y268847D03*
Y276646D03*
X535251Y266896D03*
X525111Y280547D03*
X521731Y266896D03*
Y259096D03*
Y274696D03*
X538631Y257147D03*
X542011Y274696D03*
X518352Y261047D03*
X525111D03*
X514972Y251296D03*
X518352Y272747D03*
X521731Y255196D03*
Y251296D03*
X498072Y264947D03*
X511592Y245447D03*
X514972Y243496D03*
X483432Y227896D03*
Y231797D03*
X486812Y249347D03*
Y253247D03*
X483432Y247396D03*
Y255196D03*
X525111Y272747D03*
X518352Y245447D03*
X531871Y257147D03*
X528491Y255196D03*
X511592Y253247D03*
X525111Y268847D03*
X518352Y241547D03*
Y237647D03*
X521731Y239596D03*
X525111Y249347D03*
Y245447D03*
X508212Y266896D03*
X535251Y243496D03*
X542011Y266896D03*
X538631Y272747D03*
X531871D03*
X538631Y280547D03*
X542011Y282496D03*
X538631Y276646D03*
X535251Y278596D03*
X531871Y280547D03*
X538631Y241547D03*
X542011Y243496D03*
Y251296D03*
Y255196D03*
Y262996D03*
X538631Y261047D03*
X531871Y245447D03*
X538631Y264947D03*
Y268847D03*
X535251Y270796D03*
X542011Y278596D03*
X535251Y274696D03*
Y282496D03*
X528491D03*
X538631Y245447D03*
Y253247D03*
X542011Y259096D03*
X535251Y262996D03*
X511592Y229847D03*
Y225947D03*
Y237647D03*
X508212Y235696D03*
X498072Y229847D03*
X504832Y233746D03*
X494692Y227896D03*
X501452Y235696D03*
X498072Y237647D03*
Y241547D03*
X542011Y227896D03*
Y235696D03*
X535251Y231797D03*
Y227896D03*
X531871Y229847D03*
X525111Y233746D03*
X521731Y223996D03*
X525111Y229847D03*
X514972Y231797D03*
X508212Y227896D03*
X511592Y233746D03*
X504832Y237647D03*
X501452Y227896D03*
Y231797D03*
X494692D03*
X501452Y239596D03*
X494692D03*
X501452Y243496D03*
X542011Y231797D03*
X538631Y233746D03*
Y229847D03*
X531871Y225947D03*
Y233746D03*
X528491Y231797D03*
X525111Y225947D03*
X518352D03*
X521731Y227896D03*
X525111Y257147D03*
X528491Y259096D03*
X518352Y268847D03*
Y249347D03*
X513857Y260881D03*
X504832Y307847D03*
X494692Y294196D03*
X501452Y290296D03*
X491312Y292245D03*
Y300047D03*
X508212Y290296D03*
Y294196D03*
X511592Y307847D03*
Y284447D03*
X494692Y309797D03*
X487932D03*
X498072Y303947D03*
X484552Y300047D03*
Y292245D03*
X494692Y286396D03*
X501452Y298096D03*
X508212Y329296D03*
X487932Y317596D03*
X504832Y319547D03*
X484552Y323446D03*
X508212Y317596D03*
Y325396D03*
X491312Y339047D03*
X511592Y327347D03*
Y315647D03*
Y323446D03*
X508212Y313696D03*
X504832Y315647D03*
X498072Y319547D03*
X504832Y323446D03*
X498072Y327347D03*
X491312Y331247D03*
X511592Y319547D03*
X538631Y311747D03*
X535251Y290296D03*
X514972Y301996D03*
Y290296D03*
Y286396D03*
Y294196D03*
X525111Y284447D03*
X531871Y288347D03*
Y292245D03*
X528491Y294196D03*
X525111Y300047D03*
X531871D03*
X521731Y301996D03*
X528491Y286396D03*
Y298096D03*
X535251Y294196D03*
X542011D03*
Y298096D03*
X538631Y292245D03*
Y288347D03*
Y284447D03*
X531871Y303947D03*
X535251Y301996D03*
X531871Y311747D03*
Y307847D03*
X535251Y309797D03*
X514972Y321496D03*
Y317596D03*
Y329296D03*
Y325396D03*
X518352Y319547D03*
Y323446D03*
Y315647D03*
X521731Y317596D03*
Y325396D03*
X518352Y327347D03*
X525111Y315647D03*
X528491Y317596D03*
X531871Y319547D03*
X542011Y286396D03*
X531871Y284447D03*
X542011Y290296D03*
X535251Y286396D03*
X484552Y346847D03*
X555531Y216196D03*
X558911Y222047D03*
X557000Y206800D03*
X548771Y212296D03*
X552151Y214247D03*
X562591Y220096D03*
X547800Y201400D03*
X545391Y210346D03*
Y222047D03*
X552151Y218147D03*
X555531Y220096D03*
X548771D03*
X545391Y218147D03*
Y214247D03*
X552151Y222047D03*
X548771Y216196D03*
X552151Y225947D03*
Y233746D03*
X548771Y235696D03*
X558911Y229847D03*
X552151D03*
X564084Y235685D03*
X545391Y225947D03*
Y233746D03*
X552151Y241547D03*
X548771Y239596D03*
X552151Y249347D03*
X555531Y247396D03*
X562591Y251296D03*
X548771Y243496D03*
X552151Y257147D03*
X562591Y255196D03*
X548771D03*
Y266896D03*
X558911Y264947D03*
X563800Y275900D03*
X559211Y280547D03*
X548771Y278596D03*
X558911Y272747D03*
X555531Y274696D03*
X552151Y261047D03*
X545391Y272747D03*
Y280547D03*
Y264947D03*
Y268847D03*
Y245447D03*
Y253247D03*
X548771Y259096D03*
X545391Y241547D03*
X548771Y247396D03*
X545391Y249347D03*
Y257147D03*
Y261047D03*
Y229847D03*
X548771Y231797D03*
X562616Y223996D03*
X555531Y259096D03*
Y266896D03*
X558911Y268847D03*
X552151D03*
Y276646D03*
X555531Y278596D03*
Y282496D03*
X562640Y231735D03*
X555531Y243496D03*
X552151Y253247D03*
X558911Y249347D03*
Y257147D03*
Y225947D03*
X555531Y262996D03*
X552151Y264947D03*
X555531Y270796D03*
X552151Y272747D03*
X548771Y274696D03*
X552151Y280547D03*
X562630Y227896D03*
X558911Y241547D03*
X555531Y251296D03*
X558911Y253247D03*
X555531Y255196D03*
Y227896D03*
Y223996D03*
X548771D03*
X552151Y284447D03*
X548771Y286396D03*
X552151Y288347D03*
Y296147D03*
X545391D03*
Y288347D03*
Y292245D03*
Y300047D03*
Y303947D03*
Y284447D03*
X560884Y290296D03*
X555831Y294196D03*
X552151Y292245D03*
X740650Y164800D03*
X735600Y164900D03*
X458643Y338746D03*
X467653Y340996D03*
X469913Y321496D03*
X463671Y319386D03*
X477792Y362447D03*
X457513D03*
X481172Y372197D03*
X464273Y366347D03*
X474413Y372197D03*
X471033Y366347D03*
X467653Y372197D03*
X474413Y364396D03*
X464273Y350747D03*
X471033D03*
Y358547D03*
X464273D03*
X467653Y368296D03*
Y348796D03*
X460893Y372197D03*
Y364396D03*
Y352696D03*
X457513Y354647D03*
Y358547D03*
Y346847D03*
X481172Y391696D03*
X477792Y389747D03*
X457513D03*
X471033Y393647D03*
X460893Y395595D03*
X481172Y395596D03*
X464273Y401447D03*
X471033D03*
X460893Y391696D03*
X457513Y385847D03*
Y381947D03*
X460893Y379996D03*
X477792Y381947D03*
X481172Y379996D03*
X474413Y391696D03*
X464273Y385847D03*
X471033D03*
X464273Y393647D03*
X474413Y379996D03*
X471033Y378047D03*
X467653Y376096D03*
X464273Y378047D03*
Y397546D03*
Y405347D03*
X477792Y385847D03*
X464273Y381947D03*
Y389747D03*
X474413Y383896D03*
Y387796D03*
X460893Y383896D03*
Y387796D03*
X471033Y381947D03*
Y389747D03*
X481172Y383896D03*
Y387796D03*
X467653Y379996D03*
Y391696D03*
Y383896D03*
Y387796D03*
X474413Y368296D03*
Y376096D03*
X481172Y364396D03*
X471033Y370247D03*
Y374146D03*
X481172Y368296D03*
Y376096D03*
X477792Y370247D03*
Y378047D03*
Y366347D03*
Y374146D03*
X464273Y370247D03*
Y374146D03*
X460893Y368296D03*
Y376096D03*
X464273Y354647D03*
Y362447D03*
X474413Y360496D03*
X460893Y356596D03*
Y360496D03*
X471033Y354647D03*
Y362447D03*
X457513Y370247D03*
X467653Y356596D03*
X457513Y378047D03*
X467653Y364396D03*
X457513Y366347D03*
X467653Y352696D03*
X457513Y374146D03*
X467653Y360496D03*
X504832Y342947D03*
X501452Y344896D03*
X511592Y339047D03*
Y335147D03*
X498072Y342947D03*
X508212Y337096D03*
X504832Y335147D03*
Y339047D03*
X501452Y340996D03*
X514972Y337096D03*
X518352Y339047D03*
Y342947D03*
X542011Y321496D03*
X531871Y335147D03*
X525111D03*
X528491Y337096D03*
X525111Y342947D03*
X535251Y329296D03*
X538631Y335147D03*
Y339047D03*
X491312Y370247D03*
X498072Y366347D03*
X494692Y372197D03*
X504832Y366347D03*
X501452Y368296D03*
X487932D03*
X498072Y362447D03*
X491312D03*
X494692Y360496D03*
X504832Y354647D03*
X491312Y366347D03*
X487932Y372197D03*
X484552Y370247D03*
Y366347D03*
X487932Y364396D03*
X494692D03*
X501452D03*
X498072Y350747D03*
Y346847D03*
X501452Y360496D03*
X498072Y358547D03*
Y354647D03*
X508212Y352696D03*
Y360496D03*
X504832Y346847D03*
Y358547D03*
X501452Y356596D03*
Y348796D03*
Y352696D03*
X511592Y370247D03*
X484552Y393647D03*
Y385847D03*
X498072Y393647D03*
X494692Y391696D03*
X491312Y385847D03*
X498072D03*
X508212Y387796D03*
X501452Y391696D03*
Y395597D03*
X491312Y389747D03*
X484552Y405347D03*
X504832Y381947D03*
Y378047D03*
X501452Y379996D03*
X511592Y378047D03*
Y397546D03*
X491312Y378047D03*
X484552D03*
X487932Y376096D03*
X491312Y381947D03*
Y374146D03*
X498072Y397546D03*
X487932Y403396D03*
Y399496D03*
X491312Y397546D03*
X487932Y395597D03*
X514972Y372197D03*
Y356596D03*
X521731Y360496D03*
Y356596D03*
Y348796D03*
X518352Y362447D03*
X521731Y372197D03*
X518352Y370247D03*
X525111Y354647D03*
X531871Y346847D03*
X535251Y356596D03*
X538631Y366347D03*
X542011Y368296D03*
X528491Y364396D03*
X542011Y360496D03*
Y348796D03*
X514972Y403396D03*
Y379996D03*
X531871Y374146D03*
X521731Y399496D03*
X518352Y397546D03*
Y389747D03*
X535251Y383896D03*
X525111Y381947D03*
X538631Y393647D03*
Y378047D03*
X528491Y403396D03*
X531871Y401447D03*
Y389747D03*
X525111Y393647D03*
X542011Y376096D03*
X484552Y381947D03*
Y389747D03*
X494692Y395597D03*
Y399496D03*
X491312Y401447D03*
Y393647D03*
X487932Y379996D03*
Y391696D03*
Y383896D03*
Y387796D03*
X484552Y374146D03*
X555831Y309797D03*
Y305896D03*
X548771Y313696D03*
X561971Y317320D03*
X548771Y325396D03*
X558911Y335147D03*
X555531Y333196D03*
X558911Y342947D03*
X562591Y333196D03*
X548771Y340996D03*
X562591Y344896D03*
X561966Y325502D03*
X559211Y319547D03*
X552151Y323446D03*
X545391Y319547D03*
Y335147D03*
Y331247D03*
Y315647D03*
X552151Y350747D03*
X559212Y370247D03*
X548771Y368296D03*
X562591Y352696D03*
X563200Y356596D03*
X545391Y354647D03*
Y346847D03*
Y366347D03*
Y358547D03*
X559212Y374146D03*
X555531Y387797D03*
X559212Y381947D03*
X552151Y378047D03*
X545391Y397546D03*
Y385847D03*
X632500Y238500D03*
Y235000D03*
X632532Y241717D03*
X633308Y263808D03*
X627529Y280441D03*
X618279Y251393D03*
X624500Y240500D03*
X637681Y337390D03*
X658500Y284500D03*
X648900Y336600D03*
X646520Y297400D03*
X664267Y292668D03*
X637143Y322000D03*
X637561Y317000D03*
X646700Y308850D03*
X658900Y339150D03*
X654600Y296000D03*
X662238Y296146D03*
X659694Y351206D03*
X664194D03*
X649194D03*
X654194D03*
X725725Y241560D03*
X697255Y267098D03*
X700400Y257200D03*
X710272Y281911D03*
X706800Y281900D03*
X704500Y252500D03*
X700800Y261300D03*
X690130Y277380D03*
X715200Y258900D03*
X704090Y256080D03*
X689960Y260500D03*
X677800Y254100D03*
X667700Y275600D03*
X710700Y260200D03*
X710675Y263425D03*
X679300Y261700D03*
X712400Y324400D03*
X711900Y327700D03*
X697120Y305349D03*
Y300349D03*
X704404Y315875D03*
Y310875D03*
X697521Y325500D03*
Y320500D03*
X724000Y291700D03*
X686140Y298260D03*
X695000Y289500D03*
X686600Y335600D03*
X670800Y292600D03*
X667900Y339000D03*
X697352Y335500D03*
Y330500D03*
X705800Y301600D03*
X674700Y339200D03*
X688100Y308600D03*
X688924Y288147D03*
X674469Y287375D03*
X674194Y358467D03*
X683417Y364972D03*
X669194Y351206D03*
X674194D03*
X679194D03*
X684194D03*
X695700Y346300D03*
X731662Y247716D03*
X730000Y254675D03*
X737750Y298894D03*
X729405Y290725D03*
X737912Y315500D03*
X736000Y303400D03*
X732000Y380000D03*
X797000Y404700D03*
X805600Y403900D03*
X683800Y24856D03*
X717720Y23279D03*
X710327Y-11968D03*
X692400Y20800D03*
X756100Y36200D03*
X755500Y46700D03*
X751708Y73800D03*
X753100Y92111D03*
X751600Y41000D03*
X755500Y55200D03*
X769100Y102900D03*
X752900Y101000D03*
X907086Y104284D03*
X890204D03*
X913779D03*
X883661D03*
X920472D03*
X927015D03*
X1035900Y98800D03*
X1138242Y104314D03*
X1144685D03*
X1161632D03*
X1168075D03*
X1174742D03*
X1181346D03*
X1198228D03*
X1204921D03*
X1277660Y109450D03*
X1237400Y103100D03*
X1277600Y106200D03*
X1268576Y117788D03*
X1341400Y46100D03*
X1336900Y89896D03*
X1344000Y83000D03*
X1330300Y83500D03*
X1327168Y61483D03*
X1338500Y96000D03*
X1343500Y87500D03*
X1335120Y94450D03*
X1357400Y-19800D03*
X1385608Y-17485D03*
X1388294Y-5675D03*
X1389523Y4966D03*
X1527700Y6963D03*
X1495611Y13466D03*
X1485242Y4589D03*
X1589500Y-600D03*
X1554573Y37216D03*
X1564023D03*
X1542179Y39695D03*
X1545572Y38188D03*
X1546370Y84180D03*
X1541421Y106742D03*
X1646400Y13400D03*
X1619100Y6500D03*
X1672427Y9700D03*
X1675800Y4100D03*
X1715259Y35602D03*
X1680033Y-16711D03*
X1702513Y79885D03*
X1692573Y85833D03*
X1669350Y69962D03*
X1700710Y73292D03*
X1693900Y73300D03*
X1678627Y54616D03*
X1684248Y56746D03*
X1690500Y73950D03*
X1715100Y70500D03*
X1681116Y238614D03*
X1715078Y250231D03*
X1679145Y461950D03*
X1753903Y22116D03*
X1771459Y52695D03*
X1765900Y83700D03*
X1768450Y77376D03*
X1720600Y70200D03*
X1748500Y79500D03*
X1725474Y69250D03*
X1750400Y47400D03*
X1720500Y52440D03*
X1757998Y73637D03*
X1767250Y99500D03*
Y104500D03*
X1772244Y232106D03*
X1762795D03*
X1763300Y250100D03*
X1719080Y236152D03*
X1718820Y249032D03*
X1727896Y246175D03*
X1734663Y467005D03*
X1728700Y470200D03*
X1832449Y-8950D03*
X1782371Y26832D03*
X1828824Y3699D03*
X1819800Y2100D03*
X1819837Y21700D03*
X1788200Y93000D03*
Y89000D03*
X1834300Y41100D03*
X1788200Y85000D03*
X1827000Y87000D03*
X1824240Y83680D03*
X1799438Y44328D03*
X1827100Y81600D03*
X1788216Y59197D03*
X1821350Y98270D03*
X1820648Y155537D03*
X1816348D03*
X1818500Y159500D03*
X1800000Y132627D03*
X1811348Y143448D03*
X1801366Y151937D03*
X1796059Y104402D03*
X1803400Y114000D03*
X1808226Y136171D03*
X1830316Y102163D03*
X1816348Y163437D03*
X1839500Y212700D03*
X1832274Y209734D03*
X1828950Y209600D03*
X1820648Y163437D03*
X1827565Y179174D03*
X1824200Y176900D03*
X1787000Y175500D03*
X1833629Y170807D03*
X1810040Y232106D03*
X1800787Y447943D03*
X1856873Y91200D03*
X1856778Y87397D03*
X1860815Y91184D03*
X1847000Y86500D03*
X1842250Y84000D03*
Y90750D03*
X1887300Y121500D03*
X1850700Y156000D03*
X1875700Y115700D03*
Y121500D03*
X1881500Y115700D03*
Y121500D03*
Y127300D03*
X1887300D03*
X1854663Y158248D03*
X1846663Y153748D03*
Y158248D03*
X1856700Y110167D03*
X1887300Y115700D03*
X1875700Y127300D03*
X1863908Y140992D03*
X1857110Y113600D03*
X1866606Y109967D03*
X1861932Y146431D03*
X1900740Y178720D03*
X1900700Y172990D03*
Y167290D03*
X1863750Y163750D03*
X1846163Y168448D03*
X1868375Y171900D03*
X1868843Y207920D03*
X1884340Y217866D03*
X1840900Y179700D03*
X1845700D03*
X1872100Y207900D03*
X1861243Y183100D03*
X1858686Y180377D03*
X1858500Y200100D03*
X1864000Y184900D03*
X1878789Y213663D03*
X1885465Y166285D03*
X1855000Y167100D03*
X1840149Y244425D03*
X1843449D03*
X1854374Y248790D03*
X1882677Y447930D03*
X1863137Y452710D03*
X1875900Y453600D03*
X1906438Y-15968D03*
X1911231Y137097D03*
X1905074Y198163D03*
X1906440Y178720D03*
X1906500Y173100D03*
X1906400Y167290D03*
X1912190Y178870D03*
X1912230Y167330D03*
Y173030D03*
X1917568Y201215D03*
X1925400Y196300D03*
X1929090Y193190D03*
X1929000Y445800D03*
X1942000Y440500D03*
X1938410Y490650D03*
X1947380Y482450D03*
X1929480Y472880D03*
X1970270Y474640D03*
X722050Y221150D03*
X718300Y227400D03*
X742937Y218574D03*
X771232Y214033D03*
X742897Y229573D03*
X760304Y235827D03*
X768560Y244055D03*
X769019Y276400D03*
X762616Y270113D03*
X761480Y242720D03*
X771650Y246451D03*
Y278451D03*
X759700Y232000D03*
X756114Y316209D03*
X762842Y302434D03*
X765730Y335064D03*
X771700Y342501D03*
X757956Y328095D03*
X758952Y384100D03*
X763333Y400212D03*
X765007Y348363D03*
X712600Y571900D03*
X716300Y569400D03*
X727400Y571300D03*
X727106Y586550D03*
X727000Y606600D03*
X779771Y510114D03*
X773228D03*
X769881Y517900D03*
X769818Y529200D03*
X763544Y522236D03*
X769500Y510100D03*
X755000Y574800D03*
X752500Y585150D03*
X773228Y536999D03*
X763677Y547783D03*
X776188Y530949D03*
X782567Y531100D03*
X779921Y537049D03*
X773228Y547914D03*
X779771D03*
X769881Y555700D03*
X773228Y574799D03*
X782567Y568900D03*
X769700Y566900D03*
X776188Y568749D03*
X779921Y574849D03*
X773228Y585714D03*
X779771D03*
X769500Y536983D03*
X755000Y566000D03*
X769500Y547900D03*
Y574700D03*
Y585700D03*
X732600Y573950D03*
X779921Y612649D03*
X773228Y612599D03*
X755000Y614500D03*
X769700Y604900D03*
X776188Y606549D03*
X782567Y606700D03*
X739307Y598850D03*
X755800Y604600D03*
X769500Y612583D03*
X733032Y604000D03*
X816582Y510114D03*
X810039D03*
X796653D03*
X803346D03*
X846850D03*
X840157D03*
X833464D03*
X816582Y537049D03*
Y547914D03*
X810039Y536999D03*
X806692Y530949D03*
X812999D03*
X803346Y537049D03*
X796653D03*
X799999Y530949D03*
X810039Y547914D03*
X796653D03*
X803346D03*
X810039Y585714D03*
X806692Y568749D03*
X810039Y574799D03*
X812999Y568749D03*
X803346Y585714D03*
X796653D03*
X799999Y568749D03*
X796653Y574849D03*
X803346D03*
X816582Y585714D03*
Y574849D03*
X819378Y531100D03*
X836810Y530949D03*
X833464Y537049D03*
X846850Y547914D03*
X833464D03*
X840157D03*
X846850Y536999D03*
X843503Y530949D03*
X849810D03*
X840157Y537049D03*
X849810Y568749D03*
X819378Y568900D03*
X840157Y585714D03*
X833464D03*
X840157Y574849D03*
X833464D03*
X836810Y568749D03*
X846850Y585714D03*
Y574799D03*
X843503Y568749D03*
X846850Y612599D03*
X840157Y612649D03*
X833464D03*
X810039Y612599D03*
X803346Y612649D03*
X796653D03*
X816582D03*
X806692Y606549D03*
X812999D03*
X799999D03*
X819378Y606700D03*
X843503Y606549D03*
X849810D03*
X836810D03*
X876968Y510114D03*
X870275D03*
X853393D03*
X890204D03*
X913779D03*
X883661D03*
X907086D03*
X873621Y530949D03*
X876968Y537049D03*
Y547914D03*
X870275D03*
X853393D03*
X870275Y537049D03*
X853543D03*
X856189Y531100D03*
X853393Y585714D03*
X870275D03*
X873621Y568749D03*
X876968Y574849D03*
Y585714D03*
X870275Y574849D03*
X853543D03*
X856189Y568900D03*
X890354Y537049D03*
X893000Y531100D03*
X913779Y537049D03*
X910432Y530949D03*
X907086Y537049D03*
X886621Y530949D03*
X883661Y536999D03*
X880314Y530949D03*
X883661Y547914D03*
X890204D03*
X913779D03*
X907086D03*
X880314Y568749D03*
X886621D03*
X883661Y574799D03*
Y585714D03*
X890354Y574849D03*
X893000Y568900D03*
X890204Y585714D03*
X913779Y574849D03*
X910432Y568749D03*
X913779Y585714D03*
X907086Y574849D03*
Y585714D03*
X890354Y612649D03*
X883661Y612599D03*
X907086Y612649D03*
X870275D03*
X876968D03*
X853543D03*
X856189Y606700D03*
X873621Y606549D03*
X913779Y612449D03*
X910432Y606549D03*
X893000Y606700D03*
X880314Y606549D03*
X886621D03*
X920472Y510114D03*
X927015D03*
X950590D03*
X943897D03*
X957774Y512794D03*
X957806Y528863D03*
X957283Y518057D03*
X970669Y529014D03*
X974015D03*
X929811Y531100D03*
X917125Y530949D03*
X927015Y537049D03*
X923432Y530949D03*
X920472Y536999D03*
X927015Y547914D03*
X920472D03*
X929811Y568900D03*
X920472Y574799D03*
X927015Y585714D03*
X920472D03*
X917125Y568749D03*
X923432D03*
X927015Y574849D03*
X957600Y533100D03*
X970942D03*
X957701Y552000D03*
X970731D03*
X950590Y537049D03*
X957283Y536957D03*
X953936Y530949D03*
X957283Y548200D03*
X950590Y547914D03*
X947243Y530949D03*
X943897Y537049D03*
Y547914D03*
X957600Y570900D03*
X970942D03*
X970731Y589800D03*
X950590Y574849D03*
Y585714D03*
X957283Y574757D03*
X953936Y568749D03*
X943897Y574849D03*
X947243Y568749D03*
X943897Y585714D03*
X957283Y555857D03*
X957592Y566743D03*
X974015Y536957D03*
X960629D03*
X970669Y555857D03*
Y566814D03*
X974015Y555857D03*
Y566814D03*
Y547914D03*
Y574757D03*
X963976Y566814D03*
X960629Y574757D03*
X963976Y555857D03*
X960629Y547914D03*
X974015Y585714D03*
X960629D03*
X967322Y536957D03*
Y574757D03*
Y547914D03*
Y585714D03*
X923432Y606549D03*
X917125D03*
X927015Y612449D03*
X920472Y612399D03*
X929811Y606700D03*
X953936Y606549D03*
X957283Y611600D03*
X950590Y612249D03*
X947243Y606549D03*
X943897Y612249D03*
X957765Y607220D03*
X970669Y593657D03*
X974015D03*
X963976D03*
X1013500Y529200D03*
X980708Y529014D03*
X1004133Y529022D03*
X1000787D03*
X994094D03*
X990748D03*
X984054Y529014D03*
X983900Y533100D03*
Y552000D03*
Y570900D03*
Y589800D03*
X1026500Y577500D03*
X977362Y536957D03*
X984055D03*
X1004134D03*
X997441D03*
X994094D03*
X987401D03*
X977362Y547914D03*
Y574757D03*
X984054Y547914D03*
X984055Y574757D03*
X980708Y555857D03*
Y566814D03*
X1004134Y555857D03*
X1004133Y566822D03*
Y547922D03*
X1004134Y574757D03*
X1000787Y555857D03*
Y566822D03*
X997441Y547922D03*
Y574757D03*
X994094Y547922D03*
Y574757D03*
Y555857D03*
Y566822D03*
X987401Y547914D03*
Y574757D03*
X990748Y555857D03*
Y566822D03*
X984055Y555857D03*
X984054Y566814D03*
X977362Y585714D03*
X984054D03*
X1004133Y585722D03*
X997441D03*
X994094D03*
X987401Y585714D03*
X980708Y593657D03*
X1004134D03*
X1000787D03*
X994094D03*
X990748D03*
X984055D03*
X1054331Y529022D03*
X1071064D03*
X1057792Y552000D03*
Y533100D03*
Y570900D03*
Y589800D03*
X1070976Y552000D03*
Y533100D03*
X1084003Y532904D03*
X1083116Y552000D03*
X1098300Y553100D03*
X1098118Y549843D03*
X1070976Y570900D03*
X1070242Y589800D03*
X1083116Y570900D03*
X1083108Y589800D03*
X1097899Y574773D03*
X1097834Y569200D03*
X1071064Y547922D03*
Y585722D03*
X1050985Y536957D03*
X1087797D03*
X1094490D03*
X1054331D03*
X1077757D03*
X1064371D03*
X1084450D03*
X1054331Y555857D03*
Y566822D03*
X1050984Y547922D03*
X1050985Y574757D03*
X1087797Y547922D03*
Y574757D03*
X1064371Y566822D03*
X1094488D03*
X1094490Y574757D03*
X1064371Y555857D03*
X1081102Y555842D03*
X1094488Y555859D03*
Y547922D03*
X1047637Y555842D03*
X1054331Y547922D03*
Y574757D03*
X1077757Y547922D03*
Y574757D03*
X1064371Y547922D03*
Y574757D03*
X1071064Y555857D03*
Y566822D03*
X1057677Y555842D03*
X1084450Y547922D03*
Y574757D03*
X1087797Y566822D03*
X1074409Y555842D03*
X1087795Y555859D03*
X1044292Y574757D03*
X1050985Y585722D03*
X1087797D03*
X1094488D03*
X1054331D03*
X1077757D03*
X1064371D03*
X1084450D03*
X1061024Y536957D03*
Y574757D03*
Y547922D03*
Y585722D03*
X1097352Y607220D03*
X1071062Y612560D03*
X1054331Y593657D03*
X1064371D03*
X1081102Y593642D03*
X1094488Y593659D03*
X1047637Y593642D03*
X1071064Y593657D03*
X1057677Y593642D03*
X1087795Y593659D03*
X1101181Y510114D03*
X1107724D03*
X1124606D03*
X1131299D03*
X1137992D03*
X1144535D03*
X1104141Y530949D03*
X1107724Y547914D03*
X1101181D03*
X1110520Y531100D03*
X1107874Y537049D03*
X1104141Y568749D03*
X1101181Y585714D03*
X1107724D03*
X1107874Y574849D03*
X1110520Y568900D03*
X1101181Y574799D03*
X1137992Y547914D03*
X1144535D03*
X1131299D03*
X1124606D03*
X1131299Y537049D03*
X1124606D03*
X1127952Y530949D03*
X1147331Y531100D03*
X1134645Y530949D03*
X1140952D03*
X1137992Y536999D03*
X1144685Y537049D03*
X1134645Y568749D03*
X1137992Y585714D03*
X1144535D03*
X1140952Y568749D03*
X1137992Y574799D03*
X1144685Y574849D03*
X1147331Y568900D03*
X1131299Y585714D03*
X1124606D03*
X1131299Y574849D03*
X1127952Y568749D03*
X1124606Y574849D03*
X1137992Y612599D03*
X1144685Y612649D03*
X1124606D03*
X1131299D03*
X1107874D03*
X1110520Y606700D03*
X1104141Y606549D03*
X1147331Y606700D03*
X1134645Y606549D03*
X1140952D03*
X1127952D03*
X1101181Y612599D03*
X1168110Y510114D03*
X1161417D03*
X1174803D03*
X1181346D03*
X1211614D03*
X1218157D03*
X1204921D03*
X1198228D03*
X1161417Y547914D03*
X1168110D03*
X1174803D03*
X1177763Y530949D03*
X1168110Y537049D03*
X1164763Y530949D03*
X1161417Y537049D03*
X1171456Y530949D03*
X1174803Y536999D03*
Y574799D03*
X1161417Y574849D03*
X1171456Y568749D03*
X1168110Y585714D03*
X1161417D03*
X1168110Y574849D03*
X1164763Y568749D03*
X1174803Y585714D03*
X1177763Y568749D03*
X1181496Y537049D03*
X1181346Y547914D03*
X1211614Y536999D03*
X1214574Y530949D03*
X1184142Y531100D03*
X1198228Y547914D03*
X1204921D03*
X1201574Y530949D03*
X1204921Y537049D03*
X1198228D03*
X1218307D03*
X1220953Y531100D03*
X1211614Y547914D03*
X1208267Y530949D03*
X1218157Y547914D03*
X1181346Y585714D03*
X1181496Y574849D03*
X1220953Y568900D03*
X1218157Y585714D03*
X1218307Y574849D03*
X1208267Y568749D03*
X1214574D03*
X1211614Y574799D03*
Y585714D03*
X1184142Y568900D03*
X1198228Y585714D03*
Y574849D03*
X1204921Y585714D03*
Y574849D03*
X1201574Y568749D03*
X1181496Y612649D03*
X1218307D03*
X1211614Y612599D03*
X1204921Y612649D03*
X1198228D03*
X1168110D03*
X1161417D03*
X1174803Y612599D03*
X1171456Y606549D03*
X1164763D03*
X1177763D03*
X1220953Y606700D03*
X1214574Y606549D03*
X1208267D03*
X1184142Y606700D03*
X1201574Y606549D03*
X1241732Y510114D03*
X1269000Y514700D03*
X1251771Y528899D03*
X1248425D03*
X1251771Y517999D03*
X1248425Y510157D03*
X1235039Y510114D03*
X1241732Y547914D03*
Y537049D03*
X1238385Y530949D03*
X1269800Y532978D03*
X1248425Y537049D03*
X1245078Y530949D03*
X1248425Y547957D03*
X1241732Y574849D03*
Y585714D03*
X1238385Y568749D03*
X1268500Y555800D03*
X1248425Y585757D03*
Y574849D03*
Y566699D03*
X1245078Y568749D03*
X1235039Y537049D03*
Y547914D03*
Y585714D03*
Y574849D03*
X1273200Y582200D03*
X1277200Y539100D03*
X1241732Y612649D03*
X1238385Y606549D03*
X1248425Y612649D03*
X1251771Y604499D03*
X1248425D03*
X1245078Y606549D03*
X1251771Y593599D03*
X1235039Y612649D03*
X1316100Y543400D03*
X1307600Y620100D03*
X1296295Y615596D03*
X1301384Y618119D03*
X755500Y8700D03*
X779771Y9114D03*
X773228D03*
Y-1801D03*
X779921Y-1751D03*
X776188Y-7851D03*
X769881Y-9901D03*
X782567Y-7700D03*
X769881Y27899D03*
X782567Y30100D03*
X769881Y16839D03*
X779921Y35983D03*
X773228D03*
X776188Y29949D03*
X760100Y17255D03*
X769881Y9157D03*
X773228Y46914D03*
X779771D03*
X776188Y67749D03*
X769881Y66000D03*
X782567Y67900D03*
X769881Y54839D03*
X773228Y84714D03*
X779771D03*
X779921Y73849D03*
X773228Y73799D03*
X769881Y46957D03*
X803346Y-1751D03*
X810039Y-1801D03*
X812999Y-7851D03*
X806692D03*
X799999D03*
X816582Y9114D03*
X796653D03*
X810039D03*
X803346D03*
X816732Y-1751D03*
X796653D03*
X799999Y29949D03*
X810039Y35999D03*
X803346Y36049D03*
X806692Y29949D03*
X812999D03*
X816732Y36049D03*
X796653D03*
X833464Y9114D03*
X840157D03*
X819378Y-7700D03*
X843503Y-7851D03*
X849810D03*
X836810D03*
X846850Y-1801D03*
X833464Y-1751D03*
X840157D03*
X846850Y9114D03*
X819378Y30100D03*
X846850Y35999D03*
X833464Y36049D03*
X840157D03*
X836810Y29949D03*
X849810D03*
X843503D03*
X796653Y46914D03*
X816582D03*
X799999Y67749D03*
X812999D03*
X806692D03*
X803346Y46914D03*
X810039D03*
X816582Y73849D03*
X796653D03*
X810039Y73799D03*
X803346Y73849D03*
X816582Y84714D03*
X803346D03*
X810039D03*
X796653D03*
X819378Y67900D03*
X833464Y46914D03*
X840157D03*
X836810Y67749D03*
X843503D03*
X849810D03*
X846850Y46914D03*
Y73799D03*
Y84714D03*
X840157Y73849D03*
X833464D03*
X840157Y84714D03*
X833464D03*
X870275Y9114D03*
X876968D03*
Y-1751D03*
X873621Y-7851D03*
X856189Y-7700D03*
X853543Y-1751D03*
X870275D03*
X853393Y9114D03*
X870275Y36049D03*
X876968D03*
X873621Y29949D03*
X856189Y30100D03*
X853543Y36049D03*
X910432Y-7851D03*
X883661Y-1801D03*
X880314Y-7851D03*
X886621D03*
X913779Y-1751D03*
X907086D03*
X890354D03*
X893000Y-7700D03*
X883661Y9114D03*
X913779D03*
X907086D03*
X890204D03*
X910432Y29949D03*
X893000Y30100D03*
X883661Y35999D03*
X886621Y29949D03*
X880314D03*
X890354Y36049D03*
X913779D03*
X907086D03*
X876968Y46914D03*
X873621Y67749D03*
X856189Y67900D03*
X853393Y46914D03*
X870275D03*
X876968Y84714D03*
Y73849D03*
X870275D03*
X853543D03*
X870275Y84714D03*
X853393D03*
X910432Y67749D03*
X893000Y67900D03*
X890204Y46914D03*
X886621Y67749D03*
X880314D03*
X883661Y46914D03*
X913779D03*
X883661Y73799D03*
X907086Y84714D03*
X913779Y73849D03*
Y84714D03*
X907086Y46914D03*
X890204Y84714D03*
X890354Y73849D03*
X907086D03*
X883661Y84714D03*
X923432Y-7851D03*
X929811Y-7700D03*
X917125Y-7851D03*
X927165Y-1751D03*
X920472Y-1801D03*
X927015Y9114D03*
X920472D03*
Y35999D03*
X923432Y29949D03*
X917125D03*
X927165Y36049D03*
X929811Y30100D03*
X947243Y-7851D03*
X950590Y-1751D03*
X957283Y-1843D03*
X953936Y-7851D03*
X943897Y-1751D03*
Y9114D03*
X950590D03*
X957283Y9300D03*
X953936Y29949D03*
X950590Y36049D03*
X957600Y13200D03*
X957700Y32100D03*
X970800Y13200D03*
X970942Y32100D03*
X947243Y29949D03*
X943897Y36049D03*
X957283Y35957D03*
X957765Y-7180D03*
X957283Y28014D03*
Y17057D03*
X970669Y28014D03*
X974015D03*
Y35957D03*
X963976Y28014D03*
X960629Y35957D03*
X970669Y17057D03*
X974015D03*
Y9114D03*
X963976Y17057D03*
X960629Y9114D03*
X967322Y35957D03*
Y9114D03*
X923432Y67749D03*
X929811Y67900D03*
X917125Y67749D03*
X927015Y73849D03*
X920472Y73799D03*
Y84714D03*
Y46914D03*
X927015D03*
Y84714D03*
X957558Y50729D03*
X953936Y67749D03*
X950590Y46914D03*
X970800Y50860D03*
X947243Y67749D03*
X943897Y46914D03*
X970942Y69900D03*
X943897Y84714D03*
Y73849D03*
X950590D03*
Y84714D03*
X957774Y87394D03*
X957200Y73800D03*
X957283Y54857D03*
X970669Y65814D03*
X974015D03*
Y73757D03*
X963976Y65814D03*
X970669Y54857D03*
X974015D03*
Y46914D03*
X963976Y54857D03*
X960629Y46914D03*
X967322Y73757D03*
Y46914D03*
X983900Y13200D03*
Y32100D03*
X1026700Y1700D03*
X977362Y35957D03*
X984055D03*
X980708Y28014D03*
X1004133Y28022D03*
X1004134Y35957D03*
X1000787Y28022D03*
X997441Y35957D03*
X994094D03*
Y28022D03*
X987401Y35957D03*
X990748Y28022D03*
X984054Y28014D03*
X977362Y9114D03*
X984054D03*
X980708Y17057D03*
X1004134D03*
X1004133Y9122D03*
X1000787Y17057D03*
X997441Y9122D03*
X994094D03*
Y17057D03*
X987401Y9114D03*
X990748Y17057D03*
X984055D03*
X983900Y51000D03*
Y69900D03*
X1014350Y73000D03*
X1030400Y56500D03*
X1031600Y42900D03*
X977362Y73757D03*
X984055D03*
X980708Y65814D03*
X1004133Y65822D03*
X1004134Y73757D03*
X1000787Y65822D03*
X997441Y73757D03*
X994094D03*
Y65822D03*
X987401Y73757D03*
X990748Y65822D03*
X984054Y65814D03*
X977362Y46914D03*
X984054D03*
X980708Y54857D03*
X1004134D03*
X1004133Y46922D03*
X1000787Y54857D03*
X997441Y46922D03*
X994094D03*
Y54857D03*
X987401Y46914D03*
X990748Y54857D03*
X984055D03*
X1043800Y-9700D03*
X1057792Y13200D03*
Y32100D03*
X1097352Y-7180D03*
X1083116Y13200D03*
Y32100D03*
X1097900Y31900D03*
X1070976Y13200D03*
Y32100D03*
X1097834Y28100D03*
X1071062Y-1817D03*
X1071064Y9122D03*
X1054331Y28022D03*
X1050985Y35957D03*
X1087797D03*
X1064371Y28022D03*
X1094488D03*
X1094490Y35957D03*
X1054331D03*
X1077757D03*
X1064371D03*
X1071064Y28022D03*
X1084450Y35957D03*
X1087797Y28022D03*
X1044292Y35957D03*
X1054331Y17057D03*
X1050985Y9122D03*
X1087797D03*
X1064371Y17057D03*
X1081102Y17042D03*
X1094488Y17059D03*
Y9122D03*
X1054331D03*
X1077757D03*
X1064371D03*
X1071064Y17057D03*
X1057677Y17042D03*
X1084450Y9122D03*
X1074409Y17042D03*
X1087795Y17059D03*
X1061024Y35957D03*
Y9122D03*
X1057792Y51000D03*
Y69900D03*
X1083116Y51000D03*
X1098100D03*
X1070976D03*
X1083116Y69900D03*
X1070976D03*
X1098300Y89900D03*
X1044100Y54700D03*
X1071064Y46922D03*
Y73757D03*
X1054331Y65822D03*
X1050985Y73757D03*
X1087797D03*
X1064371Y65822D03*
X1094488D03*
X1054331Y73757D03*
X1077757D03*
X1064371D03*
X1071064Y65822D03*
X1084450Y73757D03*
X1087797Y65822D03*
X1054331Y54857D03*
X1050985Y46922D03*
X1087797D03*
X1064371Y54857D03*
X1081102Y54842D03*
X1094488Y54859D03*
Y46922D03*
X1047637Y54842D03*
X1054331Y46922D03*
X1077757D03*
X1064371D03*
X1071064Y54857D03*
X1057677Y54842D03*
X1084450Y46922D03*
X1074409Y54842D03*
X1087795Y54859D03*
X1061024Y73757D03*
Y46922D03*
X1104141Y-7851D03*
X1110520Y-7700D03*
X1107874Y-1751D03*
X1101181Y-1801D03*
X1107724Y9114D03*
X1101181D03*
X1107874Y36049D03*
X1110520Y30100D03*
X1104141Y29949D03*
X1131299Y9114D03*
X1124606D03*
X1137992D03*
X1144535D03*
X1127952Y-7851D03*
X1124606Y-1751D03*
X1131299D03*
X1134645Y-7851D03*
X1147331Y-7700D03*
X1140952Y-7851D03*
X1137992Y-1801D03*
X1144685Y-1751D03*
X1147331Y30100D03*
X1134645Y29949D03*
X1137992Y35999D03*
X1140952Y29949D03*
X1144685Y36049D03*
X1127952Y29949D03*
X1131299Y36049D03*
X1124606D03*
X1110520Y67900D03*
X1104141Y67749D03*
X1107724Y46914D03*
X1107874Y73849D03*
X1107724Y84714D03*
X1127952Y67749D03*
X1137992Y46914D03*
X1144535D03*
X1134645Y67749D03*
X1140952D03*
X1147331Y67900D03*
X1131299Y46914D03*
X1124606D03*
X1131299Y73849D03*
X1124606D03*
X1131299Y84714D03*
X1124606D03*
X1137992Y73799D03*
X1144535Y84714D03*
X1137992D03*
X1144685Y73849D03*
X1161417Y9114D03*
X1168110D03*
X1174803D03*
X1171456Y-7851D03*
X1164763D03*
X1177763D03*
X1168110Y-1751D03*
X1161417D03*
X1174803Y-1801D03*
X1161417Y36049D03*
X1164763Y29949D03*
X1171456D03*
X1177763D03*
X1168110Y36049D03*
X1174803Y35999D03*
X1181496Y-1751D03*
X1181346Y9114D03*
X1204921D03*
X1198228D03*
X1184142Y-7700D03*
X1201574Y-7851D03*
X1204921Y-1751D03*
X1198228D03*
X1218307D03*
X1211614Y-1801D03*
X1214574Y-7851D03*
X1208267D03*
X1220953Y-7700D03*
X1218157Y9114D03*
X1211614D03*
X1181496Y36049D03*
X1184142Y30100D03*
X1204921Y36049D03*
X1198228D03*
X1201574Y29949D03*
X1218307Y36049D03*
X1211614Y35999D03*
X1208267Y29949D03*
X1220953Y30100D03*
X1214574Y29949D03*
X1168110Y46914D03*
X1161417D03*
X1174803D03*
X1177763Y67749D03*
X1171456D03*
X1164763D03*
X1174803Y84714D03*
X1168110D03*
Y73849D03*
X1161417D03*
X1174803Y73799D03*
X1161417Y84714D03*
X1181346Y46914D03*
X1198228D03*
X1204921D03*
X1184142Y67900D03*
X1201574Y67749D03*
X1211614Y46914D03*
X1218157D03*
X1211614Y73799D03*
X1218307Y73849D03*
X1218157Y84714D03*
X1211614D03*
X1220953Y67900D03*
X1214574Y67749D03*
X1208267D03*
X1181346Y84714D03*
X1181496Y73849D03*
X1198228D03*
X1204921D03*
X1198228Y84714D03*
X1204921D03*
X1241732Y36049D03*
X1238385Y29949D03*
X1245078D03*
X1251771Y16999D03*
X1248425Y36049D03*
Y27899D03*
X1269700Y13078D03*
X1241732Y-1751D03*
X1238385Y-7851D03*
X1241732Y9114D03*
X1248425Y-1751D03*
Y-9901D03*
X1251771D03*
X1245078Y-7851D03*
X1248425Y9157D03*
X1269800Y-5822D03*
X1235039Y9114D03*
Y-1751D03*
Y36049D03*
X1241732Y46914D03*
X1238385Y67749D03*
X1251771Y65699D03*
X1248425D03*
Y46957D03*
X1245078Y67749D03*
X1241732Y84714D03*
Y73849D03*
X1248425Y84757D03*
Y73849D03*
X1235039Y84714D03*
Y73849D03*
Y46914D03*
X1268111Y58040D03*
X1304940Y32350D03*
X1298422Y74000D03*
X1304685Y78827D03*
X1298754Y83233D03*
X1309700Y83300D03*
X913700Y242260D03*
X924227Y205210D03*
X920847Y207159D03*
X927607Y218860D03*
X930987Y216909D03*
X934367Y218860D03*
X947887Y214960D03*
X958026Y216909D03*
Y220809D03*
X944507Y216909D03*
Y220809D03*
X954647Y214960D03*
X951267Y213009D03*
X937747Y220809D03*
X951267Y216909D03*
Y220809D03*
X934367Y211060D03*
X944507Y205210D03*
Y209109D03*
X930987Y205210D03*
Y209109D03*
X941127Y211060D03*
X937747Y213009D03*
Y205210D03*
Y209109D03*
X917467D03*
X924227D03*
X930987Y228610D03*
X937747Y224709D03*
X934367Y230559D03*
X937747Y228610D03*
X927607Y222760D03*
X947887D03*
X954647D03*
X920847Y242260D03*
X927607Y226660D03*
X951267Y224709D03*
X930987D03*
X934367Y222760D03*
X974926Y238360D03*
X971546Y240309D03*
Y244209D03*
X927607Y238360D03*
X930987Y236409D03*
X927607Y242260D03*
X934367Y238360D03*
X937747Y244209D03*
Y240309D03*
X930987Y244209D03*
X934367Y242260D03*
X944507Y232509D03*
X947887Y230559D03*
X951267Y244209D03*
X954647Y242260D03*
X944507Y236409D03*
X951267Y232509D03*
X961406Y230559D03*
X968166Y234460D03*
Y222760D03*
X971546Y224709D03*
X961406Y234460D03*
X964786Y236409D03*
Y224709D03*
X971546Y228610D03*
X947887Y242260D03*
X954647Y238360D03*
X944507Y240309D03*
X961406Y226660D03*
X954647Y234460D03*
X971546Y232509D03*
X947887Y238360D03*
X964786Y228610D03*
X951267Y236409D03*
X968166Y230559D03*
X961406Y242260D03*
X964786Y244209D03*
X1022245Y207159D03*
X991826Y205210D03*
X1022245Y211060D03*
X995206Y207159D03*
X991826Y209109D03*
X998586Y205210D03*
X1018865Y213009D03*
X998586Y216909D03*
X1001965Y218860D03*
X995206D03*
X991826Y213009D03*
X988446Y214960D03*
X1025625Y216909D03*
X1015485Y218860D03*
X1022245D03*
X1012105Y216909D03*
X1032385Y213009D03*
X1035765Y211060D03*
X1029005Y207159D03*
X1018865Y216909D03*
X1032385D03*
X1029005Y218860D03*
X1008725Y211060D03*
X1012105Y213009D03*
X1008725Y218860D03*
X1005345Y216909D03*
Y213009D03*
X1035765Y218860D03*
X1025625Y213009D03*
X988446Y218860D03*
X995206Y214960D03*
X1001965D03*
X1035765D03*
X1015485D03*
X1022245D03*
X1012105Y205210D03*
X1025625Y205211D03*
X1029005Y214960D03*
X1035765Y207159D03*
X1005345Y205210D03*
X1008725Y214960D03*
X991826Y216909D03*
X985066Y220809D03*
X988446Y207158D03*
X995206Y211060D03*
X998586Y213009D03*
X988446Y230560D03*
X978306Y236409D03*
Y240309D03*
Y244209D03*
X985066Y240309D03*
Y244209D03*
X981686Y238360D03*
X991826Y224709D03*
X995206Y230559D03*
X1025625Y224709D03*
X988446Y222760D03*
X1022245D03*
X1015485D03*
X1018865Y224709D03*
X1012105D03*
X1035765Y222760D03*
X1001965D03*
X998586Y224709D03*
X1032385D03*
X1029005Y222760D03*
X1008725D03*
X1005345Y224709D03*
X998586Y228610D03*
X1001965Y230559D03*
X998586Y236409D03*
Y240309D03*
X1029005Y230559D03*
X1015485Y242260D03*
X1001965Y234460D03*
X995206Y242260D03*
Y234460D03*
X991826Y240309D03*
Y228610D03*
Y236409D03*
X1022245Y234460D03*
X1015485D03*
X1022245Y230559D03*
X1015485D03*
X1018865Y236409D03*
X1012105D03*
X1018865Y228610D03*
X1012105D03*
X1032385D03*
Y236409D03*
X1025625D03*
X1018865Y240309D03*
X1025625D03*
X1035765Y230559D03*
X1022245Y242260D03*
X1029005Y234460D03*
X1008725Y242260D03*
X1012105Y240309D03*
X1008725Y230559D03*
Y234460D03*
X1005345Y228610D03*
Y236409D03*
X1001965Y242260D03*
X1005345Y240309D03*
X1035765Y234460D03*
X1025625Y228610D03*
X998586Y244209D03*
Y232509D03*
X991826Y244209D03*
Y232509D03*
X995206Y226660D03*
X1032385Y232509D03*
X1035765Y226660D03*
X1018865Y244209D03*
X1012105D03*
X1018865Y232509D03*
X1015485Y226660D03*
X1022245D03*
X1012105Y232509D03*
X1025625D03*
X1029005Y226660D03*
X1005345Y244209D03*
X1008725Y226660D03*
X1005345Y232509D03*
X1001965Y226660D03*
X995206Y222760D03*
X981686D03*
X978306Y224709D03*
X981686Y226660D03*
X985066Y228610D03*
X978306D03*
X981686Y230559D03*
X985066Y232509D03*
X1032385Y240309D03*
X1035765Y242260D03*
X1029005D03*
X1032385Y244209D03*
X1025625D03*
X1035765Y246160D03*
X1049284Y207159D03*
X1042524Y211060D03*
X1039145Y213009D03*
X1045904D03*
Y216909D03*
X1049284Y218860D03*
X1042524D03*
X1039145Y216909D03*
X1042524Y214960D03*
X1049284D03*
Y211060D03*
X1045904Y244209D03*
Y240309D03*
Y228610D03*
X1039145Y224709D03*
X1049284Y222760D03*
X1042524D03*
X1045904Y224709D03*
X1039145Y236409D03*
X1049284Y230559D03*
Y234460D03*
X1042524Y230559D03*
X1049284Y238360D03*
X1042524Y234460D03*
X1039145Y228610D03*
X1045904Y236409D03*
X1042524Y226660D03*
X1039145Y232509D03*
X1049284Y226660D03*
X1045904Y232509D03*
X1049284Y242260D03*
X1039145Y240309D03*
X1042524Y242260D03*
X1039145Y244209D03*
X1042524Y246160D03*
X1049284D03*
X913787Y253960D03*
Y265660D03*
Y257860D03*
Y261760D03*
Y328060D03*
X927607Y253960D03*
X934367D03*
X937747Y252009D03*
X930987D03*
X924227D03*
X917467D03*
Y259809D03*
X924227D03*
X930987D03*
X920847Y265660D03*
X930987Y275409D03*
X937747D03*
Y271509D03*
Y255909D03*
X934367Y277360D03*
X930987Y271509D03*
X934367Y273460D03*
X927607Y269560D03*
X917467Y263709D03*
X924227Y267609D03*
X934367Y265660D03*
X924227Y263709D03*
Y275409D03*
X927607Y277360D03*
X920847Y273460D03*
Y269560D03*
X924227Y255909D03*
X947887Y253960D03*
X974926D03*
X941127D03*
X958026Y252009D03*
X968166Y277360D03*
X951267Y275409D03*
X961406Y277360D03*
X958026Y263709D03*
X968166Y269560D03*
X974926Y265660D03*
X961406Y261760D03*
X958026Y255909D03*
X951267Y259809D03*
X958026D03*
X954647Y277360D03*
Y265660D03*
X951267Y267609D03*
X954647Y273460D03*
X958026Y275409D03*
X954647Y269560D03*
X961406D03*
X964786Y283209D03*
X971546D03*
Y275409D03*
Y263709D03*
X974926Y269560D03*
X941127Y277360D03*
Y265660D03*
X944507Y275409D03*
Y263709D03*
X941127Y269560D03*
Y257860D03*
Y261760D03*
X947887Y277360D03*
Y265660D03*
X971546Y259809D03*
Y255909D03*
X964786Y279310D03*
X974926Y273460D03*
Y281260D03*
X968166D03*
X920847Y257860D03*
Y261760D03*
Y253960D03*
X917467Y255909D03*
X930987Y267609D03*
X937747Y263709D03*
X927607Y257860D03*
X930987Y255909D03*
X934367Y269560D03*
X937747Y267609D03*
X927607Y261760D03*
X934367Y257860D03*
X937747Y259809D03*
X927607Y265660D03*
X934367Y261760D03*
X930987Y263709D03*
X947887Y261760D03*
X954647Y257860D03*
X974926D03*
Y261760D03*
X944507Y252009D03*
X951267Y263709D03*
X954647Y261760D03*
X944507Y255909D03*
X951267Y252009D03*
X954647Y253960D03*
X964786Y263709D03*
Y275409D03*
X944507Y259809D03*
X951267Y255909D03*
X964786Y267609D03*
Y271509D03*
X947887Y257860D03*
X961406Y265660D03*
Y273460D03*
X971546Y267609D03*
Y271509D03*
X958026Y267609D03*
Y271509D03*
X968166Y265660D03*
Y273460D03*
X934367Y285160D03*
Y300760D03*
X927607D03*
Y308560D03*
X934367D03*
X927607Y285160D03*
Y292959D03*
X934367D03*
X920847Y328060D03*
X924227Y322209D03*
X927607Y320260D03*
X930987Y318309D03*
X927607Y316360D03*
X961406Y292959D03*
Y285160D03*
X954647Y292959D03*
Y285160D03*
X968166Y292959D03*
Y300760D03*
X964786Y310509D03*
X954647Y308560D03*
X961406D03*
X954647Y300760D03*
X961406D03*
X974926D03*
X947887Y308560D03*
X941127D03*
Y300760D03*
X947887D03*
X941127Y285160D03*
Y292959D03*
X947887D03*
Y285160D03*
X974926Y292959D03*
X988446Y253960D03*
X978306Y252009D03*
X985066D03*
X991826Y259809D03*
X985066D03*
X981686Y269560D03*
Y281260D03*
X995206Y269560D03*
X985066Y267609D03*
X991826Y263709D03*
X988446Y265660D03*
X998586Y263709D03*
X991826Y271509D03*
X995206Y273460D03*
X991826Y283209D03*
Y279310D03*
Y275409D03*
X988446Y281260D03*
X985066Y283209D03*
X978306D03*
Y267609D03*
Y259809D03*
X991826Y255909D03*
X995206Y265660D03*
X991826Y267609D03*
X1001965Y261760D03*
X1012105Y255909D03*
X1015485Y253960D03*
X1018865Y252009D03*
X1005345Y259809D03*
X1008725Y257860D03*
X978306Y255909D03*
Y263709D03*
X988446Y257860D03*
Y261760D03*
X985066Y255909D03*
Y263709D03*
X981686Y253960D03*
Y265660D03*
Y257860D03*
Y261760D03*
X991826Y252009D03*
X981686Y292959D03*
Y300760D03*
X988446D03*
X991826Y310509D03*
X988446Y292959D03*
X995206Y335860D03*
Y328060D03*
X991826Y314409D03*
X995206Y331960D03*
Y324160D03*
X991826Y318309D03*
X995206Y320260D03*
X998586Y333909D03*
X1005345Y337809D03*
X1001965Y335860D03*
X1015485Y343660D03*
X998586Y337809D03*
X1094731Y346546D03*
X1091351Y348497D03*
X847577Y381842D03*
X824000Y402863D03*
X827800D03*
X832300D03*
X913787Y343660D03*
Y339760D03*
Y335860D03*
Y355360D03*
Y351460D03*
Y347560D03*
X937747Y341709D03*
Y326110D03*
X917467Y333909D03*
Y341709D03*
X924227Y333909D03*
Y337809D03*
Y341709D03*
X934367Y331960D03*
Y343660D03*
X927607D03*
X934367Y324160D03*
X930987Y337809D03*
X958026Y333909D03*
Y337809D03*
Y341709D03*
X961406Y324160D03*
X971546Y337809D03*
X964786Y330009D03*
X971546D03*
X951267D03*
X958026D03*
X974926Y324160D03*
X951267Y337809D03*
X954647Y331960D03*
Y328060D03*
X971546Y322209D03*
X968166Y320260D03*
X964786Y322209D03*
X974926Y335860D03*
X958026Y326110D03*
X947887Y343660D03*
X944507Y322209D03*
X947887Y331960D03*
Y328060D03*
X941127Y331960D03*
Y328060D03*
Y339760D03*
Y335860D03*
Y343660D03*
X944507Y333909D03*
X920847Y335860D03*
Y343660D03*
Y339760D03*
X917467Y345609D03*
Y337809D03*
X937747Y333909D03*
X930987Y330009D03*
Y341709D03*
X927607Y339760D03*
X937747Y330009D03*
X934367Y328060D03*
Y339760D03*
X927607Y335860D03*
Y331960D03*
X934367Y335860D03*
X930987Y333909D03*
X937747Y337809D03*
X954647Y339760D03*
X947887Y335860D03*
X954647D03*
X951267Y333909D03*
X944507Y341709D03*
Y337809D03*
X968166Y328060D03*
Y335860D03*
X951267Y341709D03*
X947887Y339760D03*
X968166Y324160D03*
Y331960D03*
X954647Y343660D03*
X964786Y326110D03*
Y333909D03*
X974926Y328060D03*
Y331960D03*
X961406Y328060D03*
Y331960D03*
X971546Y326110D03*
Y333909D03*
X937747Y345609D03*
X927607Y347560D03*
X934367Y351460D03*
X930987Y345609D03*
X917467Y353409D03*
Y349509D03*
X924227D03*
Y345609D03*
Y353409D03*
Y361209D03*
Y357309D03*
X920847Y355360D03*
X917167Y361209D03*
X958026Y345609D03*
X920847Y351460D03*
Y347560D03*
X934367D03*
X927607Y355360D03*
X930987Y349509D03*
X927607Y351460D03*
X930987Y353409D03*
X944507Y345609D03*
X951267D03*
X978306Y333909D03*
Y330009D03*
Y326110D03*
X981686Y331960D03*
X985066Y330009D03*
X981686Y335860D03*
X985066Y333909D03*
X937747Y372909D03*
X930987Y369010D03*
Y380709D03*
X927607Y378760D03*
X937747Y369010D03*
X934367Y367060D03*
Y378760D03*
X927607Y374860D03*
X947887D03*
Y382660D03*
X958026Y376809D03*
Y380709D03*
X944507Y376809D03*
Y380709D03*
X954647Y374860D03*
Y382660D03*
X934367Y374860D03*
X951267Y376809D03*
X927607Y370959D03*
X951267Y384609D03*
X937747Y376809D03*
X951267Y372909D03*
X930987D03*
X951267Y380709D03*
X974926Y351460D03*
Y359260D03*
X971546Y353409D03*
Y357309D03*
X934367Y386560D03*
Y394359D03*
X944507Y388509D03*
Y392410D03*
X930987Y388509D03*
Y392410D03*
X941127Y386560D03*
Y394359D03*
X937747Y388509D03*
Y396309D03*
Y384609D03*
Y392410D03*
X951267Y365109D03*
X947887Y367060D03*
X954647Y355360D03*
X951267Y353409D03*
X944507Y361209D03*
Y365109D03*
X968166Y363160D03*
X961406Y367060D03*
X971546Y372909D03*
X968166Y374860D03*
X964786Y361209D03*
X961406Y363160D03*
X971546Y369010D03*
X964786Y372909D03*
X954647Y359260D03*
X947887Y355360D03*
X951267Y361209D03*
X968166Y367060D03*
X944507Y357309D03*
X961406Y370959D03*
X954647Y363160D03*
X971546Y365109D03*
X947887Y359260D03*
X964786Y369010D03*
Y353409D03*
X961406Y355360D03*
Y351460D03*
X924227Y400209D03*
X930987D03*
X920847Y394359D03*
X917467Y392410D03*
X944507Y400209D03*
X964786Y384609D03*
Y380709D03*
X920847Y398260D03*
X927607D03*
X924227Y396309D03*
X981686Y343660D03*
X988446D03*
X998586Y345609D03*
X1001965Y343660D03*
X991826Y384609D03*
X991500Y396301D03*
X1022245Y390460D03*
X995206Y386560D03*
X978306Y353409D03*
Y361209D03*
Y349509D03*
Y357309D03*
X985066Y353409D03*
Y357309D03*
X981686Y351460D03*
Y359260D03*
X1022245Y386560D03*
X998586Y388509D03*
X991826Y380709D03*
X1000800Y402800D03*
X995206Y378760D03*
X998586Y380709D03*
X1025625Y372909D03*
X1018865Y384609D03*
X995206Y367060D03*
X998586Y372909D03*
X991826D03*
X988446Y374860D03*
Y370959D03*
Y378760D03*
X1018865Y372909D03*
X1012105D03*
X1022245Y378760D03*
X1012105Y380709D03*
X1022245Y374860D03*
X1015485D03*
X1025625Y380709D03*
X1015485Y378760D03*
X1032385Y384609D03*
X1035765Y374860D03*
Y386560D03*
X1029005D03*
X1018865Y380709D03*
X1001965Y378760D03*
Y374860D03*
X1032385Y380709D03*
Y372909D03*
X1029005Y378760D03*
Y374860D03*
X1008725Y386560D03*
X1012105Y384609D03*
X1008725Y378760D03*
X1005345Y380709D03*
X1008725Y374860D03*
X1005345Y372909D03*
X998586Y369010D03*
X1001965Y367060D03*
X1005345Y384609D03*
X1035765Y378760D03*
X1025625Y384609D03*
X995206Y355360D03*
X998586Y357309D03*
X1029005Y367060D03*
X1015485Y355360D03*
X995206Y351460D03*
X998586Y361209D03*
X995206Y363160D03*
X991826Y357309D03*
Y369010D03*
Y361209D03*
X1018865Y369010D03*
X1012105D03*
X1018865Y361209D03*
X1012105D03*
X1022245Y367060D03*
X1015485D03*
X1022245Y363160D03*
X1015485D03*
X1032385Y369010D03*
Y361209D03*
X985066Y345609D03*
X1025625Y361209D03*
X1018865Y357309D03*
X1001965Y351460D03*
Y363160D03*
X1025625Y357309D03*
X1035765Y367060D03*
X1022245Y355360D03*
X1029005Y363160D03*
X1008725Y355360D03*
X1012105Y357309D03*
X1008725Y363160D03*
Y367060D03*
X1005345Y361209D03*
Y369010D03*
X1001965Y355360D03*
X1005345Y357309D03*
X1008725Y351460D03*
X1035765Y363160D03*
X1025625Y369010D03*
X988446Y367060D03*
X998586Y365109D03*
Y353409D03*
X991826Y365109D03*
X995206Y370959D03*
X991826Y353409D03*
X998586Y392410D03*
X988446Y382660D03*
X995206D03*
X1005345Y365109D03*
X1008725Y370959D03*
X1001965D03*
X1005345Y353409D03*
X1018865Y365109D03*
X1012105D03*
X1025625D03*
X1022245Y370959D03*
X1015485D03*
X1018865Y353409D03*
X1012105D03*
X1025625D03*
X1029005Y370959D03*
X1035765D03*
X1032385Y365109D03*
X1007595Y402800D03*
X1008725Y382660D03*
X1001965D03*
X1005345Y392410D03*
X1029005Y390460D03*
X1025625Y392410D03*
X1022245Y382660D03*
X1015485D03*
X1012105Y392410D03*
X1018865D03*
X1029005Y382660D03*
X1035765D03*
X1027875Y402800D03*
X1005345Y345609D03*
X1032385Y353409D03*
X1035765Y355360D03*
X998586Y384609D03*
X985066Y376809D03*
X981686Y374860D03*
X995206D03*
X978306Y372909D03*
X981686Y370959D03*
X978306Y369010D03*
X985066D03*
X981686Y367060D03*
X985066Y365109D03*
X988446Y363160D03*
X1032385Y357309D03*
X1029005Y355360D03*
X1015485Y351460D03*
X1022245D03*
X1029005D03*
X991826Y349509D03*
X1012105D03*
X995206Y347560D03*
X1001965D03*
X1008725D03*
X1042524Y355360D03*
X1045904Y357309D03*
X1039145D03*
X1045904Y384609D03*
X1093601Y381947D03*
Y389747D03*
X1090221Y383896D03*
Y387796D03*
X1096981Y383896D03*
Y391696D03*
Y379996D03*
Y387796D03*
X1042524Y386560D03*
X1039145Y384609D03*
X1049284Y390460D03*
X1045904Y380709D03*
X1049284Y378760D03*
X1045904Y369010D03*
X1039145Y372909D03*
X1052664Y380709D03*
X1049284Y374860D03*
X1073322Y389747D03*
Y393647D03*
X1083462Y383896D03*
Y387796D03*
X1073322Y378047D03*
Y381947D03*
X1080082D03*
Y389747D03*
X1076702Y383896D03*
Y391696D03*
Y379996D03*
Y387796D03*
X1042524Y378760D03*
Y374860D03*
X1039145Y380709D03*
X1045904Y372909D03*
X1052664Y361209D03*
X1039145D03*
X1049284Y367060D03*
Y363160D03*
X1042524Y367060D03*
X1052664Y372909D03*
Y369010D03*
X1076702Y364396D03*
X1073322Y370247D03*
X1086841Y366347D03*
Y370247D03*
X1073322Y358547D03*
Y366347D03*
X1083462Y364396D03*
Y372197D03*
X1093601Y362447D03*
X1090221Y356596D03*
Y360496D03*
X1080082Y366347D03*
X1096981Y356596D03*
X1080082Y370247D03*
X1096981Y364396D03*
X1080082Y362447D03*
Y374146D03*
X1096981Y360496D03*
X1049284Y359260D03*
X1042524Y363160D03*
X1039145Y369010D03*
X1045904Y361209D03*
X1052664Y357309D03*
X1049284Y370959D03*
X1042524D03*
X1045904Y365109D03*
X1039145D03*
X1052664D03*
Y392410D03*
X1040265Y394359D03*
X1049284Y382660D03*
X1042524D03*
Y390460D03*
X1056176Y402471D03*
X1041395Y402800D03*
X1061039Y359351D03*
X1060963Y370959D03*
X1061055Y363160D03*
X1052664Y353409D03*
X1064371Y367060D03*
X1052664Y396309D03*
X1060694Y394359D03*
Y390460D03*
X1049284Y386560D03*
X1060694D03*
Y382660D03*
Y378760D03*
X1048154Y402900D03*
X1086841Y378047D03*
X1090221Y376096D03*
X1093601Y374146D03*
Y370247D03*
X1049284Y355360D03*
X1080082Y358547D03*
X1083462Y356596D03*
X1052500Y400400D03*
X1072202Y216196D03*
X1099241D03*
X1065242Y208397D03*
X1068822Y214247D03*
X1065242Y212296D03*
X1095861Y218147D03*
X1099241Y220096D03*
Y212296D03*
X1089101Y214247D03*
Y210346D03*
X1092481Y216196D03*
X1095861Y206446D03*
X1075582D03*
Y218147D03*
X1082341D03*
X1078962Y216196D03*
X1078961Y212296D03*
X1078962Y220096D03*
X1082341Y214247D03*
X1085721Y212296D03*
Y216196D03*
Y220096D03*
X1095861Y222047D03*
X1082341D03*
X1092481Y220096D03*
X1089101Y218147D03*
Y222047D03*
X1065242Y220096D03*
Y216196D03*
X1075582Y222047D03*
X1072202Y220096D03*
X1068822Y218147D03*
Y222047D03*
X1099241Y227896D03*
X1095861Y229847D03*
X1068822Y233746D03*
X1065242Y235696D03*
Y223996D03*
X1068822Y237647D03*
Y249347D03*
X1065242Y247396D03*
X1068822Y241547D03*
X1072202Y243496D03*
Y251296D03*
X1099241Y223996D03*
X1092481D03*
Y231797D03*
X1089101Y233746D03*
Y237647D03*
X1095861D03*
Y245447D03*
X1078962Y251296D03*
X1082341Y245447D03*
Y249347D03*
X1078962Y247396D03*
X1092481Y243496D03*
X1075582Y245447D03*
X1085721Y251296D03*
X1075582Y249347D03*
X1085721Y243496D03*
X1089101Y241547D03*
X1099241Y251296D03*
Y247396D03*
X1085721Y223996D03*
X1075582Y229847D03*
X1082341D03*
X1078962Y227896D03*
Y223996D03*
X1085721Y231797D03*
X1082341Y237647D03*
X1075582D03*
X1072202Y231797D03*
Y223996D03*
X1089101Y253247D03*
X1092481Y255196D03*
X1099241D03*
Y259096D03*
X1095861Y257147D03*
X1085721Y227896D03*
X1095861Y225947D03*
X1082341D03*
X1092481Y227896D03*
X1089101Y229847D03*
Y225947D03*
X1075582D03*
X1065242Y227896D03*
Y231797D03*
X1072202Y227896D03*
X1068822Y225947D03*
Y229847D03*
X1075582Y233746D03*
Y241547D03*
X1085721Y235696D03*
Y239596D03*
X1072202Y235696D03*
Y239596D03*
X1082341Y233746D03*
Y241547D03*
X1095861Y233746D03*
Y241547D03*
X1092481Y235696D03*
Y239596D03*
X1078962Y231797D03*
X1099241D03*
X1078962Y243496D03*
X1099241D03*
X1078962Y235696D03*
X1099241D03*
X1078962Y239596D03*
X1099241D03*
X1116141Y206446D03*
X1109381Y214247D03*
X1116141Y218147D03*
X1106001Y212296D03*
X1102621Y218147D03*
Y214247D03*
X1119521Y220096D03*
Y216196D03*
X1119520Y212296D03*
X1106001Y216196D03*
X1112761D03*
X1129660Y206447D03*
X1126280Y216196D03*
Y212296D03*
X1122900Y214247D03*
Y218147D03*
X1129660Y214247D03*
X1147680Y222047D03*
X1147950Y209900D03*
X1136420Y218147D03*
Y222047D03*
Y210346D03*
Y214247D03*
X1151060Y212296D03*
X1157820Y220096D03*
Y212296D03*
X1106001Y220096D03*
X1116141Y222047D03*
X1102621D03*
X1112761Y220096D03*
X1126280D03*
X1122900Y222047D03*
X1133040Y216196D03*
Y220096D03*
X1109381Y218147D03*
X1129660D03*
X1109381Y222047D03*
X1129660D03*
X1144300Y216196D03*
Y212296D03*
X1147680Y218147D03*
X1154440Y214247D03*
X1151060Y220096D03*
X1157820Y216196D03*
X1144300Y220096D03*
X1147680Y214247D03*
X1151060Y216196D03*
X1154440Y218147D03*
Y222047D03*
X1161200Y214247D03*
X1102621Y229847D03*
X1109381Y233746D03*
X1112761Y231797D03*
Y223996D03*
X1116141Y237647D03*
X1109381D03*
X1106001Y223996D03*
X1102621Y237647D03*
Y245447D03*
X1112761Y251296D03*
X1116141Y245447D03*
X1106001Y243496D03*
X1112761D03*
X1109381Y241547D03*
X1106001Y251296D03*
X1119521Y223996D03*
Y227896D03*
Y247396D03*
Y251296D03*
X1106001Y231797D03*
X1116141Y229847D03*
Y264947D03*
X1111631Y271300D03*
X1106001Y262996D03*
Y259096D03*
X1119521Y270796D03*
X1118391Y274997D03*
X1119521Y255196D03*
X1102621Y261047D03*
Y257147D03*
X1109381Y261047D03*
X1116141Y257147D03*
X1112761Y259096D03*
X1129660Y237647D03*
X1126280Y223996D03*
Y231797D03*
X1122900Y229847D03*
Y237647D03*
X1129660Y233746D03*
Y241547D03*
X1126280Y251296D03*
Y243496D03*
X1122900Y245447D03*
X1144300Y243496D03*
X1151060Y247396D03*
X1154440Y245447D03*
X1144300Y247396D03*
Y251296D03*
X1136420Y245447D03*
X1154440Y241547D03*
X1136420D03*
X1157820Y239596D03*
X1144300Y235696D03*
X1136420Y229847D03*
Y233746D03*
Y225947D03*
Y237647D03*
X1133040Y223996D03*
Y235696D03*
Y243496D03*
Y251296D03*
X1147680Y225947D03*
X1151060Y223996D03*
X1147680Y233746D03*
X1154440Y229847D03*
X1157820Y223996D03*
Y231797D03*
X1154440Y253247D03*
X1130780Y278596D03*
X1129660Y261047D03*
X1130780Y274696D03*
X1126280Y259096D03*
X1122900Y257147D03*
X1157820Y278596D03*
Y270796D03*
X1151060Y266896D03*
Y282496D03*
Y274696D03*
X1137540D03*
X1151060Y259096D03*
X1144300Y255196D03*
X1133040Y259096D03*
X1134160Y268847D03*
X1136420Y257147D03*
X1144300Y278596D03*
Y270796D03*
X1137540Y282496D03*
Y278596D03*
X1147680Y264947D03*
X1106001Y227896D03*
X1116141Y225947D03*
X1102621D03*
X1112761Y227896D03*
X1126280D03*
X1133040D03*
Y231797D03*
X1122900Y225947D03*
X1109381Y229847D03*
X1129660Y225947D03*
X1109381D03*
X1129660Y229847D03*
X1116141Y233746D03*
Y241547D03*
X1126280Y235696D03*
Y239596D03*
X1112761Y235696D03*
Y239596D03*
X1122900Y233746D03*
Y241547D03*
X1119521Y231797D03*
Y243496D03*
Y235696D03*
Y239596D03*
X1106001Y235696D03*
Y239596D03*
X1102621Y233746D03*
Y241547D03*
X1106001Y247396D03*
Y255196D03*
X1116141Y249347D03*
Y253247D03*
X1102621Y249347D03*
Y253247D03*
X1112761Y247396D03*
Y255196D03*
X1126280Y247396D03*
Y255196D03*
X1136420Y249347D03*
Y253247D03*
X1122900Y249347D03*
Y253247D03*
X1133040Y247396D03*
Y255196D03*
X1109381Y245447D03*
X1129660D03*
X1109381Y257147D03*
X1129660D03*
X1109381Y249347D03*
X1129660D03*
X1109381Y253247D03*
X1129660D03*
X1151060Y243496D03*
X1144300Y239596D03*
X1151060Y235696D03*
X1144300Y227896D03*
X1154440Y233746D03*
X1147680Y229847D03*
X1154440Y237647D03*
X1157820Y227896D03*
X1147680Y241547D03*
Y237647D03*
X1151060Y239596D03*
X1144300Y231797D03*
X1151060D03*
Y227896D03*
X1157820Y235696D03*
X1161200Y237647D03*
X1119521Y305896D03*
X1130780Y290296D03*
X1127400Y288347D03*
X1130780Y309797D03*
Y301996D03*
X1127400Y303947D03*
Y307847D03*
X1157820Y290296D03*
X1151060D03*
X1144300Y286396D03*
Y294196D03*
X1157820D03*
X1140920Y300047D03*
X1134160Y292247D03*
Y300047D03*
X1140920Y292247D03*
X1144300Y309797D03*
X1137540D03*
X1147680Y303947D03*
X1130780Y313696D03*
X1134160Y323446D03*
X1137540Y317596D03*
X1147680Y327347D03*
X1140920Y331247D03*
X1147680Y319547D03*
X1127400Y315647D03*
X1130780Y344896D03*
Y329296D03*
X1144300Y301996D03*
X1134160Y303947D03*
X1137540Y298096D03*
X1134160Y346847D03*
X1130780Y352696D03*
X1161200Y206446D03*
X1167960Y206447D03*
Y218147D03*
X1171339Y208397D03*
X1174719Y218147D03*
X1171339Y220096D03*
X1174719Y206447D03*
X1178099Y208397D03*
Y216196D03*
Y220096D03*
X1161200Y210346D03*
Y218147D03*
X1181479Y222047D03*
Y206447D03*
X1188239Y210346D03*
Y222047D03*
Y206447D03*
X1201759Y218147D03*
X1205759Y206682D03*
X1198379Y212296D03*
X1194999Y210346D03*
Y222047D03*
X1188239Y214247D03*
X1181479D03*
X1178099Y212296D03*
X1184859Y208397D03*
Y220096D03*
X1191619Y216196D03*
X1194999Y214247D03*
Y218147D03*
X1198379Y220096D03*
X1201759Y222047D03*
X1164580Y212296D03*
Y208397D03*
X1167960Y214247D03*
X1174719Y210346D03*
X1184859Y216196D03*
X1181479Y210346D03*
X1184859Y212296D03*
X1188239Y218147D03*
X1191619Y220096D03*
Y212296D03*
X1198379Y216196D03*
X1205139Y220096D03*
X1164580Y216196D03*
X1167960Y210346D03*
X1171339Y212296D03*
X1174719Y214247D03*
Y222047D03*
X1164580Y235696D03*
X1167960Y229847D03*
X1164580Y223996D03*
Y227896D03*
Y239596D03*
X1178099Y247396D03*
X1161200Y241547D03*
X1164580Y247396D03*
X1161200Y249347D03*
X1171339Y247396D03*
X1178099Y243496D03*
X1171339Y235696D03*
Y231797D03*
X1178099Y227896D03*
Y235696D03*
X1174719Y237647D03*
X1167960Y253247D03*
X1174719D03*
X1164580Y270796D03*
X1171339Y274696D03*
X1174719Y280547D03*
X1171339Y266896D03*
X1164580Y278596D03*
X1171339Y259096D03*
X1178099Y274696D03*
X1191619Y239596D03*
X1188239Y225947D03*
X1184859Y235696D03*
X1188239Y237647D03*
X1184859Y247396D03*
X1188239Y249347D03*
X1201759Y229847D03*
Y225947D03*
Y233746D03*
X1198379Y235696D03*
Y243496D03*
X1201759Y241547D03*
Y249347D03*
X1198379Y239596D03*
X1194999Y225947D03*
Y233746D03*
X1184859Y239596D03*
Y251296D03*
X1212199D03*
X1208519Y233746D03*
X1215700Y223600D03*
X1194999Y264947D03*
Y268847D03*
Y272747D03*
Y280547D03*
X1188239Y257147D03*
X1208519Y272747D03*
X1208819Y280547D03*
X1181479Y261047D03*
Y268847D03*
Y276646D03*
X1212199Y274696D03*
X1208519Y264947D03*
X1184859Y259096D03*
X1191619Y274696D03*
X1205139D03*
X1198379Y278596D03*
X1201759Y261047D03*
X1198379Y255196D03*
X1201759Y257147D03*
X1167960Y261047D03*
X1174719D03*
X1164580Y251296D03*
X1167960Y272747D03*
X1171339Y255196D03*
Y251296D03*
X1161200Y245447D03*
X1164580Y243496D03*
X1174719Y272747D03*
X1167960Y249347D03*
X1181479Y257147D03*
X1178099Y255196D03*
X1161200Y253247D03*
X1174719Y268847D03*
X1167960Y241547D03*
Y245447D03*
Y237647D03*
X1171339Y239596D03*
X1174719Y249347D03*
Y245447D03*
X1205139Y255196D03*
X1208519Y249347D03*
X1201759Y253247D03*
X1205139Y243496D03*
X1212199Y239596D03*
X1205139Y235696D03*
X1212199Y227896D03*
X1208519Y225947D03*
X1205139Y282496D03*
X1201759Y280547D03*
X1198379Y274696D03*
X1201759Y272747D03*
X1205139Y270796D03*
X1201759Y264947D03*
X1205139Y262996D03*
X1208519Y257147D03*
Y253247D03*
X1205139Y251296D03*
X1208519Y241547D03*
Y237647D03*
X1205139Y239596D03*
X1212199Y231797D03*
Y223996D03*
X1205139Y278596D03*
X1201759Y276646D03*
Y268847D03*
X1208519D03*
X1205139Y266896D03*
Y259096D03*
Y223996D03*
X1198379D03*
X1205139Y227896D03*
X1178099Y282496D03*
X1184859Y262996D03*
X1191619Y259096D03*
X1194999Y261047D03*
Y257147D03*
X1188239Y253247D03*
X1194999Y249347D03*
X1198379Y247396D03*
X1191619Y243496D03*
X1188239Y241547D03*
X1181479Y245447D03*
X1184859Y278596D03*
X1188239Y276646D03*
Y280547D03*
X1181479Y272747D03*
X1188239Y268847D03*
X1191619Y266896D03*
X1181479Y280547D03*
X1188239Y261047D03*
X1191619Y262996D03*
X1198379Y259096D03*
X1191619Y255196D03*
Y251296D03*
X1194999Y253247D03*
Y245447D03*
Y241547D03*
X1188239Y245447D03*
X1184859Y243496D03*
Y282496D03*
Y274696D03*
X1191619Y282496D03*
Y278596D03*
X1184859Y270796D03*
X1188239Y272747D03*
Y264947D03*
X1174719Y229847D03*
X1167960Y225947D03*
X1174719Y233746D03*
X1181479Y229847D03*
X1184859Y227896D03*
Y231797D03*
X1191619Y235696D03*
Y227896D03*
X1198379Y231797D03*
X1161200Y233746D03*
Y229847D03*
X1171339Y227896D03*
Y223996D03*
X1174719Y225947D03*
X1178099Y231797D03*
X1181479Y233746D03*
Y225947D03*
X1188239Y229847D03*
Y233746D03*
X1191619Y231797D03*
X1194999Y229847D03*
X1161200Y225947D03*
X1164580Y231797D03*
X1174719Y257147D03*
X1178099Y259096D03*
X1167960Y268847D03*
Y264947D03*
X1174719Y284447D03*
X1164580Y294196D03*
Y290296D03*
Y286396D03*
X1161200Y284447D03*
X1178099Y286396D03*
X1181479Y288347D03*
X1188239Y284447D03*
X1201759D03*
X1198379Y286396D03*
X1205439Y286596D03*
X1208819Y284447D03*
X1184859Y286396D03*
X1191619D03*
X1194999Y284447D03*
X1181479D03*
X1281799Y193190D03*
X1268404Y246304D03*
X1279393Y247602D03*
X1270478Y243490D03*
X1277504Y250346D03*
X1272761Y240220D03*
X1300300Y169900D03*
X1344462Y209272D03*
X1308887Y285015D03*
X1335400Y284900D03*
X1390100Y170000D03*
X1385100Y165000D03*
Y170000D03*
X1117261Y340996D03*
X1157820Y337096D03*
Y333196D03*
X1147680Y342947D03*
X1151060Y340996D03*
X1157820Y329296D03*
X1154440Y342947D03*
X1144300Y344896D03*
X1157820Y325396D03*
X1151060Y344896D03*
X1154440Y339047D03*
X1113881Y350747D03*
Y358547D03*
X1117261Y348796D03*
X1110501Y352696D03*
X1107121Y346847D03*
Y354647D03*
Y358547D03*
Y362447D03*
X1110501Y364396D03*
X1113881Y366347D03*
X1117261Y372197D03*
Y368296D03*
X1110501Y372197D03*
X1113881Y405347D03*
Y401447D03*
X1110501Y391696D03*
Y395595D03*
X1107121Y389747D03*
Y385847D03*
X1113881D03*
Y397546D03*
Y393647D03*
Y378047D03*
X1117261Y376096D03*
X1110501Y379996D03*
X1107121Y381947D03*
X1151060Y368296D03*
X1147680Y366347D03*
X1120641Y350747D03*
Y358547D03*
Y366347D03*
X1127400Y362447D03*
X1134160Y366347D03*
Y370247D03*
X1151060Y356596D03*
Y360496D03*
X1144300D03*
Y356596D03*
X1147680Y346847D03*
Y350747D03*
X1151060Y352696D03*
Y348796D03*
X1147680Y358547D03*
X1157820Y360496D03*
X1154440Y358547D03*
Y354647D03*
X1157820Y352696D03*
X1147680Y354647D03*
X1144300Y348796D03*
X1154440Y346847D03*
X1140920Y362447D03*
X1154440Y366347D03*
X1144300Y372197D03*
X1137540D03*
Y368296D03*
X1140920Y366347D03*
Y370247D03*
X1151060Y364396D03*
X1144300D03*
X1137540D03*
X1147680Y362447D03*
X1124021Y372197D03*
X1130780D03*
X1124021Y364396D03*
X1137540Y403396D03*
Y399496D03*
X1124021Y391696D03*
X1130780Y395596D03*
X1127400Y385847D03*
Y389747D03*
X1130780Y391696D03*
X1124021Y379996D03*
X1127400Y381947D03*
X1130780Y379996D03*
X1137540Y395597D03*
X1140920Y397546D03*
X1137540Y376096D03*
X1157820Y387796D03*
X1140920Y378047D03*
Y381947D03*
X1147680Y393647D03*
X1120641Y385847D03*
Y393647D03*
Y378047D03*
Y401447D03*
X1140920Y374146D03*
X1151060Y395597D03*
Y391696D03*
X1147680Y385847D03*
Y397546D03*
X1151060Y379996D03*
X1154440Y378047D03*
Y381947D03*
X1140920Y389747D03*
X1134160Y393647D03*
Y385847D03*
Y378047D03*
X1140920Y385847D03*
X1144300Y391696D03*
X1134160Y405347D03*
X1113881Y381947D03*
Y389747D03*
X1124021Y383896D03*
Y387796D03*
X1110501Y383896D03*
Y387796D03*
X1120641Y381947D03*
Y389747D03*
X1134160Y381947D03*
Y389747D03*
X1144300Y395597D03*
Y399496D03*
X1130780Y383896D03*
Y387796D03*
X1140920Y401447D03*
Y393647D03*
X1117261Y379996D03*
X1137540D03*
X1117261Y391696D03*
X1137540D03*
X1117261Y383896D03*
X1137540D03*
X1117261Y387796D03*
X1137540D03*
X1124021Y368296D03*
Y376096D03*
X1130780Y364396D03*
X1134160Y374146D03*
X1120641Y370247D03*
Y374146D03*
X1130780Y368296D03*
Y376096D03*
X1127400Y370247D03*
Y378047D03*
Y366347D03*
Y374146D03*
X1113881Y370247D03*
Y374146D03*
X1110501Y368296D03*
Y376096D03*
X1113881Y354647D03*
Y362447D03*
X1124021Y360496D03*
X1110501Y356596D03*
Y360496D03*
X1120641Y354647D03*
Y362447D03*
X1107121Y370247D03*
X1117261Y356596D03*
X1107121Y378047D03*
X1117261Y364396D03*
X1107121Y366347D03*
X1117261Y352696D03*
X1107121Y374146D03*
X1117261Y360496D03*
X1161200Y335147D03*
Y339047D03*
X1164580Y329296D03*
Y333196D03*
Y337096D03*
X1167960Y339047D03*
Y327347D03*
X1161200Y331247D03*
Y327347D03*
X1178099Y337096D03*
X1164580Y321496D03*
X1161200Y323446D03*
X1167960Y342947D03*
Y323446D03*
X1164580Y325396D03*
X1171339D03*
X1174719Y342947D03*
Y335147D03*
X1194999D03*
Y331247D03*
X1208519Y339047D03*
X1212199Y344896D03*
X1181479Y327347D03*
Y335147D03*
X1184859Y321496D03*
X1188239Y339047D03*
Y335147D03*
X1184859Y329296D03*
X1191619Y321496D03*
X1198379Y325396D03*
Y340996D03*
X1205139Y333196D03*
X1184859Y337096D03*
X1178099Y340996D03*
X1181479Y339047D03*
Y342947D03*
X1178099Y344896D03*
X1167960Y370247D03*
X1164580Y372197D03*
X1171339Y356596D03*
Y360496D03*
X1164580Y356596D03*
X1171339Y348796D03*
X1174719Y354647D03*
X1161200Y370247D03*
X1171339Y372197D03*
X1167960Y362447D03*
X1178099Y364396D03*
X1171339Y399496D03*
X1164580Y403396D03*
X1178099D03*
X1167960Y389747D03*
X1161200Y397546D03*
X1167960Y397547D03*
X1174719Y393647D03*
X1161200Y378047D03*
X1164580Y379996D03*
X1174719Y381947D03*
X1194999Y346847D03*
Y354647D03*
X1209219Y370247D03*
X1212199Y356597D03*
Y352696D03*
X1181479Y346847D03*
X1188239Y366347D03*
X1194999D03*
X1191619Y348796D03*
X1184859Y356596D03*
X1191619Y360496D03*
X1201759Y350747D03*
X1205139Y360496D03*
X1181479Y374146D03*
Y389747D03*
X1209769Y374146D03*
X1184859Y383896D03*
X1188239Y393647D03*
X1201759Y389747D03*
X1197258Y397546D03*
X1194999Y385847D03*
X1188239Y378047D03*
X1201759D03*
X1208819Y393647D03*
Y381897D03*
X1174719Y346847D03*
X1178099Y348796D03*
Y352696D03*
X1315496Y361190D03*
X1154440Y307847D03*
X1157820Y313696D03*
X1161200Y307847D03*
Y315647D03*
X1167960D03*
X1174719D03*
X1205500Y309797D03*
X1198379D03*
X1194999Y296147D03*
Y300047D03*
Y307847D03*
Y303947D03*
X1191619Y298096D03*
X1181479Y300047D03*
Y311747D03*
Y307847D03*
Y303947D03*
X1184859Y294196D03*
X1191619D03*
X1184859Y309797D03*
X1188239Y311747D03*
X1184859Y301996D03*
X1205439Y298096D03*
Y305896D03*
X1208826Y319544D03*
X1198379Y313696D03*
X1194999Y315647D03*
X1205439Y294196D03*
X1336336Y333825D03*
X1306290Y298255D03*
X1364260Y331619D03*
X1364856Y366666D03*
X1375201Y396303D03*
X1365731Y360698D03*
X1378207Y394568D03*
X1371600Y368700D03*
X1355100Y427500D03*
Y432500D03*
X1370100Y442500D03*
X1365100D03*
X1375100D03*
X1539400Y320200D03*
X1557250Y315410D03*
X1548024Y322145D03*
X1575645Y320664D03*
X1548334Y325497D03*
X1543864Y311399D03*
X1674019Y175990D03*
X1654685Y121790D03*
X1664500Y99000D03*
X1672200Y112200D03*
X1664135Y131239D03*
X1657835D03*
X1678400Y103000D03*
X1674800Y103100D03*
X1754600Y109200D03*
X1748425Y119190D03*
X1654015Y217239D03*
X1643775Y246137D03*
X1638216Y246021D03*
X1687550Y213751D03*
X1672265Y473600D03*
X1779303Y497246D03*
X1895330Y64390D03*
X1880986Y53299D03*
X1909406Y76790D03*
X1918379Y84788D03*
X1933914Y96040D03*
X1945156Y160236D03*
X1928100Y136078D03*
X1950983Y147344D03*
X1940500Y157600D03*
X1937100Y206800D03*
X1944500Y183900D03*
X1950994Y173745D03*
X1939316Y173600D03*
X1940240Y169970D03*
X1939550Y165600D03*
X1939400Y198400D03*
X1943800Y241800D03*
X1943900Y238500D03*
X1925600Y242700D03*
X1971200Y152500D03*
X1967817Y201029D03*
X1965900Y184600D03*
X1965057Y176447D03*
X1966542Y179606D03*
G54D57*
X480052Y210346D03*
X531871Y202547D03*
X525111D03*
X483432Y212296D03*
Y239596D03*
X525111Y323446D03*
X521731Y329296D03*
X525111Y319547D03*
X528491Y321496D03*
X487932Y356596D03*
X531871Y331247D03*
X528491Y333196D03*
X518352Y335147D03*
X521731Y340996D03*
Y337096D03*
X535251Y344896D03*
X542011D03*
Y340996D03*
Y337096D03*
X538631Y331247D03*
Y327347D03*
X535251Y340996D03*
X538631Y342947D03*
X542011Y333196D03*
Y329296D03*
Y325396D03*
X538631Y323446D03*
X535251Y337096D03*
X528491Y340996D03*
X531871Y339047D03*
Y342947D03*
X528491Y344896D03*
X511592Y362447D03*
X514972Y368296D03*
X508212Y364396D03*
X498072Y378047D03*
X494692Y379996D03*
Y387796D03*
X518352Y350747D03*
Y354647D03*
X511592Y358547D03*
X514972Y360496D03*
Y364396D03*
X511592Y366347D03*
X508212Y368296D03*
Y372197D03*
X504832Y374146D03*
X501452Y376096D03*
X498072Y381947D03*
X494692Y383896D03*
X518352Y346847D03*
X521731Y352696D03*
X511592Y354647D03*
X498072Y374146D03*
X528491Y387796D03*
X521731D03*
Y391696D03*
X518352Y393647D03*
X514972Y395597D03*
X511592Y389747D03*
X528491Y379996D03*
Y383896D03*
X525111Y385847D03*
X521731Y383896D03*
X525111Y389747D03*
X521731Y395597D03*
X514972Y391696D03*
Y387796D03*
X528491Y376096D03*
X531871Y381947D03*
X535251Y348796D03*
X538631Y346847D03*
Y354647D03*
Y358547D03*
Y362447D03*
X531871D03*
Y366347D03*
X535251Y372197D03*
Y379996D03*
X538631Y350747D03*
X542011Y356596D03*
X535251Y360496D03*
X531871Y358547D03*
X535251Y364396D03*
Y368296D03*
X538631Y374146D03*
X531871Y378047D03*
X525111Y346847D03*
X528491Y348796D03*
Y352696D03*
X511592Y401447D03*
X508212Y383896D03*
X514972Y376096D03*
X504832Y401446D03*
X552151Y331247D03*
Y335147D03*
Y342947D03*
X548771Y344896D03*
Y333196D03*
X552151Y339047D03*
X555531Y340996D03*
X545391Y327347D03*
Y339047D03*
X562591Y340996D03*
X558911Y339047D03*
X555531Y344896D03*
X562591Y337096D03*
X555531D03*
X552151Y346847D03*
X548771Y387796D03*
X552151Y385847D03*
X555531Y352696D03*
Y348796D03*
X552151Y354647D03*
X558911Y350747D03*
X559211Y366347D03*
X555531Y379996D03*
X552151Y381947D03*
X558911Y354647D03*
X552151Y362447D03*
X545391Y350747D03*
X548771Y348796D03*
X947887Y324160D03*
X937747Y322209D03*
X941127Y324160D03*
G54D55*
X99980Y136909D03*
X1472000Y-5000D03*
Y-15000D03*
X1462000Y-5000D03*
Y-15000D03*
X1452000Y-5000D03*
Y-15000D03*
X1442000Y-5000D03*
Y-15000D03*
X1525000D03*
X1515000D03*
X1505000D03*
X1482000D03*
X1492000Y-5000D03*
Y-15000D03*
X1482000Y-5000D03*
X1575000Y-15000D03*
X1565000D03*
X1555000D03*
X1545000D03*
X1535000D03*
X1713503Y-5000D03*
X1703503D03*
Y-15000D03*
X1743503D03*
X1733503Y-5000D03*
Y-15000D03*
X1723503Y-5000D03*
Y-15000D03*
X1753503Y-5000D03*
Y-15000D03*
X1743503Y-5000D03*
X1779504D03*
X1769504D03*
Y-15000D03*
X1809504D03*
X1799504Y-5000D03*
Y-15000D03*
X1789504Y-5000D03*
Y-15000D03*
X1819504Y-5000D03*
Y-15000D03*
X1809504Y-5000D03*
G54D53*
X1859854Y501441D03*
X1952756Y589960D03*
X1944882Y582086D03*
X1952756D03*
X1944882Y574212D03*
X1952756D03*
X1944882Y566338D03*
X1952756D03*
X1944882Y558464D03*
Y589960D03*
X1952756Y558464D03*
X1944882Y605708D03*
X1952756D03*
X1944882Y597834D03*
X1952756D03*
X1854501Y195587D03*
G54D47*
X1638131Y475946D03*
G54D23*
X40500Y-42250D03*
Y-52250D03*
X60500Y-42250D03*
X80500D03*
X100500D03*
X60500Y-52250D03*
X80500D03*
X100500D03*
X120500Y-42250D03*
X140500D03*
X120500Y-52250D03*
X140500D03*
X467246Y-52301D03*
Y-42301D03*
X487246Y-52301D03*
Y-42301D03*
X507246Y-52301D03*
Y-42301D03*
X527246Y-52301D03*
Y-42301D03*
X547246Y-52301D03*
Y-42301D03*
X567246Y-52301D03*
Y-42301D03*
X798984Y-52057D03*
Y-42057D03*
X818984Y-52057D03*
Y-42057D03*
X838984Y-52057D03*
Y-42057D03*
X858984Y-52057D03*
Y-42057D03*
X878984Y-52057D03*
Y-42057D03*
X898984Y-52057D03*
Y-42057D03*
X1135583Y-52285D03*
Y-42285D03*
X1155583Y-52285D03*
Y-42285D03*
X1392258Y-52257D03*
Y-42257D03*
X1412258Y-52257D03*
Y-42257D03*
X1432258Y-52257D03*
Y-42257D03*
X1452258Y-52257D03*
Y-42257D03*
X12290Y264640D03*
G54D54*
X1851250Y584622D03*
Y576748D03*
Y568874D03*
Y561000D03*
X1724807Y451179D03*
G54D50*
X1674921Y528523D03*
X1773347D03*
Y545059D03*
G54D41*
X-15748Y116969D03*
Y132717D03*
Y373110D03*
Y388858D03*
X787Y132717D03*
X28740Y124843D03*
Y140591D03*
X787Y388858D03*
X28740Y380984D03*
Y396732D03*
G54D29*
X1288068Y454425D03*
X638541D03*
Y171945D03*
X1288068D03*
G54D43*
X-11811Y313504D03*
Y337126D03*
X3937Y313504D03*
X-3937D03*
X3937Y337126D03*
X-3937D03*
X27559Y204370D03*
X35433Y337126D03*
X27559D03*
X35433Y313504D03*
X27559D03*
G54D34*
X40512Y467244D03*
X30512D03*
G54D51*
X1809665Y618663D03*
X1819665D03*
X1829665D03*
G54D44*
X-14488Y434094D03*
X89980Y145531D03*
X99980D03*
X119980D03*
G54D38*
X1466694Y375787D03*
G54D42*
X-7874Y216181D03*
Y325315D03*
G54D31*
X637793Y88678D03*
Y50878D03*
Y69778D03*
Y514079D03*
X94683Y31978D03*
Y13078D03*
Y69778D03*
Y50878D03*
X637793Y-5822D03*
Y13078D03*
X94683Y532955D03*
Y570755D03*
Y589679D03*
Y551879D03*
X637793Y570755D03*
Y589679D03*
Y608555D03*
X744293Y69778D03*
Y50878D03*
Y570755D03*
Y589679D03*
Y608555D03*
X1287403Y532955D03*
Y551879D03*
Y608555D03*
X744293Y-5822D03*
X1287403D03*
Y31978D03*
Y13078D03*
Y69778D03*
Y50878D03*
G54D46*
X-1969Y178386D03*
X44291D03*
G54D22*
X-3937Y-43307D03*
X1956693D03*
X-3937Y646063D03*
X1956693D03*
G54D39*
X1611283Y615236D03*
G54D61*
X1950000Y220787D03*
G54D40*
X1705772Y567874D03*
G54D58*
X1955506Y454297D03*
X1699600D03*
Y235400D03*
G54D37*
X783171Y183126D03*
X1454685Y338189D03*
G54D36*
X0Y0D03*
G54D30*
X1149606Y439173D03*
Y163582D03*
X976378Y439173D03*
Y163582D03*
X602362Y387992D03*
X500000Y439173D03*
Y163582D03*
X326772Y439173D03*
Y163582D03*
X224410Y301378D03*
X602362Y214764D03*
X874016Y301378D03*
X1251969Y214764D03*
Y387992D03*
%LPD*%
G75*
G36*
G01X1430600Y188700D02*
X1429700Y189600D01*
Y246700D01*
X1431500Y248500D01*
X1433450D01*
X1433500Y248375D01*
G03X1436100I1300J525D01*
G01X1436150Y248500D01*
X1436900D01*
X1438300Y247100D01*
Y245985D01*
G02X1437795Y245599I-400J0D01*
G03Y242701I-395J-1449D01*
G02X1438300Y242315I105J-386D01*
G01Y209715D01*
G03Y207285I700J-1215D01*
G01Y190100D01*
X1436900Y188700D01*
X1430600D01*
G37*
G36*
G01X1476891Y412832D02*
X1472523Y417200D01*
X1455000D01*
X1444214Y427986D01*
Y428039D01*
X1443805Y428448D01*
Y429936D01*
G02X1444404Y430283I400J0D01*
G03X1446178Y430604I696J1217D01*
G02X1446804Y430591I308J-255D01*
G03Y432409I1196J909D01*
G02X1446178Y432396I-318J242D01*
G03X1444404Y432717I-1078J-896D01*
G02X1443805Y433064I-199J347D01*
G01Y435383D01*
G02X1444381Y435742I400J0D01*
G03X1446119Y436155I619J1258D01*
G02X1446767Y436143I320J-241D01*
G03Y437857I1233J857D01*
G02X1446119Y437845I-328J229D01*
G03X1444381Y438258I-1119J-845D01*
G02X1443805Y438617I-176J359D01*
G01Y440799D01*
G02X1444337Y441177I400J0D01*
G03X1445878Y441604I463J1323D01*
G02X1446504Y441591I308J-255D01*
G03Y443409I1196J909D01*
G02X1445878Y443396I-318J242D01*
G03X1444337Y443823I-1078J-896D01*
G02X1443805Y444201I-132J378D01*
G01Y446222D01*
G02X1444270Y446617I400J0D01*
G03X1445619Y447155I230J1383D01*
G02X1446267Y447143I320J-241D01*
G03Y448857I1233J857D01*
G02X1445619Y448845I-328J229D01*
G03X1444270Y449383I-1119J-845D01*
G02X1443805Y449778I-65J395D01*
G01Y564859D01*
X1445835Y566889D01*
X1514960D01*
X1515184Y566665D01*
Y532085D01*
G02X1514636Y531714I-400J0D01*
G03X1513255Y531516I-518J-1303D01*
G02X1512649Y531657I-246J315D01*
G03X1510152Y531707I-1261J-612D01*
G02X1509572Y531568I-352J189D01*
G03X1507556Y531113I-799J-1152D01*
G02X1506852Y531132I-347J199D01*
G03X1504666Y531546I-1252J-632D01*
G02X1504134I-266J298D01*
G03Y529454I-934J-1046D01*
G02X1504666I266J-298D01*
G03X1506816Y529803I934J1046D01*
G02X1507520Y529784I347J-199D01*
G03X1510008Y529754I1252J632D01*
G02X1510588Y529893I352J-189D01*
G03X1512251Y529940I800J1152D01*
G02X1512857Y529799I246J-315D01*
G03X1514636Y529108I1261J612D01*
G02X1515184Y528737I148J-371D01*
G01Y489288D01*
G02X1514793Y488888I-400J0D01*
G03Y486084I32J-1402D01*
G02X1515184Y485684I-9J-400D01*
G01Y482528D01*
G02X1514793Y482128I-400J0D01*
G03X1515478Y479485I32J-1402D01*
G01X1515608Y479554D01*
X1516044Y479118D01*
G02X1515986Y478505I-283J-282D01*
G03X1517934Y476557I789J-1159D01*
G02X1518547Y476615I331J-225D01*
G01X1519114Y476048D01*
G02X1518808Y475366I-283J-283D01*
G03X1520125Y474049I-83J-1400D01*
G02X1520807Y474355I399J23D01*
G01X1521221Y473941D01*
X1521227Y473866D01*
G03X1522525Y472568I1398J100D01*
G01X1522600Y472562D01*
X1523576Y471586D01*
X1523468Y471446D01*
G03X1525567Y469595I1107J-860D01*
G01X1526042Y469120D01*
G02X1525929Y468475I-283J-283D01*
G03X1527882Y466854I596J-1269D01*
G01X1527896Y466906D01*
X1528076Y467086D01*
X1528389Y466773D01*
Y465235D01*
X1528225Y465205D01*
G03Y462447I250J-1379D01*
G01X1528389Y462417D01*
Y458475D01*
X1528225Y458445D01*
G03X1527362Y456214I250J-1379D01*
G02X1527289Y455655I-318J-243D01*
G03X1528024Y453149I858J-1109D01*
G02X1528389Y452751I-35J-398D01*
G01Y446269D01*
X1529886Y444772D01*
X1529900Y444722D01*
G03X1530872Y443750I1350J378D01*
G01X1530922Y443736D01*
X1531152Y443506D01*
X1530971Y443325D01*
X1530917Y443312D01*
G03X1532612Y441617I333J-1362D01*
G01X1532625Y441671D01*
X1532806Y441852D01*
X1533036Y441622D01*
X1533050Y441572D01*
G03X1534022Y440600I1350J378D01*
G01X1534072Y440586D01*
X1535402Y439256D01*
Y434133D01*
X1535508Y434026D01*
Y433898D01*
X1536702Y432704D01*
X1540280D01*
X1542750Y430234D01*
X1542665Y430099D01*
G03X1542927Y428295I1185J-749D01*
G01Y427255D01*
G03Y425145I923J-1055D01*
G01Y422700D01*
X1542290Y422063D01*
X1520860D01*
X1520649Y421852D01*
X1520647D01*
X1519672Y420876D01*
X1519532Y420990D01*
G03X1517560Y419018I-882J-1090D01*
G01X1517674Y418878D01*
X1516522Y417726D01*
X1516382Y417840D01*
G03X1514405Y415875I-882J-1090D01*
G01X1514516Y415735D01*
X1511613Y412832D01*
X1510964D01*
G02X1510572Y413314I0J400D01*
G03X1507828I-1372J286D01*
G02X1507436Y412832I-392J-82D01*
G01X1476891D01*
G37*
G36*
G01X1566962Y404435D02*
X1564517Y406880D01*
X1564638Y407020D01*
G03X1562661Y408997I-1063J914D01*
G01X1562521Y408876D01*
X1562031Y409366D01*
G02X1562161Y410018I283J283D01*
G03X1560329Y411850I-536J1296D01*
G02X1559677Y411720I-369J153D01*
G01X1558626Y412771D01*
X1542450D01*
G02X1542062Y413266I0J400D01*
G03X1539475Y414281I-1362J334D01*
G02X1538775I-350J194D01*
G03X1536303Y414241I-1225J-681D01*
G02X1535604Y414219I-356J183D01*
G03X1535647Y412859I-1204J-719D01*
G02X1536346Y412881I356J-183D01*
G03X1536475Y412700I1203J721D01*
G02X1536451Y412161I-307J-256D01*
G01X1533295Y409005D01*
X1533158Y409097D01*
G03X1531212Y407151I-783J-1163D01*
G01X1531304Y407014D01*
X1531016Y406726D01*
X1526307D01*
G02X1525922Y407237I-1J400D01*
G03X1523228I-1347J387D01*
G02X1522843Y406726I-384J-111D01*
G01X1520092D01*
X1520052Y406873D01*
G03X1517544Y407293I-1352J-373D01*
G02X1516931Y407237I-330J226D01*
G01X1515360Y408808D01*
Y411999D01*
G02X1515552Y412199I200J0D01*
G03X1516181Y414825I-52J1401D01*
G02Y415525I194J350D01*
G03X1516725Y416069I-681J1225D01*
G02X1517425I350J-194D01*
G03X1519331Y417975I1225J681D01*
G02Y418675I194J350D01*
G03X1519875Y419219I-681J1225D01*
G02X1520575I350J-194D01*
G03X1523025I1225J681D01*
G02X1523725I350J-194D01*
G03X1526189Y420556I1225J681D01*
G01X1526166Y420600D01*
Y420850D01*
X1526402D01*
G02X1526639Y420928I237J-322D01*
G01X1529561D01*
G02X1529936Y420389I0J-400D01*
G03X1532475Y419219I1314J-488D01*
G02X1533175I350J-194D01*
G03X1535625I1225J681D01*
G02X1536325I350J-194D01*
G03X1538775I1225J681D01*
G02X1539475I350J-194D01*
G03X1542014Y420389I1225J682D01*
G02X1542389Y420928I375J139D01*
G01X1544009D01*
X1545832Y419104D01*
X1549190D01*
X1550346Y420260D01*
G02X1550931Y420240I283J-282D01*
G03X1552021Y422560I1059J918D01*
G02X1551630Y422960I9J400D01*
G01Y426026D01*
X1552649Y427045D01*
X1552664Y427055D01*
G03X1553036Y427428I-789J1159D01*
G01X1553039Y427431D01*
X1562412D01*
G03X1564738I1163J783D01*
G01X1572368D01*
X1573266Y426533D01*
X1580528D01*
X1580556Y426366D01*
G03X1583322I1383J228D01*
G01X1583350Y426533D01*
X1584037D01*
X1584076Y426494D01*
X1585016D01*
X1589597Y431075D01*
X1589704Y431050D01*
G03X1591502Y432848I333J1465D01*
G01X1591477Y432955D01*
X1601641Y443119D01*
X1601777Y443030D01*
G03X1603857Y445110I823J1257D01*
G01X1603768Y445246D01*
X1611842Y453320D01*
X1611903Y453331D01*
G03X1613116Y454544I-265J1478D01*
G01X1613127Y454605D01*
X1616302Y457780D01*
Y462311D01*
G03Y464003I-1241J846D01*
G01Y468045D01*
G02X1616682Y468445I400J0D01*
G03X1617792Y469022I-75J1500D01*
G02X1618422I315J-246D01*
G03Y470868I1185J923D01*
G02X1617792I-315J246D01*
G03X1616682Y471445I-1185J-923D01*
G02X1616302Y471845I20J400D01*
G01Y474338D01*
G02X1616912Y474678I400J0D01*
G03X1618568Y474731I788J1279D01*
G02X1619177Y474537I231J-326D01*
G03X1619737Y476176I1323J463D01*
G02X1619137Y476395I-217J336D01*
G03X1618482Y477239I-1437J-439D01*
G02X1618407Y477864I208J342D01*
G01X1619883Y479340D01*
Y497291D01*
G02X1620583Y497556I400J0D01*
G03Y499678I1200J1061D01*
G02X1619883Y499943I-300J265D01*
G01Y500157D01*
X1619675Y500365D01*
X1619659D01*
X1615524Y504500D01*
X1615472D01*
X1601168Y518805D01*
G02X1601397Y519484I283J283D01*
G03X1596366Y533811I-1042J7681D01*
G02X1595760Y534154I-206J343D01*
G01Y545073D01*
X1595454Y545378D01*
X1595300Y545532D01*
Y545600D01*
X1593231Y547669D01*
Y567661D01*
X1594369Y568799D01*
X1600314D01*
Y568325D01*
G03X1600865Y567157I1512J-1D01*
G02X1600920Y566594I-254J-309D01*
G03X1602952Y566729I1080J-894D01*
G02X1602931Y567295I272J293D01*
G03X1603327Y568156I-1106J1030D01*
G01X1603336Y568240D01*
Y568325D01*
X1603337D01*
X1603336D01*
Y568799D01*
X1605348D01*
X1605708Y568439D01*
X1605700Y568346D01*
G03X1607429Y563808I5583J-471D01*
G02X1607233Y563125I-275J-291D01*
G03X1606022Y561645I300J-1481D01*
G01Y557644D01*
G03X1608053Y556225I1511J0D01*
G02X1608554Y556016I137J-376D01*
G03X1609530Y557969I1275J583D01*
G02X1609044Y558359I-86J391D01*
G01Y559681D01*
G02X1609586Y560055I400J0D01*
G03X1611337Y561987I494J1312D01*
G02X1611509Y562276I179J89D01*
G03X1611756Y562291I-216J5599D01*
G01X1611848Y562299D01*
X1620900Y553247D01*
Y527012D01*
G02X1620406Y526623I-400J0D01*
G03Y523509I-376J-1557D01*
G02X1620900Y523120I94J-389D01*
G01Y512862D01*
X1632112Y501650D01*
Y473865D01*
G03X1632073Y471904I1247J-1006D01*
G01X1632112Y471851D01*
Y471454D01*
G03Y468894I963J-1280D01*
G01Y457525D01*
X1631859Y457272D01*
X1631677Y457454D01*
X1631664Y457510D01*
G03X1629068Y456188I-1464J-335D01*
G02Y455662I-302J-263D01*
G03X1628746Y454298I1132J-987D01*
G01X1628775Y454188D01*
X1627527Y452940D01*
X1627519D01*
Y452932D01*
X1620998Y446411D01*
X1620939Y446398D01*
G03X1619854Y445313I287J-1372D01*
G01X1619841Y445254D01*
X1619500Y444913D01*
X1614440Y439854D01*
G02X1613758Y440126I-282J283D01*
G03X1613290Y441177I-1502J-39D01*
G02X1613259Y441724I276J290D01*
G03X1611161Y441663I-1076J899D01*
G02Y441116I-292J-274D01*
G03X1612217Y438586I1095J-1028D01*
G02X1612490Y437904I-10J-400D01*
G01X1611078Y436492D01*
X1611039D01*
X1609099Y434552D01*
X1609108Y434522D01*
X1594114Y419528D01*
Y413738D01*
G03Y411662I1086J-1038D01*
G01Y410215D01*
X1593550Y409651D01*
G02X1592881Y409830I-283J283D01*
G03X1591302Y410937I-1451J-390D01*
G02X1590897Y411482I-33J398D01*
G03X1588486Y413143I-1397J553D01*
G02X1587960Y413131I-270J295D01*
G03X1588014Y410868I-960J-1155D01*
G02X1588540Y410880I270J-295D01*
G03X1589628Y410538I961J1155D01*
G02X1590033Y409993I33J-398D01*
G03X1591040Y407989I1397J-553D01*
G02X1591219Y407320I-104J-386D01*
G01X1588624Y404725D01*
X1588503Y404771D01*
G03X1586911Y404435I-535J-1403D01*
G01X1585007D01*
G02X1584608Y404859I0J400D01*
G03X1581808I-1400J82D01*
G02X1581409Y404435I-399J-24D01*
G01X1570835D01*
X1570825Y404625D01*
G03X1568025I-1400J-71D01*
G01X1568015Y404435D01*
X1566962D01*
G37*
G36*
G01X1550868Y427238D02*
G02X1550864Y426677I-287J-278D01*
G01X1550304Y426117D01*
X1550202Y426135D01*
G03X1550000Y423351I-237J-1382D01*
G02X1550410Y422952I10J-400D01*
G01Y421741D01*
X1548775Y420106D01*
X1546247D01*
X1543940Y422413D01*
Y424791D01*
X1544104Y424821D01*
G03X1544531Y427425I-254J1379D01*
G02Y428125I194J350D01*
G03X1543750Y430748I-682J1225D01*
G01X1543659Y430742D01*
X1540695Y433706D01*
X1537117D01*
X1536652Y434171D01*
X1536888Y434407D01*
X1537012Y434355D01*
G03X1537052Y436961I538J1295D01*
G02X1536510Y437334I-142J374D01*
G01Y439567D01*
X1535255Y440822D01*
X1535396Y440963D01*
G03X1535625Y441269I-997J985D01*
G02X1536325I350J-194D01*
G03X1538775I1225J681D01*
G02X1539475I350J-194D01*
G03X1541925I1225J681D01*
G02X1542625I350J-194D01*
G03X1543209Y440703I1226J680D01*
G02X1543231Y440004I-183J-356D01*
G03Y437596I719J-1204D01*
G02X1543209Y436897I-205J-343D01*
G03X1544569Y436854I641J-1247D01*
G02X1544591Y437553I205J343D01*
G03Y440047I-641J1247D01*
G02X1544569Y440746I183J356D01*
G03X1544531Y443175I-719J1204D01*
G02Y443875I194J350D01*
G03X1543169I-681J1225D01*
G02Y443175I-194J-350D01*
G03X1542625Y442631I681J-1225D01*
G02X1541925I-350J194D01*
G03X1539475I-1225J-681D01*
G02X1538775I-350J194D01*
G03X1536325I-1225J-681D01*
G02X1535625I-350J194D01*
G03X1533439Y442971I-1225J-681D01*
G01X1533297Y442838D01*
X1533160Y442975D01*
X1533131Y442946D01*
X1529500Y446577D01*
Y450207D01*
G02X1530200Y450471I400J-1D01*
G03X1532475Y450719I1050J929D01*
G02X1533175I350J-194D01*
G03X1535625I1225J681D01*
G02X1536325I350J-194D01*
G03X1538775I1225J681D01*
G02X1539475I350J-194D01*
G03X1541925I1225J681D01*
G02X1542625I350J-194D01*
G03Y452081I1225J681D01*
G02X1541925I-350J194D01*
G03X1541335Y452650I-1226J-680D01*
G02X1541325Y453357I182J356D01*
G03X1541450Y455742I-672J1231D01*
G02X1541344Y456292I227J329D01*
G03X1539378Y455912I-1169J774D01*
G02X1539484Y455362I-227J-329D01*
G03X1540018Y453338I1169J-774D01*
G02X1540028Y452631I-182J-356D01*
G03X1539475Y452081I673J-1230D01*
G02X1538775I-350J194D01*
G03X1536325I-1225J-681D01*
G02X1535625I-350J194D01*
G03X1533175I-1225J-681D01*
G02X1532475I-350J194D01*
G03X1530200Y452329I-1225J-681D01*
G02X1529500Y452593I-300J265D01*
G01Y453892D01*
X1529518Y453931D01*
G03Y455161I-1371J615D01*
G01X1529500Y455200D01*
Y456109D01*
G03Y458023I-1025J957D01*
G01Y458723D01*
G02X1530017Y459105I400J-1D01*
G03Y461787I408J1341D01*
G02X1529500Y462169I-117J383D01*
G01Y462869D01*
G03Y464783I-1025J957D01*
G01Y465483D01*
G02X1530017Y465865I400J-1D01*
G03X1529477Y468239I408J1341D01*
G02X1528924Y468251I-270J295D01*
G01X1528622Y468553D01*
G02X1528809Y469224I283J283D01*
G03X1527113Y470920I-334J1362D01*
G02X1526442Y470733I-388J96D01*
G01X1523869Y473306D01*
X1523920Y473429D01*
G03X1522088Y475261I-1295J537D01*
G01X1521965Y475210D01*
X1521518Y475657D01*
G02X1521551Y476252I283J283D01*
G03X1519581Y478222I-876J1094D01*
G02X1518986Y478189I-312J250D01*
G01X1518532Y478643D01*
G02X1518795Y479326I282J283D01*
G03X1517325Y480796I-70J1400D01*
G02X1516642Y480533I-400J19D01*
G01X1516209Y480966D01*
G03X1516200Y481015I-1386J-229D01*
G01Y482313D01*
G02X1516639Y482711I400J0D01*
G03Y485501I136J1395D01*
G02X1516200Y485899I-39J398D01*
G01Y487212D01*
X1516203Y487230D01*
G03Y487742I-1378J256D01*
G01X1516200Y487760D01*
Y561196D01*
G02X1516911Y561447I400J0D01*
G03Y563213I1089J883D01*
G02X1516200Y563464I-311J251D01*
G01Y567236D01*
X1520197Y571233D01*
X1531368D01*
X1531401Y571200D01*
X1564010D01*
G02X1564407Y570756I-1J-400D01*
G03X1564404Y570726I1393J-154D01*
G02X1564108Y570568I-199J17D01*
G03X1562457Y568333I-675J-1228D01*
G02X1562461Y567761I-278J-288D01*
G03X1562660Y565607I987J-995D01*
G02X1562738Y565015I-225J-331D01*
G03X1562671Y564931I1062J-916D01*
G01X1562510Y564850D01*
X1562359Y564919D01*
G03X1560287Y564969I-1059J-919D01*
G02X1559732Y564947I-289J277D01*
G03X1559813Y562931I-932J-1047D01*
G02X1560368Y562953I289J-277D01*
G03X1562313Y563031I932J1047D01*
G02X1562868Y563053I289J-277D01*
G03X1565193Y563943I932J1047D01*
G02X1565593Y564298I397J-45D01*
G03X1566646Y566634I7J1402D01*
G02Y567166I298J266D01*
G03X1566681Y568992I-1046J933D01*
G02X1566726Y569547I309J254D01*
G03X1567193Y570756I-926J1052D01*
G02X1567590Y571200I398J44D01*
G01X1568216D01*
X1578896Y560520D01*
X1578899Y560442D01*
G03X1580242Y559099I1401J58D01*
G01X1580320Y559096D01*
X1594758Y544658D01*
Y532528D01*
G03X1598900Y519551I5597J-5363D01*
G01X1598960Y519540D01*
X1599177Y519323D01*
X1599242Y519314D01*
X1618800Y499756D01*
Y491360D01*
G02X1618245Y490992I-400J1D01*
G03X1616727Y490710I-545J-1292D01*
G02X1616173I-277J288D01*
G03Y488690I-973J-1010D01*
G02X1616727I277J-288D01*
G03X1618475Y488531I973J1010D01*
G01X1618585Y488564D01*
G02X1618785Y488365I0J-200D01*
G01Y488111D01*
G02X1618800Y488001I-385J-109D01*
G01Y479800D01*
X1615815Y476815D01*
G02X1615210Y476860I-283J282D01*
G03X1612546Y476347I-1210J-890D01*
G02X1612014Y476075I-387J101D01*
G03X1612845Y474351I-508J-1307D01*
G02X1613389Y474598I382J-119D01*
G03X1614585Y474587I611J1372D01*
G02X1615141Y474219I156J-368D01*
G01Y471142D01*
G02X1614577Y470778I-400J1D01*
G03Y468222I-577J-1278D01*
G02X1615141Y467858I164J-365D01*
G01Y464854D01*
G02X1614955Y464655I-200J1D01*
G03Y461659I106J-1498D01*
G02X1615141Y461460I-14J-200D01*
G01Y458091D01*
X1612814Y455764D01*
X1612672Y455898D01*
G03X1610549Y453775I-1034J-1089D01*
G01X1610683Y453633D01*
X1602825Y445775D01*
X1602732Y445783D01*
G03X1602364Y445770I-131J-1496D01*
G02X1601901Y446152I-63J395D01*
G03X1600636Y444617I-1501J-52D01*
G02X1601099Y444235I63J-395D01*
G03X1601104Y444155I1501J54D01*
G01X1601112Y444062D01*
X1590842Y433792D01*
X1590712Y433857D01*
G03X1588960Y433562I-675J-1342D01*
G02X1588372Y433578I-287J279D01*
G03X1587189Y431092I-1134J-985D01*
G02X1587459Y430409I-13J-400D01*
G01X1585885Y428835D01*
G02X1585299Y428858I-282J283D01*
G03X1582861Y428234I-1066J-911D01*
G02X1582352Y427934I-391J82D01*
G03X1580962Y427600I-413J-1340D01*
G01X1574211D01*
X1573037Y428774D01*
X1564866D01*
X1564809Y428879D01*
G03X1562341I-1234J-665D01*
G01X1562284Y428774D01*
X1553166D01*
X1553109Y428879D01*
G03X1550868Y427238I-1234J-665D01*
G37*
%LPC*%
G75*
G36*
G01X1448806Y545659D02*
G03X1448196Y545641I-297J-268D01*
G02X1448138Y547583I-1174J937D01*
G03X1448748Y547601I297J268D01*
G02X1448806Y545659I1174J-937D01*
G37*
G36*
G01X1482927Y538690D02*
G03X1482373I-277J-288D01*
G02Y540710I-973J1010D01*
G03X1482927I277J288D01*
G02Y538690I973J-1010D01*
G37*
G36*
G01X1459798Y532547D02*
G03X1460402Y532525I312J251D01*
G02X1460331Y530557I1098J-1025D01*
G03X1459727Y530579I-312J-251D01*
G02X1459798Y532547I-1098J1025D01*
G37*
G36*
G01X1482713Y530068D02*
G03X1482187I-263J-302D01*
G02Y532332I-987J1132D01*
G03X1482713I263J302D01*
G02Y530068I987J-1132D01*
G37*
G36*
G01X1483227Y523190D02*
G03X1482673I-277J-288D01*
G02Y525210I-973J1010D01*
G03X1483227I277J288D01*
G02Y523190I973J-1010D01*
G37*
G36*
G01X1460140Y522578D02*
G03X1459531Y522505I-274J-291D01*
G02X1459317Y524293I-1174J766D01*
G03X1459926Y524366I274J291D01*
G02X1460140Y522578I1174J-766D01*
G37*
G36*
G01X1507320Y516655D02*
G03X1507113Y516413I-12J-200D01*
G02X1505569Y517508I-1370J-296D01*
G03X1505916Y517958I-49J397D01*
G02X1507441Y519657I1489J197D01*
G01X1507444Y519656D01*
X1509966D01*
X1509969Y519657D01*
G02X1510644Y519514I35J-1502D01*
G03X1511166Y519686I170J362D01*
G02X1511877Y517719I1234J-666D01*
G03X1511365Y517518I-150J-371D01*
G02X1509969Y516653I-1360J637D01*
G01X1509966Y516654D01*
X1507444D01*
X1507441Y516653D01*
G02X1507320Y516655I-36J1502D01*
G37*
G36*
G01X1483213Y514568D02*
G03X1482687I-263J-302D01*
G02Y516832I-987J1132D01*
G03X1483213I263J302D01*
G02Y514568I987J-1132D01*
G37*
G36*
G01X1498094Y517624D02*
X1500619D01*
G02Y514620I36J-1502D01*
G01X1498091D01*
G02X1497993Y514621I-34J1502D01*
G03X1497576Y514222I-17J-400D01*
G02X1496160Y515623I-1402J-1D01*
G03X1496555Y516044I-4J400D01*
G02X1498091Y517624I1500J78D01*
G01X1498094D01*
G37*
G36*
G01X1460140Y514014D02*
G03X1460081Y513441I246J-315D01*
G02X1458008Y513652I-1146J-971D01*
G03X1458067Y514225I-246J315D01*
G02X1460200Y516328I1146J971D01*
G03X1460726I263J302D01*
G02Y514064I987J-1132D01*
G03X1460200I-263J-302D01*
G02X1460140Y514014I-991J1128D01*
G37*
G36*
G01X1483659Y508533D02*
G03X1483443Y508292I-21J-199D01*
G02X1481939Y506473I-1468J-317D01*
G01X1481936Y506474D01*
X1479414D01*
X1479411Y506473D01*
G02X1478563Y506712I-34J1502D01*
G03X1478003Y506580I-216J-337D01*
G02X1477495Y508517I-1203J720D01*
G03X1478047Y508678I198J347D01*
G02X1479411Y509477I1328J-703D01*
G01X1479414Y509476D01*
X1481936D01*
X1481939Y509477D01*
G02X1481997I29J-1502D01*
G03X1482403Y509888I6J400D01*
G02X1485206Y509906I1401J40D01*
G03X1485624Y509500I400J-6D01*
G02X1485729Y509502I81J-1500D01*
G01X1488257D01*
G02X1489694Y508542I36J-1502D01*
G03X1490258Y508335I373J144D01*
G02X1489647Y506537I671J-1231D01*
G03X1489073Y506717I-366J-162D01*
G02X1488257Y506498I-782J1283D01*
G01X1485729D01*
G02X1484194Y508100I-36J1502D01*
G03X1483797Y508526I-399J26D01*
G02X1483659Y508533I2J1402D01*
G37*
G36*
G01X1512628Y503048D02*
Y503038D01*
G02X1511126Y501536I-1502J0D01*
G01X1508625D01*
G02X1508626Y504540I0J1502D01*
G01X1511126D01*
G02X1512628Y503048I0J-1502D01*
G37*
G36*
G01X1510691Y497863D02*
G03X1510080Y497857I-303J-261D01*
G02X1510061Y499667I-1080J894D01*
G03X1510672Y499673I303J261D01*
G02X1510691Y497863I1080J-894D01*
G37*
G36*
G01X1491455Y489341D02*
G03X1491749Y488850I387J-102D01*
G02X1490070Y487845I-324J-1364D01*
G03X1489776Y488336I-387J102D01*
G02X1491455Y489341I324J1364D01*
G37*
G36*
G01X1449553Y485874D02*
G03X1449150Y485457I-4J-400D01*
G02X1447764Y486797I-1401J-62D01*
G03X1448167Y487214I4J400D01*
G02X1450553Y488274I1401J62D01*
G03X1451119Y488278I281J285D01*
G02X1451077Y486212I1069J-1055D01*
G03X1450512Y486239I-296J-269D01*
G02X1449553Y485874I-944J1037D01*
G37*
G36*
G01X1455573Y464404D02*
G03X1455027I-273J-292D01*
G02X1452917Y464459I-1027J1096D01*
G03X1452356Y464475I-289J-277D01*
G02Y466525I-956J1025D01*
G03X1452917Y466541I272J293D01*
G02X1455027Y466596I1083J-1041D01*
G03X1455573I273J292D01*
G02X1457683Y466541I1027J-1096D01*
G03X1458244Y466525I289J277D01*
G02X1460156I956J-1025D01*
G03X1460717Y466541I272J293D01*
G02X1462827Y466596I1083J-1041D01*
G03X1463373I273J292D01*
G02X1465483Y466541I1027J-1096D01*
G03X1466044Y466525I289J277D01*
G02Y464475I956J-1025D01*
G03X1465483Y464459I-272J-293D01*
G02X1463373Y464404I-1083J1041D01*
G03X1462827I-273J-292D01*
G02X1460717Y464459I-1027J1096D01*
G03X1460156Y464475I-289J-277D01*
G02X1458244I-956J1025D01*
G03X1457683Y464459I-272J-293D01*
G02X1455573Y464404I-1083J1041D01*
G37*
G36*
G01Y458704D02*
G03X1455027I-273J-292D01*
G02X1452917Y458759I-1027J1096D01*
G03X1452356Y458775I-289J-277D01*
G02Y460825I-956J1025D01*
G03X1452917Y460841I272J293D01*
G02X1455027Y460896I1083J-1041D01*
G03X1455573I273J292D01*
G02X1457683Y460841I1027J-1096D01*
G03X1458244Y460825I289J277D01*
G02X1460156I956J-1025D01*
G03X1460717Y460841I272J293D01*
G02X1462827Y460896I1083J-1041D01*
G03X1463373I273J292D01*
G02X1465483Y460841I1027J-1096D01*
G03X1466044Y460825I289J277D01*
G02Y458775I956J-1025D01*
G03X1465483Y458759I-272J-293D01*
G02X1463373Y458704I-1083J1041D01*
G03X1462827I-273J-292D01*
G02X1460717Y458759I-1027J1096D01*
G03X1460156Y458775I-289J-277D01*
G02X1458244I-956J1025D01*
G03X1457683Y458759I-272J-293D01*
G02X1455573Y458704I-1083J1041D01*
G37*
G36*
G01Y453004D02*
G03X1455027I-273J-292D01*
G02X1452917Y453059I-1027J1096D01*
G03X1452356Y453075I-289J-277D01*
G02Y455125I-956J1025D01*
G03X1452917Y455141I272J293D01*
G02X1455027Y455196I1083J-1041D01*
G03X1455573I273J292D01*
G02X1457683Y455141I1027J-1096D01*
G03X1458244Y455125I289J277D01*
G02X1460156I956J-1025D01*
G03X1460717Y455141I272J293D01*
G02X1462827Y455196I1083J-1041D01*
G03X1463373I273J292D01*
G02X1465483Y455141I1027J-1096D01*
G03X1466044Y455125I289J277D01*
G02Y453075I956J-1025D01*
G03X1465483Y453059I-272J-293D01*
G02X1463373Y453004I-1083J1041D01*
G03X1462827I-273J-292D01*
G02X1460717Y453059I-1027J1096D01*
G03X1460156Y453075I-289J-277D01*
G02X1458244I-956J1025D01*
G03X1457683Y453059I-272J-293D01*
G02X1455573Y453004I-1083J1041D01*
G37*
G36*
G01X1463173Y448901D02*
G03X1462627I-273J-292D01*
G02X1460517Y448956I-1027J1096D01*
G03X1459956Y448972I-289J-277D01*
G02Y451022I-956J1025D01*
G03X1460517Y451038I272J293D01*
G02X1462627Y451093I1083J-1041D01*
G03X1463173I273J292D01*
G02X1465283Y451038I1027J-1096D01*
G03X1465844Y451022I289J277D01*
G02X1467811Y450968I956J-1025D01*
G03X1468389I289J277D01*
G02X1470411I1011J-971D01*
G03X1470989I289J277D01*
G02Y449026I1011J-971D01*
G03X1470411I-289J-277D01*
G02X1468389I-1011J971D01*
G03X1467811I-289J-277D01*
G02X1465844Y448972I-1011J971D01*
G03X1465283Y448956I-272J-293D01*
G02X1463173Y448901I-1083J1041D01*
G37*
G36*
G01X1504996Y433308D02*
G03X1504477Y433036I-133J-377D01*
G02X1503591Y434728I-1352J370D01*
G03X1504110Y435000I133J377D01*
G02X1504996Y433308I1352J-370D01*
G37*
G36*
G01X1460333Y431616D02*
G03X1460281Y431002I228J-329D01*
G02X1458451Y431116I-981J-1002D01*
G03X1458476Y431732I-242J318D01*
G02X1460526Y433927I1002J1119D01*
G03X1461083I278J287D01*
G02X1463177Y433929I1048J-1076D01*
G03X1463739Y433933I279J286D01*
G02X1465706Y433950I992J-991D01*
G03X1466272Y433960I278J287D01*
G02X1468460Y433936I1083J-1041D01*
G03X1469016Y433904I295J271D01*
G02X1470983Y433768I915J-1062D01*
G03X1471560Y433744I300J265D01*
G02X1471478Y431805I970J-1012D01*
G03X1470901Y431829I-300J-265D01*
G02X1468954Y431837I-969J1013D01*
G03X1468398Y431838I-279J-287D01*
G02X1466254Y431897I-1043J1081D01*
G03X1465688Y431917I-293J-272D01*
G02X1463811Y431884I-957J1025D01*
G03X1463250Y431849I-263J-301D01*
G02X1461083Y431775I-1119J1002D01*
G03X1460526I-278J-287D01*
G02X1460333Y431616I-1048J1076D01*
G37*
G36*
G01X1468940Y426991D02*
G03X1468377Y426976I-274J-291D01*
G02X1466178Y427003I-1087J1037D01*
G03X1465598Y427015I-296J-269D01*
G02X1465588Y428995I-998J985D01*
G03X1466169Y429012I282J283D01*
G02X1468377Y429050I1122J-999D01*
G03X1468940Y429035I289J276D01*
G02X1470852Y429042I960J-1022D01*
G03X1471407Y429053I272J293D01*
G02X1471448Y427034I993J-990D01*
G03X1470893Y427023I-272J-293D01*
G02X1468940Y426991I-993J990D01*
G37*
G36*
G01X1495528Y530151D02*
G02X1495133Y531647I-1328J449D01*
G03X1495778Y531817I266J298D01*
G02X1496173Y530321I1328J-449D01*
G03X1495528Y530151I-266J-298D01*
G37*
G36*
G01X1474542Y525426D02*
G02X1473431Y526778I-1402J-19D01*
G03X1473914Y527175I83J391D01*
G02X1475025Y525823I1402J19D01*
G03X1474542Y525426I-83J-391D01*
G37*
G36*
G01X1489743Y518244D02*
G02X1488278Y519206I-1333J-434D01*
G03X1488631Y519687I-38J398D01*
G02X1490136Y521502I1469J313D01*
G01X1492664D01*
G02X1492757Y521501I30J-1502D01*
G03X1492910Y521838I8J200D01*
G02X1494214Y521427I1020J962D01*
G03X1493960Y520818I82J-391D01*
G02X1492664Y518498I-1260J-818D01*
G01X1490136D01*
G02X1489953Y518505I-34J1502D01*
G03X1489743Y518244I-20J-199D01*
G37*
G36*
G01X1511174Y509182D02*
G02X1510031Y508532I41J-1401D01*
G03X1509671Y509145I-338J214D01*
G02X1509549Y509143I-86J1500D01*
G01X1509546Y509144D01*
X1507772D01*
G03X1507392Y508618I0J-400D01*
G02X1505452Y509444I-1332J-438D01*
G03X1505638Y509981I-173J361D01*
G02X1507021Y512147I1347J664D01*
G01X1507024Y512146D01*
X1509546D01*
X1509549Y512147D01*
G02X1510831Y509806I36J-1502D01*
G03X1511174Y509182I331J-224D01*
G37*
G36*
G01X1498181Y506386D02*
G02X1496892Y506674I-914J-1063D01*
G03X1497099Y507307I-107J385D01*
G02X1498313Y509741I1178J932D01*
G01X1498316Y509740D01*
X1500838D01*
X1500841Y509741D01*
G02Y506737I36J-1502D01*
G01X1500838Y506738D01*
X1498316D01*
X1498313Y506737D01*
X1498308D01*
G03X1498181Y506386I4J-200D01*
G37*
G36*
G01X1483483Y498148D02*
G02X1483451Y499700I-1183J752D01*
G03X1484117Y499714I328J229D01*
G02X1486557Y499582I1183J-752D01*
G03X1487268Y499568I359J177D01*
G02X1487243Y498280I1232J-668D01*
G03X1486532Y498294I-359J-177D01*
G02X1484149Y498162I-1232J668D01*
G03X1483483Y498148I-328J-229D01*
G37*
G36*
G01X1471973Y494854D02*
G02X1471770Y496133I-1330J445D01*
G03X1472470Y496245I321J239D01*
G02X1472673Y494966I1330J-445D01*
G03X1471973Y494854I-321J-239D01*
G37*
G36*
G01X1457378Y487031D02*
G02X1455817Y487025I-776J-1167D01*
G03X1455802Y487697I-224J331D01*
G02X1457388Y487703I788J1279D01*
G03X1457378Y487031I212J-339D01*
G37*
G36*
G01X1483895Y470616D02*
G02X1483894Y469186I1205J-716D01*
G03X1483205I-344J-204D01*
G02X1483206Y470616I-1205J716D01*
G03X1483895I344J204D01*
G37*
G36*
G01X1511165Y455164D02*
G02X1511145Y453875I1235J-664D01*
G03X1510435Y453886I-358J-179D01*
G02X1508116Y455440I-1234J665D01*
G03X1508067Y455998I-309J254D01*
G02X1510059Y456176I909J1068D01*
G03X1510108Y455618I309J-254D01*
G02X1510455Y455175I-908J-1068D01*
G03X1511165Y455164I358J179D01*
G37*
G36*
G01X1504495Y446629D02*
G02X1503769Y448171I-1370J297D01*
G03X1504344Y448442I184J355D01*
G02X1505070Y446900I1370J-297D01*
G03X1504495Y446629I-184J-355D01*
G37*
G36*
G01X1483958Y442059D02*
G02X1483346Y443607I-1355J359D01*
G03X1483945Y443843I212J339D01*
G02X1484557Y442295I1355J-359D01*
G03X1483958Y442059I-212J-339D01*
G37*
G36*
G01X1523025Y441269D02*
G02X1521119Y443175I-1225J681D01*
G03Y443875I-194J350D01*
G02Y446325I681J1225D01*
G03Y447025I-194J350D01*
G02X1520575Y447569I681J1225D01*
G03X1519875I-350J-194D01*
G02X1517425I-1225J681D01*
G03X1516725I-350J-194D01*
G02X1516181Y447025I-1225J681D01*
G03Y446325I194J-350D01*
G02X1514275Y444419I-681J-1225D01*
G03X1513575I-350J-194D01*
G02X1511125I-1225J681D01*
G03X1510425I-350J-194D01*
G02Y445781I-1225J681D01*
G03X1511125I350J194D01*
G02X1513575I1225J-681D01*
G03X1514275I350J194D01*
G02X1514819Y446325I1225J-681D01*
G03Y447025I-194J350D01*
G02X1514777Y449451I681J1225D01*
G03X1514753Y450151I-205J343D01*
G02X1516112Y450199I636J1249D01*
G03X1516136Y449499I205J-343D01*
G02X1516725Y448931I-636J-1249D01*
G03X1517425I350J194D01*
G02X1517996Y449490I1225J-681D01*
G03X1518002Y450195I-186J354D01*
G02X1519896Y452114I673J1230D01*
G03X1520590Y452108I349J196D01*
G02X1522481Y450175I1210J-708D01*
G03Y449475I194J-350D01*
G02X1523025Y448931I-681J-1225D01*
G03X1523725I350J194D01*
G02X1525631Y447025I1225J-681D01*
G03Y446325I194J-350D01*
G02Y443875I-681J-1225D01*
G03Y443175I194J-350D01*
G02X1523725Y441269I-681J-1225D01*
G03X1523025I-350J-194D01*
G37*
G36*
G01X1465770Y419370D02*
G02X1465310Y421175I-1245J644D01*
G03X1465898Y421339I224J331D01*
G02X1468495Y421568I1364J-628D01*
G03X1469143Y421556I328J229D01*
G02X1471258Y421698I1119J-845D01*
G03X1471821Y421693I284J281D01*
G02X1471804Y419702I979J-1004D01*
G03X1471241Y419707I-284J-281D01*
G02X1469143Y419866I-979J1004D01*
G03X1468495Y419854I-320J-241D01*
G02X1466364Y419507I-1233J857D01*
G03X1465770Y419370I-239J-321D01*
G37*
G36*
G01X1624353Y462838D02*
G03X1624133Y462351I161J-366D01*
G02X1621199Y461939I-1433J-451D01*
G03X1620732Y462344I-400J11D01*
G02X1621622Y464567I-232J1383D01*
G03X1622322Y464682I320J240D01*
G02X1624353Y462838I1427J-469D01*
G37*
G36*
G01X1620256Y453770D02*
G03X1620718Y453475I388J98D01*
G02X1619544Y451630I282J-1475D01*
G03X1619082Y451925I-388J-98D01*
G02X1620256Y453770I-282J1475D01*
G37*
G36*
G01X1559675Y420042D02*
X1555775D01*
G02Y422866I0J1412D01*
G01X1559676D01*
G02X1561086Y421464I-1J-1412D01*
G01Y421370D01*
X1561076Y421286D01*
G02X1559675Y420042I-1401J167D01*
G37*
G36*
G01X1557725Y416662D02*
X1553824D01*
G02X1553825Y419486I1J1412D01*
G01X1554448D01*
G02X1554998Y418963I0J-551D01*
G03X1555016Y418813I777J17D01*
G02X1555159Y418507I-1189J-742D01*
G03X1556391I616J472D01*
G02X1556534Y418813I1332J-436D01*
G03X1556550Y419022I-759J163D01*
G02X1557050Y419486I500J-37D01*
G01X1557725D01*
G02X1559136Y418084I0J-1411D01*
G01Y417990D01*
X1559126Y417906D01*
G02X1557725Y416662I-1401J167D01*
G37*
G36*
G01X1567475Y413282D02*
X1563574D01*
G02X1563575Y416106I1J1412D01*
G01X1564198D01*
G02X1564748Y415583I0J-551D01*
G03X1564766Y415433I777J17D01*
G02X1564909Y415127I-1189J-742D01*
G03X1566141I616J472D01*
G02X1566284Y415433I1332J-436D01*
G03X1566300Y415642I-759J163D01*
G02X1566800Y416106I500J-37D01*
G01X1567475D01*
G02X1568886Y414704I0J-1411D01*
G01Y414610D01*
X1568876Y414526D01*
G02X1567475Y413282I-1401J167D01*
G37*
G36*
G01X1571375Y406522D02*
X1567474D01*
G02X1567475Y409346I1J1412D01*
G01X1568098D01*
G02X1568648Y408823I0J-551D01*
G03X1568666Y408673I777J17D01*
G02X1568809Y408367I-1189J-742D01*
G03X1570041I616J472D01*
G02X1570184Y408673I1332J-436D01*
G03X1570200Y408882I-759J163D01*
G02X1570700Y409346I500J-37D01*
G01X1571375D01*
G02X1572786Y407944I0J-1411D01*
G01Y407850D01*
X1572776Y407766D01*
G02X1571375Y406522I-1401J167D01*
G37*
G36*
G01X1603899Y433762D02*
G02X1602160Y433733I-849J-1239D01*
G03X1602162Y434376I-237J322D01*
G02X1603875Y434405I838J1124D01*
G03X1603899Y433762I250J-313D01*
G37*
G36*
G01X1586980Y421813D02*
G02X1585719Y422818I-1420J-489D01*
G03X1586139Y423346I42J398D01*
G02X1587508Y425336I1420J489D01*
G03X1587895Y425723I-13J400D01*
G02X1589447Y424173I1501J-49D01*
G03X1589060Y423786I13J-400D01*
G02X1587400Y422341I-1501J49D01*
G03X1586980Y421813I-42J-398D01*
G37*
G36*
G01X1528781Y411775D02*
G02X1527419I-681J-1225D01*
G03Y412475I-194J350D01*
G02X1526896Y412981I680J1226D01*
G03X1526197Y412959I-343J-205D01*
G02X1526154Y414319I-1247J641D01*
G03X1526853Y414341I343J205D01*
G02X1528781Y412475I1247J-641D01*
G03Y411775I194J-350D01*
G37*
G36*
G01X1534733Y510723D02*
G03X1534654Y510095I203J-345D01*
G02X1532093Y509000I-1059J-1065D01*
G03X1531668Y509391I-400J-8D01*
G02X1532135Y512078I-88J1399D01*
G03X1532676Y512331I158J367D01*
G02X1534733Y510723I1344J-401D01*
G37*
G36*
G01X1568662Y504677D02*
G03X1569135Y505096I74J393D01*
G02X1570261Y502751I3463J220D01*
G03X1569638Y502643I-270J-296D01*
G02X1568662Y504677I-1238J657D01*
G37*
G36*
G01X1556520Y501002D02*
G03Y500448I288J-277D01*
G02X1554500I-1010J-973D01*
G03Y501002I-288J277D01*
G02X1554521Y502968I1010J972D01*
G03X1554502Y503553I-282J284D01*
G02X1554407Y505574I922J1056D01*
G03X1554394Y506137I-290J275D01*
G02X1554306Y508204I1044J1080D01*
G03Y508730I-302J263D01*
G02X1554574Y510945I1132J987D01*
G03X1554674Y511498I-230J327D01*
G02X1556700Y511187I1158J790D01*
G03X1556631Y510630I248J-314D01*
G02X1556570Y508730I-1193J-913D01*
G03Y508204I302J-263D01*
G02X1556470Y506126I-1132J-987D01*
G03X1556452Y505563I275J-291D01*
G02X1556413Y503616I-1028J-953D01*
G03X1556432Y503031I282J-284D01*
G02X1556520Y501002I-922J-1056D01*
G37*
G36*
G01X1543485Y500927D02*
G03Y500373I288J-277D01*
G02X1541465I-1010J-973D01*
G03Y500927I-288J277D01*
G02Y502873I1010J973D01*
G03Y503427I-288J277D01*
G02X1541450Y505356I1010J972D01*
G03X1541434Y505917I-293J272D01*
G02X1541379Y508027I1041J1083D01*
G03Y508573I-292J273D01*
G02X1541414Y510663I1096J1027D01*
G03X1541418Y511224I-283J283D01*
G02X1543468Y511264I1006J976D01*
G03X1543495Y510703I298J-267D01*
G02X1543571Y508573I-1020J-1103D01*
G03Y508027I292J-273D01*
G02X1543516Y505917I-1096J-1027D01*
G03X1543500Y505356I277J-289D01*
G02X1543485Y503427I-1025J-957D01*
G03Y502873I288J-277D01*
G02Y500927I-1010J-973D01*
G37*
G36*
G01X1549310Y500527D02*
G03Y499973I288J-277D01*
G02X1547290I-1010J-973D01*
G03Y500527I-288J277D01*
G02X1547238Y502415I1010J973D01*
G03X1547222Y502954I-303J261D01*
G02X1547259Y505083I1078J1046D01*
G03X1547275Y505644I-277J289D01*
G02Y507556I1025J956D01*
G03X1547259Y508117I-293J272D01*
G02X1547204Y510227I1041J1083D01*
G03Y510773I-292J273D01*
G02X1549396I1096J1027D01*
G03Y510227I292J-273D01*
G02X1549341Y508117I-1096J-1027D01*
G03X1549325Y507556I277J-289D01*
G02Y505644I-1025J-956D01*
G03X1549341Y505083I293J-272D01*
G02X1549378Y502954I-1041J-1083D01*
G03X1549362Y502415I287J-278D01*
G02X1549310Y500527I-1062J-915D01*
G37*
G36*
G01X1527529Y500207D02*
G03X1527514Y499639I274J-291D01*
G02X1525486I-1014J-968D01*
G03X1525471Y500207I-289J277D01*
G02X1524998Y501300I1029J1094D01*
G01Y503764D01*
G02X1525459Y504883I1502J36D01*
G03X1525475Y505444I-277J289D01*
G02X1527525I1025J956D01*
G03X1527541Y504883I293J-272D01*
G02X1528002Y503764I-1041J-1083D01*
G01Y501300D01*
G02X1527529Y500207I-1502J1D01*
G37*
G36*
G01X1532993Y500044D02*
G03X1533547Y499831I373J144D01*
G02X1532872Y498076I633J-1251D01*
G03X1532318Y498289I-373J-144D01*
G02X1530675Y500513I-633J1251D01*
G03Y501067I-288J277D01*
G02X1532253Y503322I1009J973D01*
G03X1532776Y503514I163J365D01*
G02X1532888Y503706I1263J-608D01*
G03X1532777Y504270I-328J228D01*
G02X1534782Y504609I818J1260D01*
G03X1534863Y504040I316J-245D01*
G02X1533471Y501624I-824J-1134D01*
G03X1532948Y501432I-163J-365D01*
G02X1532695Y501067I-1264J606D01*
G03Y500513I288J-277D01*
G02X1532993Y500044I-1011J-972D01*
G37*
G36*
G01X1604781Y488209D02*
G03X1605313Y488186I279J286D01*
G02X1605221Y486096I887J-1086D01*
G03X1604689Y486119I-279J-286D01*
G02X1604781Y488209I-887J1086D01*
G37*
G36*
G01X1600429Y478233D02*
G03X1599828I-301J-264D01*
G02Y480217I-1128J992D01*
G03X1600429I300J264D01*
G02Y478233I1128J-992D01*
G37*
G36*
G01X1595520Y473218D02*
G03X1596145Y473174I330J226D01*
G02X1596056Y471386I1033J-948D01*
G03X1595430Y471403I-320J-240D01*
G02X1595520Y473218I-1150J967D01*
G37*
G36*
G01X1589693Y453068D02*
G03X1590295Y453064I303J261D01*
G02X1590283Y451217I1049J-930D01*
G03X1589681Y451221I-303J-261D01*
G02X1587504Y451319I-1049J930D01*
G03X1586902Y451367I-322J-238D01*
G02X1584927Y451378I-982J1001D01*
G03X1584325Y451338I-284J-282D01*
G02X1584201Y453175I-1117J847D01*
G03X1584803Y453215I284J282D01*
G02X1587048Y453200I1117J-847D01*
G03X1587650Y453152I322J238D01*
G02X1589693Y453068I982J-1001D01*
G37*
G36*
G01X1589919Y441621D02*
G03X1590461Y441606I279J286D01*
G02X1590397Y439397I985J-1134D01*
G03X1589855Y439412I-279J-286D01*
G02X1589919Y441621I-985J1134D01*
G37*
G36*
G01X1565558Y501438D02*
G02X1563954Y501658I-958J-1024D01*
G03X1564042Y502305I-185J355D01*
G02X1564155Y504448I958J1024D01*
G03X1564143Y505096I-241J320D01*
G02X1564150Y507568I857J1234D01*
G03X1564210Y508178I-226J330D01*
G02X1566054Y508041I1000J982D01*
G03X1566023Y507429I241J-319D01*
G02X1565857Y505096I-1023J-1100D01*
G03X1565845Y504448I229J-328D01*
G02X1565646Y502085I-845J-1119D01*
G03X1565558Y501438I185J-355D01*
G37*
G36*
G01X1596016Y494058D02*
G02X1593522Y494530I-1136J822D01*
G03X1592902Y494755I-387J-100D01*
G02X1590840Y495052I-877J1220D01*
G03X1590210I-315J-246D01*
G02Y496898I-1185J923D01*
G03X1590840I315J246D01*
G02X1593492Y496296I1185J-923D01*
G03X1594104Y496048I391J85D01*
G02X1595579Y496095I775J-1168D01*
G03X1596115Y496226I199J347D01*
G02X1598723Y496090I1265J-810D01*
G03X1599437I357J179D01*
G02X1601950Y496358I1343J-674D01*
G03X1602536Y496318I311J251D01*
G02X1602453Y494367I964J-1018D01*
G03X1601865Y494378I-299J-266D01*
G02X1599437Y494742I-1086J1038D01*
G03X1598723I-357J-179D01*
G02X1596559Y494159I-1342J674D01*
G03X1596016Y494058I-219J-335D01*
G37*
G36*
G01X1570800Y480997D02*
G02X1569699Y482101I-1375J-271D01*
G03X1570170Y482571I78J392D01*
G02X1571271Y481467I1375J271D01*
G03X1570800Y480997I-78J-392D01*
G37*
G36*
G01X1589493Y473407D02*
G02Y471333I1087J-1037D01*
G03X1588930Y471348I-289J-276D01*
G02X1586803Y471593I-960J1022D01*
G03X1586137I-333J-222D01*
G02Y473147I-1167J777D01*
G03X1586803I333J222D01*
G02X1588930Y473392I1167J-777D01*
G03X1589493Y473407I274J291D01*
G37*
G54D24*
X1464553Y508872D03*
X1461267Y489790D03*
X1451533Y527867D03*
X1460661Y484891D03*
X1453533Y532667D03*
X1503400Y524663D03*
X1472500Y509810D03*
X1474400Y517200D03*
X1489380Y546030D03*
X1478700Y533700D03*
X1612100Y446000D03*
X1623705Y467855D03*
X1617300Y519000D03*
X1625485Y494188D03*
X1629500Y491500D03*
X1591350Y445300D03*
X1587573D03*
X1587550Y456550D03*
X1585155Y538574D03*
X1611642Y461877D03*
X1596500Y455500D03*
G54D25*
X1581730Y537170D03*
G54D26*
X1448800Y427800D03*
X1458300Y442675D03*
X1453700Y501600D03*
X1458060Y495020D03*
X1445750Y539000D03*
X1461500Y540000D03*
X1483400Y438100D03*
X1483115Y454379D03*
X1497275Y414694D03*
X1491425Y418074D03*
X1503125Y424834D03*
X1491425Y433406D03*
X1483818Y430597D03*
X1501219Y416596D03*
X1505442Y443900D03*
X1514825Y460446D03*
X1522625Y467206D03*
X1518725D03*
X1503125D03*
X1522625Y460446D03*
X1526525D03*
X1518725D03*
X1520675Y457066D03*
X1493375Y463826D03*
X1501175D03*
X1497275Y443546D03*
X1495325Y453686D03*
Y446926D03*
X1497275Y450306D03*
Y457066D03*
X1487525Y453686D03*
X1501175Y457066D03*
X1503125Y460446D03*
Y453786D03*
X1507025Y460446D03*
X1510925D03*
X1497275Y436786D03*
X1495325Y440166D03*
X1501175Y436786D03*
X1503125Y440166D03*
X1487525Y418074D03*
X1495325Y433406D03*
Y424834D03*
X1497275Y428214D03*
X1482500Y434600D03*
X1483200Y450455D03*
X1482000Y462028D03*
Y426595D03*
Y422658D03*
Y414783D03*
Y418720D03*
X1472449Y439421D03*
X1489475Y450306D03*
X1491425Y453686D03*
X1493375Y457066D03*
X1499225Y460446D03*
X1493375Y450306D03*
X1489475Y457066D03*
X1495325Y460446D03*
X1497275Y463826D03*
X1483375Y458375D03*
X1512875Y463826D03*
X1510925Y467206D03*
X1507025D03*
X1508975Y463826D03*
X1501175Y421454D03*
Y428214D03*
X1495325Y418074D03*
X1499225Y424834D03*
X1516775Y463826D03*
X1505075D03*
X1524575D03*
X1493375Y414694D03*
X1489475D03*
X1493375Y443546D03*
X1489475D03*
X1491425Y440166D03*
X1487525D03*
X1516775Y457066D03*
X1514825Y467206D03*
X1499225Y440166D03*
X1524575Y457066D03*
X1505075D03*
X1501175Y443546D03*
X1501200Y450600D03*
X1491425Y446926D03*
X1493375Y428214D03*
X1489475D03*
X1493375Y436786D03*
X1489475D03*
X1499225Y446926D03*
Y453686D03*
X1491425Y460446D03*
X1499225Y467206D03*
X1489475Y463826D03*
X1491425Y467206D03*
X1487525Y460446D03*
X1495325Y467206D03*
X1485030Y463690D03*
X1491400Y424600D03*
X1487500D03*
X1489475Y421454D03*
X1493375D03*
X1520675Y463826D03*
X1524950Y429350D03*
X1501490Y504988D03*
X1501934Y513047D03*
X1516775Y470586D03*
X1514825Y473966D03*
X1489475Y484106D03*
X1487525Y487486D03*
X1489475Y470586D03*
X1491425Y473966D03*
X1487525D03*
X1507025Y487486D03*
X1501175Y470586D03*
X1505075D03*
X1510925Y473966D03*
X1508975Y470586D03*
X1510925Y480726D03*
X1508975Y477346D03*
X1499225Y480726D03*
X1476800Y498900D03*
X1482000Y481713D03*
X1520675Y470586D03*
X1512875D03*
X1482200Y477800D03*
X1497275Y470586D03*
Y477346D03*
X1489475D03*
X1499225Y473966D03*
X1493375Y470586D03*
X1495325Y473966D03*
X1493375Y477346D03*
X1491425Y480726D03*
X1501175Y477346D03*
X1512875D03*
X1497275Y484106D03*
X1499225Y487486D03*
X1503125Y473966D03*
X1507025D03*
X1501175Y484106D03*
X1505075D03*
X1503125Y480726D03*
X1505075Y477346D03*
X1508975Y484106D03*
X1507025Y480726D03*
X1510925Y487486D03*
X1512875Y484106D03*
X1493375D03*
X1495325Y480726D03*
Y487486D03*
X1472250Y485100D03*
X1482958Y486118D03*
X1487525Y480726D03*
X1510740Y557860D03*
X1557725Y424834D03*
X1563575Y421454D03*
X1567475D03*
X1571375D03*
X1569425Y418074D03*
X1583208Y412815D03*
X1569425Y411314D03*
X1571375Y414694D03*
X1551875D03*
X1561625Y424834D03*
X1559675Y414694D03*
X1555775D03*
X1565525Y418074D03*
X1561625D03*
X1565525Y411314D03*
Y424834D03*
X1569425D03*
X1583208Y416752D03*
X1547000Y416750D03*
X1593400Y432200D03*
X1623814Y471400D03*
X1629530Y496374D03*
X1526525Y473966D03*
X1528475Y477346D03*
X1530425Y473966D03*
X1526525Y487486D03*
X1522625D03*
X1518725D03*
X1530425D03*
X1528475Y484106D03*
X1520675D03*
X1524575Y477346D03*
X1526525Y480726D03*
X1530425D03*
X1524575Y484106D03*
X1522625Y480726D03*
X1567475Y450306D03*
X1565525Y440166D03*
X1571375Y457066D03*
X1567475D03*
X1569425Y460446D03*
X1582200Y456200D03*
X1565525Y431594D03*
X1569425D03*
X1571390Y464480D03*
X1561625Y431594D03*
X1559675Y463826D03*
X1555775Y443546D03*
Y436786D03*
X1547975Y457066D03*
X1549925Y446926D03*
X1551875Y463826D03*
X1553825Y467206D03*
X1546025D03*
X1540175Y463826D03*
X1544075Y457066D03*
X1534325Y460446D03*
X1555775Y463826D03*
X1547975D03*
X1559675Y436786D03*
Y443546D03*
X1557725Y453686D03*
X1551875Y457066D03*
X1555775D03*
X1561625Y460446D03*
X1557725Y446926D03*
X1549938Y453714D03*
X1563575Y457066D03*
X1542125Y460446D03*
X1538225D03*
X1549925Y467206D03*
X1557725D03*
X1569425Y453686D03*
X1561625Y446926D03*
X1551875Y450306D03*
X1536275Y463826D03*
X1532375D03*
X1534325Y467206D03*
X1538225D03*
X1583773Y436137D03*
X1544075Y463826D03*
X1553825Y440166D03*
Y446926D03*
X1561625Y440166D03*
X1557725D03*
X1551875Y436786D03*
X1549925Y440166D03*
X1532349Y455200D03*
X1549925Y460446D03*
X1542125Y467206D03*
X1559595Y450631D03*
X1569425Y446926D03*
X1565525Y453686D03*
X1551875Y443546D03*
X1571375Y436786D03*
X1584200Y462610D03*
X1565525Y467206D03*
X1561625D03*
X1567475Y463826D03*
X1569425Y467206D03*
X1553825Y460446D03*
X1567475Y443546D03*
X1571375D03*
X1563575Y450306D03*
X1567475Y436786D03*
X1569425Y440166D03*
X1565525Y460446D03*
X1563575Y463826D03*
X1582300Y446100D03*
X1565525Y446926D03*
X1559675Y457066D03*
X1546025Y460446D03*
X1580370Y462090D03*
X1557725Y460446D03*
X1582644Y495077D03*
X1568600Y494500D03*
X1567817Y499735D03*
X1569425Y473966D03*
X1571375Y470586D03*
X1565525Y480726D03*
X1570062Y487039D03*
X1587433Y490425D03*
X1567475Y470586D03*
X1553825Y487486D03*
X1546025Y480726D03*
X1549925Y487486D03*
X1555775Y484106D03*
Y477346D03*
X1557725Y473966D03*
X1555775Y470586D03*
X1553825Y473966D03*
X1547975Y470586D03*
X1549925Y473966D03*
X1557725Y480726D03*
X1553825D03*
X1538225Y473966D03*
X1544075Y477346D03*
X1536275Y470586D03*
X1540175Y477346D03*
X1542125Y473966D03*
X1544075Y470586D03*
X1536275Y484106D03*
X1534325Y487486D03*
X1532375Y470586D03*
X1551875D03*
X1549925Y480726D03*
X1551875Y477346D03*
X1546025Y473966D03*
X1547975Y477346D03*
X1559675Y470586D03*
Y484106D03*
X1561625Y480726D03*
X1557725Y487486D03*
X1561625D03*
X1567475Y484106D03*
X1563575D03*
X1559675Y477346D03*
X1565525Y487486D03*
X1563575Y477346D03*
X1571375D03*
X1536275D03*
X1534325Y480726D03*
Y473966D03*
X1538225Y480726D03*
X1532375Y484106D03*
Y477346D03*
X1540175Y470586D03*
X1563575D03*
X1561625Y473966D03*
X1565525D03*
X1567475Y477346D03*
X1542125Y487486D03*
X1540175Y484106D03*
X1546025Y487486D03*
X1551875Y484106D03*
X1538225Y487486D03*
X1542125Y480726D03*
X1544075Y484106D03*
X1547975D03*
X1604200Y464387D03*
X1599900Y487100D03*
%LPD*%
G75*
G54D10*
X-17936Y-49379D03*
Y-53779D03*
Y-44979D03*
Y-40579D03*
X-18079Y-35764D03*
Y-58764D03*
X-17179Y643156D03*
X-17194Y638753D03*
X-17179Y647556D03*
Y660756D03*
Y651956D03*
Y656356D03*
X-13636Y-40479D03*
Y-44879D03*
Y-53679D03*
X-9079Y-50164D03*
X-4679D03*
X-279D03*
X-9079Y-54264D03*
X-4679D03*
X-279D03*
X22964Y-40379D03*
Y-44779D03*
Y-53579D03*
Y-49179D03*
X18964Y-53579D03*
Y-49179D03*
X13964Y-53579D03*
Y-49179D03*
X8964Y-40379D03*
Y-44779D03*
Y-53579D03*
Y-49179D03*
X3964Y-40379D03*
Y-44779D03*
Y-53579D03*
Y-49179D03*
X25921Y-35764D03*
X30321D03*
X43521D03*
X39121D03*
X34721D03*
X8321D03*
X12721D03*
X21521D03*
X17121D03*
X-13679D03*
X-9279D03*
X3921D03*
X-4879D03*
X-479D03*
X17121Y-58764D03*
X21521D03*
X12721D03*
X8321D03*
X34721D03*
X39121D03*
X43521D03*
X30321D03*
X25921D03*
X-479D03*
X-13679D03*
X-4879D03*
X3921D03*
X-13636Y-49279D03*
X-9279Y-58764D03*
X28868Y457576D03*
Y454576D03*
X20998Y457566D03*
Y454566D03*
X23598D03*
X26198D03*
Y457566D03*
X23598D03*
X22421Y647556D03*
X26821D03*
X31221D03*
X18021D03*
Y643156D03*
X31221D03*
X26821D03*
X22421D03*
X18006Y638753D03*
X9221Y647556D03*
X13621D03*
Y643156D03*
X9221D03*
X4821D03*
Y647556D03*
X22406Y638753D03*
X26806D03*
X31206D03*
X-12794D03*
X-12779Y647556D03*
Y643156D03*
X40006Y638753D03*
X44406D03*
X35606D03*
X35621Y647556D03*
Y643156D03*
X18021Y660756D03*
X35621Y656356D03*
X26821Y660756D03*
X18021Y651956D03*
X31221D03*
X22421Y660756D03*
X26821Y651956D03*
X22421D03*
X4821D03*
X13621D03*
X9221D03*
X-8379Y660756D03*
X4821Y656356D03*
X9221D03*
X13621D03*
X-3979D03*
X421D03*
X13621Y660756D03*
X-3979D03*
X421D03*
X4821D03*
X-12779Y651956D03*
X22421Y656356D03*
X26821D03*
X31221D03*
X18021D03*
X-8379D03*
X-12779D03*
X31221Y660756D03*
X35621Y651956D03*
Y660756D03*
X44421D03*
X40021D03*
X-12779D03*
X9221D03*
X107921Y-58764D03*
X102921D03*
X97921D03*
X92921D03*
X87921D03*
X82921D03*
X77921D03*
X72921D03*
X67921D03*
X62921D03*
X57921D03*
X52921D03*
X47921Y-35764D03*
Y-58764D03*
X107921Y-35764D03*
X102921D03*
X97921D03*
X92921D03*
X87921D03*
X82921D03*
X77921D03*
X72921D03*
X67921D03*
X62921D03*
X57921D03*
X52921D03*
X108174Y164127D03*
X103700Y397200D03*
X106400D03*
X101000D03*
X109100D03*
Y399900D03*
X101000D03*
X106400D03*
X103700D03*
X104517Y406279D03*
X105761Y409208D03*
X108010Y411479D03*
X48806Y638753D03*
X75206D03*
X106006D03*
X70806D03*
X53206D03*
X66406D03*
X92806D03*
X97206D03*
X101606D03*
X57606D03*
X62006D03*
X79606D03*
X84006D03*
X88406D03*
X53221Y660756D03*
X101621D03*
X97221D03*
X92821D03*
X106021D03*
X48821D03*
X70821D03*
X66421D03*
X62021D03*
X57621D03*
X75221D03*
X88421D03*
X84021D03*
X79621D03*
X167921Y-58764D03*
X162921D03*
X157921D03*
X152921D03*
X147921D03*
X142921D03*
X137921D03*
X132921D03*
X127921D03*
X122921D03*
X117921D03*
X112921D03*
X162921Y-35764D03*
X157921D03*
X152921D03*
X147921D03*
X142921D03*
X137921D03*
X132921D03*
X127921D03*
X122921D03*
X117921D03*
X112921D03*
X167921D03*
X166000Y212900D03*
X168600D03*
X164300Y207870D03*
X160800Y212900D03*
X163400D03*
X157800Y207300D03*
X161216Y209533D03*
Y206933D03*
X154500Y205500D03*
X150600Y212900D03*
X151000Y205500D03*
X140889Y211972D03*
X137615Y212039D03*
X143900Y204600D03*
X147500Y205500D03*
X137300Y204500D03*
X140200Y204400D03*
X153200Y212900D03*
X123624Y164600D03*
X139815Y268974D03*
X137900Y272800D03*
X139800Y237000D03*
X165825Y239543D03*
X168425Y236943D03*
Y239543D03*
X165825Y236943D03*
X163225D03*
X152825D03*
X145025D03*
X147625D03*
X150225D03*
X142425D03*
X122231Y234716D03*
X125564Y237816D03*
X122632D03*
X163225Y239543D03*
X158025Y236943D03*
X155425D03*
X160625D03*
X142371Y244384D03*
X122231Y266716D03*
X122531Y269816D03*
X125463D03*
X142466Y268982D03*
X142700Y276200D03*
X136729Y276386D03*
X139683Y276174D03*
X163225Y242143D03*
X168425Y244743D03*
X165825D03*
X163225D03*
X168425Y242143D03*
X165825D03*
X150700Y276800D03*
X169150Y259470D03*
Y255470D03*
X157633Y268727D03*
X162833D03*
X160233D03*
X165433D03*
X168033Y271327D03*
X162833Y276527D03*
Y273927D03*
Y271327D03*
X165433Y276527D03*
Y273927D03*
Y271327D03*
X159983Y276507D03*
X168033Y276527D03*
Y273927D03*
Y268727D03*
X153300Y276800D03*
X139866Y333016D03*
X160233Y306257D03*
Y308857D03*
Y303657D03*
X157518Y335391D03*
X157745Y332800D03*
X139900Y302400D03*
X142433Y301057D03*
X147633D03*
X150233D03*
X145033D03*
X125500Y333500D03*
X122231Y330716D03*
X122731Y333916D03*
X145200Y341300D03*
X148200D03*
X142465Y332940D03*
X152833Y301057D03*
X163233Y306257D03*
Y308857D03*
X168433Y306257D03*
Y308857D03*
Y301057D03*
X165833D03*
X163233D03*
X160633D03*
X158033D03*
X155433D03*
X169150Y287600D03*
Y291600D03*
X165833Y306257D03*
X163233Y303657D03*
X168433D03*
X165833D03*
Y308857D03*
X151000Y341300D03*
X169150Y323600D03*
Y319600D03*
X160501Y332965D03*
X160274Y335556D03*
X165701Y338165D03*
Y335565D03*
X163101Y332965D03*
X168301D03*
X165701D03*
X163101Y335565D03*
X168301Y340765D03*
Y338165D03*
Y335565D03*
X163101Y338165D03*
Y340765D03*
X165701D03*
X154200Y341100D03*
X125663Y301716D03*
X122231Y298716D03*
X122731Y301716D03*
X139767Y364883D03*
X147833Y364457D03*
X125600Y364900D03*
X122600Y365500D03*
X122331Y362716D03*
X142421Y364908D03*
X145033Y364457D03*
X142863Y402829D03*
X140219Y402894D03*
X137619Y402900D03*
X134992D03*
X142818Y400163D03*
X143073Y397194D03*
X140475Y397310D03*
X140218Y400163D03*
X137529Y400296D03*
X134929D03*
X111561Y398819D03*
X122000Y397600D03*
X125300Y397700D03*
X122231Y394716D03*
X150633Y364457D03*
X167433Y369657D03*
X169150Y355600D03*
Y351600D03*
X167700Y363900D03*
X161833Y364457D03*
X164633D03*
X159033D03*
X156233D03*
X153433D03*
X164633Y369657D03*
X161833D03*
X161933Y372357D03*
X164733D03*
X167533D03*
X166340Y374785D03*
X167670Y383993D03*
Y387993D03*
X110406Y638753D03*
X145606D03*
X141206D03*
X136806D03*
X132406D03*
X158806D03*
X119206D03*
X123606D03*
X114806D03*
X128006D03*
X163206D03*
X154406D03*
X167606D03*
X150006D03*
X132421Y660756D03*
X145621D03*
X141221D03*
X136821D03*
X123621D03*
X114821D03*
X128021D03*
X110421D03*
X119221D03*
X150021D03*
X167621D03*
X163221D03*
X158821D03*
X154421D03*
X182921Y-58764D03*
X177921D03*
X172921D03*
X227921Y-35764D03*
X222921D03*
X217921D03*
X212921D03*
X207921D03*
X202921D03*
X197921D03*
X192921D03*
X187921D03*
X182921D03*
X177921D03*
X227921Y-58764D03*
X222921D03*
X217921D03*
X212921D03*
X207921D03*
X202921D03*
X197921D03*
X192921D03*
X187921D03*
X172921Y-35764D03*
X176300Y211900D03*
X182300Y216108D03*
X179300D03*
Y213208D03*
X176300Y217308D03*
Y214500D03*
X173300Y217700D03*
Y214800D03*
Y211900D03*
X176400Y234300D03*
X176508Y231609D03*
X179400Y234300D03*
X182400D03*
X176400Y239900D03*
X182400D03*
X179400D03*
X173400D03*
Y231400D03*
Y234300D03*
Y237000D03*
X176400D03*
X182400D03*
X179400D03*
X188200Y236800D03*
X188300Y234000D03*
X185250Y239850D03*
X204200Y249500D03*
X201100Y246500D03*
X198200Y249500D03*
Y246500D03*
X201200Y249500D03*
X203900Y246500D03*
X207200Y249500D03*
X185768Y270065D03*
X173835Y277804D03*
X198082Y277995D03*
X203847Y274933D03*
X203947Y277933D03*
X188510Y272666D03*
X176835Y277804D03*
X182935Y278204D03*
Y275604D03*
X191400Y278400D03*
X188475Y270065D03*
X185735Y275604D03*
X188600Y278300D03*
X188535Y275604D03*
X185735Y278204D03*
X195300Y229250D03*
X188100Y239800D03*
X185250Y234250D03*
Y236950D03*
X176835Y275204D03*
X185754Y272689D03*
X179835Y277804D03*
Y275204D03*
X195100Y252000D03*
X201200Y252500D03*
X198200D03*
X204200D03*
X207200D03*
X200947Y277933D03*
X200847Y274933D03*
X200947Y280933D03*
X173835Y275204D03*
X230800Y265200D03*
X224390Y258920D03*
X219500Y254500D03*
X190800Y295500D03*
X196956Y295583D03*
X193800Y295500D03*
X190665Y306877D03*
X198119Y339710D03*
X191792Y327743D03*
X197792Y327643D03*
X194792D03*
X184800Y295500D03*
X187956Y295583D03*
X181800Y295500D03*
X201177Y330728D03*
Y333728D03*
Y336728D03*
X201163Y339476D03*
Y342476D03*
X204177Y336728D03*
X204060Y342527D03*
X204163Y339476D03*
X188654Y330973D03*
Y327973D03*
X197684Y307227D03*
X200251Y306548D03*
X188630Y333923D03*
X190570Y309539D03*
X185630Y333923D03*
X172800Y295500D03*
Y298400D03*
X198182Y280995D03*
X178956Y295583D03*
X175800Y295500D03*
X187900Y306900D03*
X191300Y339800D03*
X172800Y304000D03*
X175800D03*
X178800D03*
X187800D03*
X181800D03*
X184800D03*
X172800Y301100D03*
X175800D03*
X178800D03*
X181800D03*
X187800D03*
X184800D03*
Y298400D03*
X181800D03*
X175800D03*
X178800D03*
X187800D03*
X185300Y336900D03*
X173300Y337000D03*
Y339900D03*
X188300D03*
Y336900D03*
X179300Y337000D03*
X176300Y339900D03*
X179300D03*
X182300D03*
Y337000D03*
X198223Y342430D03*
X176300Y337000D03*
X185300Y339900D03*
X224000Y330900D03*
X229100Y325900D03*
X219000Y335900D03*
X214000Y340900D03*
X197730Y309959D03*
X204060Y345527D03*
X191300Y343248D03*
X173300Y343448D03*
X188300Y343348D03*
X201045Y345449D03*
X198233Y345402D03*
X195233D03*
X176300Y343448D03*
X201045Y348449D03*
X198233Y348402D03*
Y351402D03*
X195233D03*
X173424Y359621D03*
X188424D03*
X188400Y369787D03*
X176400D03*
X179400Y366787D03*
Y369787D03*
X176400Y366787D03*
X173400Y369787D03*
Y366787D03*
X199900Y370400D03*
X182400Y366787D03*
Y369787D03*
X185400Y366787D03*
Y369787D03*
X188400Y366787D03*
X182424Y359621D03*
X185424D03*
X176424D03*
X179424D03*
X182300Y343448D03*
X173471Y363281D03*
X188471D03*
X182471D03*
X185471D03*
X176471D03*
X179471D03*
X174750Y386308D03*
Y383308D03*
X171158Y382768D03*
Y385768D03*
Y388768D03*
X187100Y394000D03*
X190100Y393000D03*
X197411Y374812D03*
X199754Y376090D03*
X174750Y389308D03*
X199900Y373400D03*
X179300Y343448D03*
X185300Y343348D03*
X211606Y638753D03*
X224806D03*
X220406D03*
X216006D03*
X189606D03*
X198406D03*
X202806D03*
X207206D03*
X176406D03*
X172006D03*
X185206D03*
X180806D03*
X194006D03*
X226500Y649900D03*
X229206Y638753D03*
X224821Y660756D03*
X220421D03*
X198421D03*
X211621D03*
X189621D03*
X202821D03*
X207221D03*
X194021D03*
X185221D03*
X172021D03*
X176421D03*
X180821D03*
X229221D03*
X216021D03*
X292921Y-35764D03*
X287921D03*
X282921D03*
X277921D03*
X272921D03*
X267921D03*
X262921D03*
X257921D03*
X252921D03*
X247921D03*
X242921D03*
X237921D03*
X232921D03*
X292921Y-58764D03*
X287921D03*
X282921D03*
X277921D03*
X272921D03*
X267921D03*
X262921D03*
X257921D03*
X252921D03*
X247921D03*
X242921D03*
X237921D03*
X232921D03*
X234501Y270392D03*
X234000Y320900D03*
X290806Y638753D03*
X268806D03*
X273206D03*
X277606D03*
X282006D03*
X260006D03*
X264406D03*
X255606D03*
X251206D03*
X286406D03*
X242406D03*
X246806D03*
X233606D03*
X238006D03*
X286421Y660756D03*
X268821D03*
X282021D03*
X273221D03*
X277621D03*
X264421D03*
X251221D03*
X255621D03*
X260021D03*
X246821D03*
X242421D03*
X238021D03*
X233621D03*
X290821D03*
X352921Y-58764D03*
Y-35764D03*
X347921Y-58764D03*
Y-35764D03*
X342921Y-58764D03*
Y-35764D03*
X337921Y-58764D03*
Y-35764D03*
X332921Y-58764D03*
Y-35764D03*
X327921Y-58764D03*
Y-35764D03*
X322921Y-58764D03*
Y-35764D03*
X317921Y-58764D03*
Y-35764D03*
X312921Y-58764D03*
X307921D03*
Y-35764D03*
X302921Y-58764D03*
Y-35764D03*
X297921D03*
Y-58764D03*
X312921Y-35764D03*
X330406Y638753D03*
X348006D03*
X326006D03*
X312806D03*
X317206D03*
X321606D03*
X352406D03*
X295206D03*
X299606D03*
X308406D03*
X304006D03*
X334806D03*
X339206D03*
X343606D03*
X312821Y660756D03*
X317221D03*
X308421D03*
X304021D03*
X352421D03*
X295221D03*
X326021D03*
X321621D03*
X339221D03*
X299621D03*
X334821D03*
X330421D03*
X343621D03*
X348021D03*
X392921Y-35764D03*
X387921Y-58764D03*
Y-35764D03*
X382921Y-58764D03*
Y-35764D03*
X377921Y-58764D03*
Y-35764D03*
X372921Y-58764D03*
Y-35764D03*
X367921Y-58764D03*
Y-35764D03*
X362921Y-58764D03*
Y-35764D03*
X357921Y-58764D03*
Y-35764D03*
X392921Y-58764D03*
X402921Y-35764D03*
X397921Y-58764D03*
Y-35764D03*
X412921Y-58764D03*
Y-35764D03*
X407921Y-58764D03*
Y-35764D03*
X402921Y-58764D03*
X385494Y309904D03*
X367914Y309910D03*
X371237Y309846D03*
X389502Y309910D03*
X389528Y292910D03*
X392694Y292904D03*
X368116Y293087D03*
X371094Y292904D03*
X373736Y293068D03*
X382625Y293207D03*
X378294Y292904D03*
X385494D03*
X392694Y309904D03*
X374994Y309910D03*
X382497D03*
X378577Y309795D03*
X407094Y292904D03*
X396897Y293058D03*
X399894Y292904D03*
X404266Y293030D03*
X407094Y309904D03*
X396709Y309910D03*
X399894Y309904D03*
X404117Y309910D03*
X383206Y638753D03*
X387606D03*
X392006D03*
X396406D03*
X400806D03*
X405206D03*
X409606D03*
X414006D03*
X370006D03*
X365606D03*
X374406D03*
X378806D03*
X356806D03*
X361206D03*
X374421Y660756D03*
X387621D03*
X383221D03*
X400821D03*
X396421D03*
X392021D03*
X405221D03*
X409621D03*
X414021D03*
X361221D03*
X365621D03*
X356821D03*
X370021D03*
X378821D03*
X477921Y-58764D03*
Y-35764D03*
X472921Y-58764D03*
Y-35764D03*
X467921Y-58764D03*
Y-35764D03*
X462921Y-58764D03*
Y-35764D03*
X457921Y-58764D03*
Y-35764D03*
X452921Y-58764D03*
Y-35764D03*
X447921Y-58764D03*
Y-35764D03*
X442921Y-58764D03*
Y-35764D03*
X437921Y-58764D03*
Y-35764D03*
X432921Y-58764D03*
X422921Y-35764D03*
X417921Y-58764D03*
Y-35764D03*
X432921D03*
X427921Y-58764D03*
Y-35764D03*
X422921Y-58764D03*
X466806Y638753D03*
X462406D03*
X475606D03*
X471206D03*
X418406D03*
X422806D03*
X427206D03*
X440406D03*
X436006D03*
X431606D03*
X449206D03*
X458006D03*
X453606D03*
X444806D03*
X458021Y660756D03*
X449221D03*
X462421D03*
X466821D03*
X471221D03*
X418421D03*
X475621D03*
X453621D03*
X422821D03*
X427221D03*
X440421D03*
X431621D03*
X436021D03*
X444821D03*
X537921Y-58764D03*
Y-35764D03*
X532921Y-58764D03*
Y-35764D03*
X527921Y-58764D03*
Y-35764D03*
X522921Y-58764D03*
Y-35764D03*
X517921Y-58764D03*
Y-35764D03*
X512921Y-58764D03*
Y-35764D03*
X507921Y-58764D03*
Y-35764D03*
X502921Y-58764D03*
Y-35764D03*
X497921Y-58764D03*
Y-35764D03*
X492921Y-58764D03*
Y-35764D03*
X487921Y-58764D03*
Y-35764D03*
X482921Y-58764D03*
Y-35764D03*
X480006Y638753D03*
X484406D03*
X488806D03*
X493206D03*
X497606D03*
X510806D03*
X537206D03*
X519606D03*
X524006D03*
X532806D03*
X528406D03*
X515206D03*
X502006D03*
X506406D03*
X524021Y660756D03*
X480021D03*
X484421D03*
X497621D03*
X493221D03*
X488821D03*
X519621D03*
X532821D03*
X537221D03*
X528421D03*
X515221D03*
X510821D03*
X506421D03*
X502021D03*
X597921Y-35764D03*
Y-58764D03*
X592921Y-35764D03*
Y-58764D03*
X587921Y-35764D03*
Y-58764D03*
X582921Y-35764D03*
Y-58764D03*
X577921Y-35764D03*
Y-58764D03*
X572921Y-35764D03*
Y-58764D03*
X567921Y-35764D03*
Y-58764D03*
X562921Y-35764D03*
Y-58764D03*
X557921Y-35764D03*
Y-58764D03*
X552921Y-35764D03*
Y-58764D03*
X547921D03*
Y-35764D03*
X542921Y-58764D03*
Y-35764D03*
X590006Y638753D03*
X572406D03*
X559206D03*
X568006D03*
X563606D03*
X550406D03*
X581206D03*
X585606D03*
X576806D03*
X598806D03*
X594406D03*
X601500Y649500D03*
X554806Y638753D03*
X541606D03*
X546006D03*
X559221Y660756D03*
X546021D03*
X554821D03*
X598821D03*
X572421D03*
X568021D03*
X563621D03*
X585621D03*
X541621D03*
X594421D03*
X576821D03*
X590021D03*
X581221D03*
X550421D03*
X637921Y-58764D03*
X632921Y-35764D03*
Y-58764D03*
X627921Y-35764D03*
Y-58764D03*
X622921Y-35764D03*
Y-58764D03*
X617921Y-35764D03*
Y-58764D03*
X612921Y-35764D03*
Y-58764D03*
X607921Y-35764D03*
Y-58764D03*
X602921Y-35764D03*
Y-58764D03*
X652921Y-35764D03*
Y-58764D03*
X647921Y-35764D03*
Y-58764D03*
X642921Y-35764D03*
Y-58764D03*
X637921Y-35764D03*
X662921D03*
Y-58764D03*
X657921Y-35764D03*
Y-58764D03*
X653750Y225500D03*
X641600Y221400D03*
Y226600D03*
Y224000D03*
Y229200D03*
X644500D03*
Y224000D03*
Y226600D03*
X641600Y231800D03*
X644500D03*
X650700Y224000D03*
X647600D03*
X650700Y226600D03*
X647600D03*
X650700Y231800D03*
X647600D03*
Y229200D03*
X650700D03*
X641541Y236028D03*
Y238628D03*
X637001Y227337D03*
Y222137D03*
Y224737D03*
Y229937D03*
X641541Y243828D03*
Y241228D03*
X638406Y638753D03*
X634006D03*
X642806D03*
X629606D03*
X616406D03*
X612006D03*
X603206D03*
X625206D03*
X651606D03*
X647206D03*
X660406D03*
X620806D03*
X656006D03*
X607606D03*
X607621Y660756D03*
X638421D03*
X647221D03*
X616421D03*
X634021D03*
X612021D03*
X620821D03*
X625221D03*
X629621D03*
X642821D03*
X603221D03*
X656021D03*
X660421D03*
X651621D03*
X692921Y-58764D03*
X687921Y-35764D03*
Y-58764D03*
X682921Y-35764D03*
Y-58764D03*
X677921Y-35764D03*
Y-58764D03*
X672921Y-35764D03*
Y-58764D03*
X667921Y-35764D03*
Y-58764D03*
X697921Y-35764D03*
Y-58764D03*
X692921Y-35764D03*
X722921D03*
Y-58764D03*
X717921Y-35764D03*
Y-58764D03*
X712921Y-35764D03*
Y-58764D03*
X707921Y-35764D03*
Y-58764D03*
X702921Y-35764D03*
Y-58764D03*
X695606Y638753D03*
X673606D03*
X708806D03*
X704406D03*
X700006D03*
X722006D03*
X717606D03*
X713206D03*
X664806D03*
X669206D03*
X686806D03*
X682406D03*
X678006D03*
X691206D03*
X664821Y660756D03*
X695621D03*
X708821D03*
X700021D03*
X704421D03*
X669221D03*
X686821D03*
X691221D03*
X678021D03*
X673621D03*
X682421D03*
X722021D03*
X717621D03*
X713221D03*
X777921Y-58764D03*
X772921Y-35764D03*
Y-58764D03*
X767921Y-35764D03*
Y-58764D03*
X762921Y-35764D03*
Y-58764D03*
X757921Y-35764D03*
Y-58764D03*
X752921Y-35764D03*
Y-58764D03*
X787921Y-35764D03*
Y-58764D03*
X782921Y-35764D03*
Y-58764D03*
X777921Y-35764D03*
X747921D03*
Y-58764D03*
X742921Y-35764D03*
Y-58764D03*
X737921Y-35764D03*
Y-58764D03*
X732921Y-35764D03*
Y-58764D03*
X727921Y-35764D03*
Y-58764D03*
X786674Y211463D03*
X785920Y204763D03*
X786300Y207400D03*
X787200Y244200D03*
Y271900D03*
X787100Y241100D03*
X770632Y234833D03*
X770965Y237519D03*
X773800Y237700D03*
X768382Y237861D03*
X769637Y266647D03*
X770485Y269489D03*
X772630Y266810D03*
X787200Y276400D03*
X787100Y303900D03*
X775200Y301200D03*
X770900Y301800D03*
X768290Y301780D03*
X747498Y335516D03*
X750298Y338316D03*
Y335516D03*
X744698Y338316D03*
Y335516D03*
X747498Y338316D03*
X769440Y298735D03*
X772400Y299400D03*
X787000Y308300D03*
X771730Y330665D03*
X775732Y332989D03*
X770278Y333272D03*
X772949Y333009D03*
X787400Y340400D03*
X747000Y386000D03*
X743500D03*
X750500D03*
X754000D03*
X750298Y344833D03*
X744698Y347833D03*
X747498D03*
X750298D03*
X747673Y364009D03*
X745073D03*
X750273D03*
X747573Y366909D03*
X744973D03*
X750173D03*
X744698Y344833D03*
X747498D03*
X747000Y380000D03*
X743500D03*
X753874Y379863D03*
X750500Y380000D03*
Y374000D03*
X754000D03*
X747000D03*
X743500D03*
X769380Y366440D03*
X775070Y365070D03*
X772290Y365020D03*
X769440Y363810D03*
X775420Y397110D03*
X772742Y397209D03*
X766860Y396240D03*
X769770Y396070D03*
X770406Y638753D03*
X779206D03*
X774806D03*
X730806D03*
X726406D03*
X739606D03*
X735206D03*
X748406D03*
X744006D03*
X766006D03*
X761606D03*
X757206D03*
X752806D03*
X783606D03*
X744021Y660756D03*
X735221D03*
X779221D03*
X770421D03*
X774821D03*
X726421D03*
X730821D03*
X739621D03*
X748421D03*
X783621D03*
X757221D03*
X761621D03*
X752821D03*
X766021D03*
X842921Y-35764D03*
X837921Y-58764D03*
Y-35764D03*
X832921Y-58764D03*
X847921D03*
Y-35764D03*
X842921Y-58764D03*
X832921Y-35764D03*
X827921Y-58764D03*
Y-35764D03*
X822921Y-58764D03*
Y-35764D03*
X817921Y-58764D03*
Y-35764D03*
X812921Y-58764D03*
Y-35764D03*
X807921Y-58764D03*
Y-35764D03*
X802921Y-58764D03*
Y-35764D03*
X797921D03*
Y-58764D03*
X792921Y-35764D03*
Y-58764D03*
X816900Y216300D03*
X816874Y212863D03*
X814274D03*
X811674D03*
X808818Y211179D03*
X808618Y208579D03*
X803200Y213100D03*
X800600D03*
X794474Y211463D03*
X791874D03*
X789274D03*
X788522Y204343D03*
X791122Y204339D03*
X829327Y214740D03*
X832276Y214754D03*
X827322Y217430D03*
X826700Y214802D03*
X824072Y214865D03*
X824446Y217476D03*
X821775Y217617D03*
X789432Y236947D03*
X789400Y273700D03*
X811983Y244843D03*
Y242243D03*
X814583Y239643D03*
X815432Y237000D03*
X814583Y244843D03*
Y242243D03*
X812832Y237000D03*
X811983Y239643D03*
X802432Y237000D03*
X799832D03*
X792032D03*
X794632D03*
X810232D03*
X797232D03*
X805032D03*
X807632D03*
X791000Y244400D03*
X793600D03*
X816800Y234300D03*
X816900Y230900D03*
X817000Y252500D03*
X789800Y276400D03*
X792400D03*
X801991Y276557D03*
X804591D03*
X792191Y269101D03*
X789591D03*
X814891Y271657D03*
Y274257D03*
Y276857D03*
Y269057D03*
X812291D03*
Y274257D03*
Y276857D03*
Y271657D03*
X817000Y255100D03*
Y257700D03*
X848282Y251727D03*
X828180Y231748D03*
X828682Y237027D03*
X831682D03*
X828682Y234327D03*
X837500Y239500D03*
X845050Y229400D03*
X837500Y234050D03*
Y236650D03*
X834682Y236877D03*
X840155Y234245D03*
X834700Y234200D03*
X831682Y234327D03*
X834682Y239627D03*
X831682D03*
X828682D03*
X848282Y246427D03*
Y249027D03*
X825682Y239627D03*
Y234327D03*
Y237027D03*
X825313Y231753D03*
X848382Y279727D03*
Y277027D03*
Y274427D03*
X825464Y277510D03*
Y274910D03*
Y280110D03*
X822464D03*
Y277510D03*
Y274910D03*
X834464Y280110D03*
X831464D03*
X828464Y277510D03*
Y274910D03*
Y280110D03*
X834464Y277510D03*
X831464D03*
X834464Y274910D03*
X845050Y252250D03*
X817491Y276857D03*
Y274257D03*
Y271657D03*
Y269057D03*
X837264Y274910D03*
Y280110D03*
Y277510D03*
X840064D03*
Y280110D03*
X817183Y242243D03*
Y239643D03*
Y244843D03*
X818032Y237000D03*
X822682Y234327D03*
Y231727D03*
Y237027D03*
Y239627D03*
X831464Y274910D03*
X844400Y280500D03*
X848282Y254327D03*
X788600Y306100D03*
X789500Y301200D03*
X797300D03*
X799900D03*
X810300D03*
X802500D03*
X812900D03*
X807700D03*
X805100D03*
X815500D03*
X811991Y308957D03*
Y306357D03*
Y303757D03*
X814591Y306357D03*
Y308957D03*
Y303757D03*
X792900Y308400D03*
X789900D03*
X794700Y301200D03*
X792100D03*
X793000Y340400D03*
X790300Y340300D03*
X816991Y337357D03*
Y334757D03*
Y339957D03*
X814391D03*
Y337357D03*
Y334757D03*
X811791Y337357D03*
Y339957D03*
Y334757D03*
X791879Y332798D03*
X794600Y332600D03*
X816938Y319888D03*
Y323888D03*
X817100Y317000D03*
X848382Y282327D03*
X834682Y298527D03*
X828682D03*
X825682D03*
Y295527D03*
Y301227D03*
Y303927D03*
X822682D03*
Y301227D03*
Y295527D03*
Y298527D03*
X844300Y312450D03*
X831682Y298527D03*
X837782Y298127D03*
Y301027D03*
Y303927D03*
X818100Y301200D03*
X817191Y303757D03*
Y306357D03*
Y308957D03*
X834682Y301227D03*
X831682D03*
X828682D03*
X831682Y303927D03*
X834682D03*
X822482Y339827D03*
Y337027D03*
X831482D03*
X834482D03*
X828482Y339827D03*
X831482D03*
X834482D03*
X840282Y340227D03*
X840382Y337427D03*
X837382Y339877D03*
Y337077D03*
X847682Y314627D03*
X847982Y338327D03*
Y341327D03*
X828482Y337027D03*
X828682Y303927D03*
X847682Y309327D03*
Y312027D03*
Y306727D03*
X825482Y339827D03*
Y337027D03*
X789860Y364947D03*
X820218Y385950D03*
Y382950D03*
X826097Y385923D03*
X816591Y369857D03*
Y372457D03*
X811391Y369857D03*
X813991D03*
Y372457D03*
X811391D03*
X790900Y372300D03*
X788300Y372400D03*
X802759Y364575D03*
X816672Y358809D03*
X795310Y364721D03*
X816593Y356210D03*
X807959Y364575D03*
X805359D03*
X810559D03*
X815759D03*
X813159D03*
X816900Y361400D03*
X792610Y364821D03*
X816591Y375057D03*
X792238Y396753D03*
X789600Y396809D03*
X811515Y397289D03*
X808915D03*
X813648Y395557D03*
X815472Y390442D03*
X814877Y393138D03*
X792000Y399409D03*
X789400D03*
X822089Y362782D03*
Y359782D03*
X822482Y342827D03*
X828482D03*
X831482D03*
X834482D03*
X828089Y359841D03*
X834089D03*
X831089D03*
X844350Y344000D03*
X840262Y343011D03*
X837382Y342877D03*
X821658Y369463D03*
X832058Y366863D03*
Y369463D03*
X834658D03*
Y366863D03*
X837363Y366829D03*
X826858Y366863D03*
Y369463D03*
X824258Y366863D03*
Y369463D03*
X829458D03*
Y366863D03*
X821658D03*
X847982Y344327D03*
X834089Y362782D03*
X831089D03*
X826216Y383108D03*
X823218Y382950D03*
X848608Y376068D03*
Y378668D03*
X846008Y376068D03*
Y378668D03*
X848932Y373257D03*
X823218Y385950D03*
X828089Y362782D03*
X825482Y342827D03*
X825089Y359841D03*
Y362782D03*
X849606Y638753D03*
X836406D03*
X832006D03*
X796806D03*
X801206D03*
X792406D03*
X827606D03*
X818806D03*
X823206D03*
X810006D03*
X788006D03*
X845206D03*
X814406D03*
X805606D03*
X840806D03*
X849621Y660756D03*
X832021D03*
X810021D03*
X818821D03*
X836421D03*
X788021D03*
X814421D03*
X801221D03*
X805621D03*
X823221D03*
X827621D03*
X840821D03*
X796821D03*
X792421D03*
X845221D03*
X907921Y-58764D03*
Y-35764D03*
X902921Y-58764D03*
Y-35764D03*
X897921Y-58764D03*
Y-35764D03*
X892921Y-58764D03*
Y-35764D03*
X887921Y-58764D03*
Y-35764D03*
X882921Y-58764D03*
Y-35764D03*
X877921Y-58764D03*
Y-35764D03*
X872921Y-58764D03*
Y-35764D03*
X867921Y-58764D03*
Y-35764D03*
X862921Y-58764D03*
Y-35764D03*
X857921Y-58764D03*
Y-35764D03*
X852921Y-58764D03*
Y-35764D03*
X854282Y251727D03*
X857282D03*
X851282D03*
X857282Y249027D03*
Y246427D03*
X851282D03*
Y249027D03*
X854282D03*
Y246427D03*
X851382Y277027D03*
Y274427D03*
X857382Y277027D03*
X854382Y279727D03*
X857382D03*
X854382Y274427D03*
X857382D03*
X854382Y277027D03*
X874586Y259278D03*
X854282Y254327D03*
X857282D03*
X869586Y254278D03*
X851282Y254327D03*
X851382Y279727D03*
X884586Y269278D03*
X879586Y264278D03*
X889586Y274278D03*
X851382Y282327D03*
X854382D03*
X857382D03*
X851075Y335405D03*
X857075D03*
X856982Y338327D03*
X853982D03*
X856682Y314627D03*
X853682D03*
X850682D03*
X856982Y341327D03*
X853982D03*
X862008Y341100D03*
X850982Y338327D03*
Y341327D03*
X872008Y331100D03*
X867008Y336100D03*
X850682Y306727D03*
Y309327D03*
Y312027D03*
X856682Y309327D03*
X853682D03*
X856682Y306727D03*
X853682D03*
X856682Y312027D03*
X853682D03*
X877008Y326100D03*
X854075Y335405D03*
X856982Y344327D03*
X853982D03*
X850982D03*
X851208Y376068D03*
Y378668D03*
X851727Y373197D03*
X858406Y638753D03*
X854006D03*
X884806D03*
X880406D03*
X876006D03*
X871606D03*
X867206D03*
X911206D03*
X906806D03*
X889206D03*
X898006D03*
X902406D03*
X893606D03*
X862806D03*
X854021Y660756D03*
X858421D03*
X862821D03*
X898021D03*
X902421D03*
X871621D03*
X884821D03*
X893621D03*
X867221D03*
X889221D03*
X911221D03*
X906821D03*
X880421D03*
X876021D03*
X937921Y-35764D03*
X932921Y-58764D03*
Y-35764D03*
X927921Y-58764D03*
Y-35764D03*
X922921Y-58764D03*
Y-35764D03*
X917921Y-58764D03*
Y-35764D03*
X912921Y-58764D03*
Y-35764D03*
X942921D03*
X967921D03*
X962921Y-58764D03*
Y-35764D03*
X957921Y-58764D03*
Y-35764D03*
X952921Y-58764D03*
Y-35764D03*
X947921Y-58764D03*
Y-35764D03*
X942921Y-58764D03*
X972921D03*
Y-35764D03*
X967921Y-58764D03*
X937921D03*
X924406Y638753D03*
X920006D03*
X915606D03*
X972806D03*
X968406D03*
X964006D03*
X917100Y649300D03*
X942006Y638753D03*
X937606D03*
X933206D03*
X928806D03*
X959606D03*
X955206D03*
X950806D03*
X946406D03*
X959621Y660756D03*
X964021D03*
X968421D03*
X972821D03*
X920021D03*
X915621D03*
X924421D03*
X946421D03*
X942021D03*
X937621D03*
X933221D03*
X928821D03*
X955221D03*
X950821D03*
X1002921Y-58764D03*
Y-35764D03*
X997921Y-58764D03*
Y-35764D03*
X992921Y-58764D03*
Y-35764D03*
X987921Y-58764D03*
Y-35764D03*
X982921Y-58764D03*
Y-35764D03*
X977921Y-58764D03*
Y-35764D03*
X1032921Y-58764D03*
Y-35764D03*
X1027921Y-58764D03*
Y-35764D03*
X1022921Y-58764D03*
Y-35764D03*
X1017921Y-58764D03*
Y-35764D03*
X1012921Y-58764D03*
Y-35764D03*
X1007921Y-58764D03*
Y-35764D03*
X1024994Y292918D03*
X1017630Y292910D03*
X1020702Y292904D03*
X1027902D03*
X1031953Y292910D03*
X1024140Y309910D03*
X1021065Y309759D03*
X1017083Y309910D03*
X1032042D03*
X1028136Y309815D03*
X1003606Y638753D03*
X1012406D03*
X977206D03*
X990406D03*
X986006D03*
X994806D03*
X1016806D03*
X1021206D03*
X981606D03*
X999206D03*
X1025606D03*
X1008006D03*
X1030006D03*
X1034406D03*
X999221Y660756D03*
X1034421D03*
X1030021D03*
X1008021D03*
X1012421D03*
X1003621D03*
X1016821D03*
X977221D03*
X981621D03*
X1021221D03*
X1025621D03*
X994821D03*
X986021D03*
X990421D03*
X1067921Y-58764D03*
Y-35764D03*
X1062921Y-58764D03*
Y-35764D03*
X1057921Y-58764D03*
Y-35764D03*
X1052921Y-58764D03*
Y-35764D03*
X1047921Y-58764D03*
Y-35764D03*
X1042921Y-58764D03*
Y-35764D03*
X1037921Y-58764D03*
Y-35764D03*
X1092921Y-58764D03*
Y-35764D03*
X1087921Y-58764D03*
Y-35764D03*
X1082921Y-58764D03*
Y-35764D03*
X1077921Y-58764D03*
Y-35764D03*
X1072921Y-58764D03*
Y-35764D03*
X1046276Y292910D03*
X1049502Y292904D03*
X1053684Y292910D03*
X1056702Y292904D03*
X1039182Y292919D03*
X1042302Y292904D03*
X1035102D03*
X1049547Y309904D03*
X1046612Y309910D03*
X1056747Y309904D03*
X1053594Y309910D03*
X1042347Y309904D03*
X1039383Y309910D03*
X1035147Y309904D03*
X1086126Y338758D03*
X1083301Y338841D03*
X1096006Y638753D03*
X1078406D03*
X1082806D03*
X1074006D03*
X1069606D03*
X1091606D03*
X1052006D03*
X1038806D03*
X1087206D03*
X1060806D03*
X1056406D03*
X1065206D03*
X1043206D03*
X1047606D03*
X1078421Y660756D03*
X1060821D03*
X1087221D03*
X1038821D03*
X1091621D03*
X1052021D03*
X1074021D03*
X1065221D03*
X1096021D03*
X1056421D03*
X1043221D03*
X1047621D03*
X1082821D03*
X1069621D03*
X1157921Y-58764D03*
Y-35764D03*
X1152921Y-58764D03*
Y-35764D03*
X1147921Y-58764D03*
Y-35764D03*
X1142921Y-58764D03*
Y-35764D03*
X1137921Y-58764D03*
Y-35764D03*
X1132921Y-58764D03*
Y-35764D03*
X1127921Y-58764D03*
Y-35764D03*
X1122921Y-58764D03*
Y-35764D03*
X1117921Y-58764D03*
Y-35764D03*
X1112921Y-58764D03*
Y-35764D03*
X1107921Y-58764D03*
Y-35764D03*
X1102921Y-58764D03*
Y-35764D03*
X1097921Y-58764D03*
Y-35764D03*
X1135606Y638753D03*
X1126806D03*
X1144406D03*
X1140006D03*
X1118006D03*
X1122406D03*
X1153206D03*
X1157606D03*
X1104806D03*
X1100406D03*
X1131206D03*
X1148806D03*
X1109206D03*
X1113606D03*
X1157621Y660756D03*
X1148821D03*
X1122421D03*
X1126821D03*
X1100421D03*
X1118021D03*
X1140021D03*
X1113621D03*
X1109221D03*
X1153221D03*
X1144421D03*
X1104821D03*
X1131221D03*
X1135621D03*
X1217921Y-58764D03*
Y-35764D03*
X1212921Y-58764D03*
Y-35764D03*
X1207921Y-58764D03*
Y-35764D03*
X1202921Y-58764D03*
Y-35764D03*
X1197921Y-58764D03*
Y-35764D03*
X1192921Y-58764D03*
Y-35764D03*
X1187921Y-58764D03*
Y-35764D03*
X1182921Y-58764D03*
Y-35764D03*
X1177921Y-58764D03*
Y-35764D03*
X1172921Y-58764D03*
Y-35764D03*
X1167921Y-58764D03*
Y-35764D03*
X1162921Y-58764D03*
Y-35764D03*
X1188406Y638753D03*
X1214806D03*
X1197206D03*
X1201606D03*
X1192806D03*
X1170806D03*
X1162006D03*
X1166406D03*
X1206006D03*
X1219206D03*
X1179606D03*
X1175206D03*
X1210406D03*
X1184006D03*
X1184021Y660756D03*
X1219221D03*
X1192821D03*
X1188421D03*
X1201621D03*
X1179621D03*
X1214821D03*
X1206021D03*
X1166421D03*
X1210421D03*
X1170821D03*
X1162021D03*
X1175221D03*
X1197221D03*
X1232921Y-58764D03*
Y-35764D03*
X1227921Y-58764D03*
Y-35764D03*
X1222921Y-58764D03*
Y-35764D03*
X1252921Y-58764D03*
Y-35764D03*
X1247921Y-58764D03*
Y-35764D03*
X1242921Y-58764D03*
Y-35764D03*
X1237921Y-58764D03*
Y-35764D03*
X1257921D03*
X1272921Y-58764D03*
Y-35764D03*
X1267921Y-58764D03*
Y-35764D03*
X1262921Y-58764D03*
Y-35764D03*
X1257921Y-58764D03*
X1277921D03*
Y-35764D03*
X1263206Y638753D03*
X1223606D03*
X1228006D03*
X1258806D03*
X1241206D03*
X1236806D03*
X1250006D03*
X1245606D03*
X1276406D03*
X1254406D03*
X1280806D03*
X1272006D03*
X1267606D03*
X1232406D03*
X1228021Y660756D03*
X1232421D03*
X1280821D03*
X1245621D03*
X1236821D03*
X1223621D03*
X1276421D03*
X1241221D03*
X1272021D03*
X1258821D03*
X1250021D03*
X1254421D03*
X1263221D03*
X1267621D03*
X1342921Y-35764D03*
Y-58764D03*
X1317921D03*
X1312921Y-35764D03*
Y-58764D03*
X1307921Y-35764D03*
Y-58764D03*
X1302921Y-35764D03*
Y-58764D03*
X1297921D03*
Y-35764D03*
X1292921Y-58764D03*
Y-35764D03*
X1287921Y-58764D03*
Y-35764D03*
X1282921Y-58764D03*
Y-35764D03*
X1322921D03*
Y-58764D03*
X1317921Y-35764D03*
X1337921D03*
Y-58764D03*
X1332921Y-35764D03*
Y-58764D03*
X1327921Y-35764D03*
Y-58764D03*
X1324806Y638753D03*
X1298406D03*
X1285206D03*
X1294006D03*
X1302806D03*
X1333606D03*
X1338006D03*
X1320406D03*
X1311606D03*
X1329206D03*
X1307206D03*
X1342406D03*
X1289606D03*
X1316006D03*
X1329221Y660756D03*
X1311621D03*
X1316021D03*
X1333621D03*
X1342421D03*
X1285221D03*
X1324821D03*
X1338021D03*
X1298421D03*
X1289621D03*
X1294021D03*
X1320421D03*
X1302821D03*
X1307221D03*
X1402921Y-58764D03*
X1397921D03*
X1402921Y-35764D03*
X1392921Y-58764D03*
X1397921Y-35764D03*
X1387921Y-58764D03*
X1392921Y-35764D03*
X1382921Y-58764D03*
X1387921Y-35764D03*
X1377921Y-58764D03*
X1382921Y-35764D03*
X1372921Y-58764D03*
X1377921Y-35764D03*
X1367921Y-58764D03*
X1362921Y-35764D03*
Y-58764D03*
X1357921Y-35764D03*
Y-58764D03*
X1352921Y-35764D03*
Y-58764D03*
X1347921Y-35764D03*
Y-58764D03*
X1351206Y638753D03*
X1360006D03*
X1404506Y638853D03*
X1355606Y638753D03*
X1386906Y638853D03*
X1364406Y638753D03*
X1391306Y638853D03*
X1346806Y638753D03*
X1400106Y638853D03*
X1382006Y638753D03*
X1377606D03*
X1373206D03*
X1395706Y638853D03*
X1368806Y638753D03*
X1368821Y660756D03*
X1346821D03*
X1355621D03*
X1360021D03*
X1364421D03*
X1351221D03*
X1404521Y660856D03*
X1400121D03*
X1395721D03*
X1386921D03*
X1377621Y660756D03*
X1382021D03*
X1373221D03*
X1391321Y660856D03*
X1407921Y-58764D03*
X1412921Y-35764D03*
X1407921D03*
X1442921Y-58764D03*
X1447921Y-35764D03*
X1437921Y-58764D03*
X1442921Y-35764D03*
X1432921Y-58764D03*
X1437921Y-35764D03*
X1427921Y-58764D03*
X1432921Y-35764D03*
X1422921Y-58764D03*
X1427921Y-35764D03*
X1417921Y-58764D03*
X1422921Y-35764D03*
X1412921Y-58764D03*
X1417921Y-35764D03*
X1462921Y-58764D03*
X1457921D03*
X1462921Y-35764D03*
X1452921Y-58764D03*
X1457921Y-35764D03*
X1447921Y-58764D03*
X1452921Y-35764D03*
X1431664Y190213D03*
X1456080Y547540D03*
X1463369Y561763D03*
X1446600Y563900D03*
X1449300D03*
X1454600D03*
X1451900D03*
X1457300D03*
X1452392Y544998D03*
X1453166Y547481D03*
X1422106Y638853D03*
X1466106D03*
X1448506D03*
X1457306D03*
X1417706D03*
X1413306D03*
X1461706D03*
X1452906D03*
X1408906D03*
X1444106D03*
X1435306D03*
X1426506D03*
X1430906D03*
X1439706D03*
X1457321Y660856D03*
X1417721D03*
X1413321D03*
X1408921D03*
X1422121D03*
X1426521D03*
X1435321D03*
X1444121D03*
X1439721D03*
X1430921D03*
X1448521D03*
X1452921D03*
X1466121D03*
X1461721D03*
X1502921Y-58764D03*
X1507921Y-35764D03*
X1497921Y-58764D03*
X1502921Y-35764D03*
X1492921Y-58764D03*
X1497921Y-35764D03*
X1487921Y-58764D03*
X1492921Y-35764D03*
X1482921Y-58764D03*
X1487921Y-35764D03*
X1477921Y-58764D03*
X1482921Y-35764D03*
X1472921Y-58764D03*
X1477921Y-35764D03*
X1467921Y-58764D03*
X1472921Y-35764D03*
X1467921D03*
X1527921Y-58764D03*
X1522921D03*
X1527921Y-35764D03*
X1517921Y-58764D03*
X1522921Y-35764D03*
X1512921Y-58764D03*
X1517921Y-35764D03*
X1507921Y-58764D03*
X1512921Y-35764D03*
X1473018Y562003D03*
X1470314Y561923D03*
X1467714Y561896D03*
X1526586Y559860D03*
X1527285Y562386D03*
X1524538Y562286D03*
X1495187Y561842D03*
X1497918Y561872D03*
X1492187Y561842D03*
X1489316Y561742D03*
X1500530Y561872D03*
X1492130Y545910D03*
X1495130D03*
X1497866Y545797D03*
X1496906Y638853D03*
X1492506D03*
X1501706Y638753D03*
X1506106D03*
X1514906D03*
X1483706Y638853D03*
X1523706Y638753D03*
X1510506D03*
X1488106Y638853D03*
X1474906D03*
X1519306Y638753D03*
X1479306Y638853D03*
X1528106Y638753D03*
X1470506Y638853D03*
X1496921Y660856D03*
X1483721D03*
X1488121D03*
X1492521D03*
X1479321D03*
X1510521Y660756D03*
X1528121D03*
X1523721D03*
X1501721D03*
X1506121D03*
X1514921D03*
X1519321D03*
X1474921Y660856D03*
X1470521D03*
X1587921Y-58764D03*
X1582921D03*
X1587921Y-35764D03*
X1532921D03*
X1542921D03*
X1532921Y-58764D03*
X1537921Y-35764D03*
X1577921Y-58764D03*
X1582921Y-35764D03*
X1572921Y-58764D03*
X1577921Y-35764D03*
X1567921Y-58764D03*
X1572921Y-35764D03*
X1562921Y-58764D03*
X1567921Y-35764D03*
X1557921Y-58764D03*
X1562921Y-35764D03*
X1552921Y-58764D03*
X1557921Y-35764D03*
X1547921Y-58764D03*
X1552921Y-35764D03*
X1542921Y-58764D03*
X1547921Y-35764D03*
X1537921Y-58764D03*
X1567425Y144373D03*
X1583078Y260122D03*
X1583047Y257171D03*
X1586399Y257099D03*
X1589030Y259807D03*
X1588999Y257104D03*
X1586430Y259824D03*
X1570020Y295340D03*
X1531986Y559860D03*
X1529286D03*
X1529985Y562386D03*
X1532685D03*
X1546795Y563316D03*
X1546685Y568656D03*
X1546825Y565986D03*
X1549395Y563541D03*
X1549285Y568881D03*
X1549425Y566211D03*
X1535385Y562386D03*
X1534897Y559808D03*
X1541267Y563185D03*
X1543967D03*
X1541080Y565859D03*
X1538331Y563913D03*
X1538385Y560978D03*
X1544080Y568859D03*
Y565859D03*
X1580121Y647556D03*
X1555106Y638753D03*
X1555121Y647556D03*
X1590121D03*
X1590106Y638753D03*
X1590121Y643156D03*
X1585121Y647556D03*
X1585106Y638753D03*
X1585121Y643156D03*
X1565121Y647556D03*
X1570121Y643156D03*
X1570106Y638753D03*
X1565106D03*
X1565121Y643156D03*
X1570121Y647556D03*
X1560121D03*
X1560106Y638753D03*
X1560121Y643156D03*
X1575121D03*
X1575106Y638753D03*
X1575121Y647556D03*
X1555121Y643156D03*
X1580106Y638753D03*
X1580121Y643156D03*
X1550121Y647556D03*
X1541306Y638753D03*
X1545706D03*
X1550106D03*
X1550121Y643156D03*
X1536906Y638753D03*
X1532506D03*
X1565121Y651956D03*
X1570121Y660756D03*
Y656356D03*
X1565121Y660756D03*
X1555121Y651956D03*
X1590121Y660756D03*
Y656356D03*
Y651956D03*
X1585121Y660756D03*
Y656356D03*
Y651956D03*
X1580121Y660756D03*
Y656356D03*
Y651956D03*
X1560121Y660756D03*
Y656356D03*
Y651956D03*
X1555121Y660756D03*
Y656356D03*
X1570121Y651956D03*
X1575121D03*
Y656356D03*
Y660756D03*
X1565121Y656356D03*
X1550121Y651956D03*
Y656356D03*
X1541321Y660756D03*
X1550121D03*
X1545721D03*
X1532521D03*
X1536921D03*
X1642921Y-35764D03*
Y-58764D03*
X1637921Y-35764D03*
Y-58764D03*
X1632921Y-35764D03*
Y-58764D03*
X1627921D03*
X1622921D03*
X1627921Y-35764D03*
X1617921Y-58764D03*
X1622921Y-35764D03*
X1612921Y-58764D03*
X1617921Y-35764D03*
X1607921Y-58764D03*
X1612921Y-35764D03*
X1602921Y-58764D03*
X1607921Y-35764D03*
X1597921Y-58764D03*
X1602921Y-35764D03*
X1592921Y-58764D03*
X1597921Y-35764D03*
X1592921D03*
X1647921D03*
Y-58764D03*
X1608099Y197125D03*
X1591598Y257028D03*
X1591628Y259924D03*
X1608280Y249234D03*
X1625106Y638753D03*
X1625121Y647556D03*
X1630121Y643156D03*
X1630106Y638753D03*
X1630121Y647556D03*
X1635121Y643156D03*
X1635106Y638753D03*
X1635121Y647556D03*
X1640121Y643156D03*
Y647556D03*
X1640106Y638753D03*
X1650121Y647556D03*
X1650106Y638753D03*
X1650121Y643156D03*
X1645121Y647556D03*
X1645106Y638753D03*
X1645121Y643156D03*
X1625121D03*
X1620121Y647556D03*
X1620106Y638753D03*
X1620121Y643156D03*
X1615121Y647556D03*
X1615106Y638753D03*
X1615121Y643156D03*
X1610121Y647556D03*
X1610106Y638753D03*
X1610121Y643156D03*
X1605121Y647556D03*
X1605106Y638753D03*
X1605121Y643156D03*
X1600121Y647556D03*
X1600106Y638753D03*
X1600121Y643156D03*
X1595121Y647556D03*
X1595106Y638753D03*
X1595121Y643156D03*
X1625121Y651956D03*
Y660756D03*
X1630121Y651956D03*
Y656356D03*
Y660756D03*
X1635121Y651956D03*
Y656356D03*
Y660756D03*
X1625121Y656356D03*
X1640121D03*
Y651956D03*
X1650121Y660756D03*
Y656356D03*
Y651956D03*
X1645121Y660756D03*
Y656356D03*
Y651956D03*
X1640121Y660756D03*
X1620121D03*
Y656356D03*
Y651956D03*
X1615121Y660756D03*
Y656356D03*
Y651956D03*
X1610121Y660756D03*
Y656356D03*
Y651956D03*
X1605121Y660756D03*
Y656356D03*
Y651956D03*
X1600121Y660756D03*
Y656356D03*
Y651956D03*
X1595121Y660756D03*
Y656356D03*
Y651956D03*
X1692921Y-40764D03*
X1702921Y-54764D03*
X1687921D03*
X1682921D03*
X1677921D03*
X1672921D03*
X1692921D03*
X1697921D03*
X1707921D03*
X1712921D03*
X1697921Y-40764D03*
X1692921Y-50764D03*
X1687921D03*
X1682921D03*
X1677921D03*
X1672921D03*
X1712921D03*
X1707921D03*
X1702921D03*
X1697921Y-45764D03*
X1707921D03*
X1702921D03*
X1712921D03*
X1697921Y-50764D03*
X1667921Y-35764D03*
X1712921D03*
Y-58764D03*
X1707921Y-35764D03*
Y-58764D03*
X1702921Y-35764D03*
Y-58764D03*
X1697921Y-35764D03*
Y-58764D03*
X1687921Y-40764D03*
X1672921Y-45764D03*
X1677921D03*
X1682921D03*
Y-40764D03*
X1687921Y-45764D03*
X1692921D03*
X1667921Y-58764D03*
X1662921Y-35764D03*
Y-58764D03*
X1657921Y-35764D03*
Y-58764D03*
X1652921Y-35764D03*
Y-58764D03*
X1712921Y-40764D03*
X1707921D03*
X1702921D03*
X1677921D03*
X1672921D03*
X1677921Y-35764D03*
Y-58764D03*
X1672921Y-35764D03*
Y-58764D03*
X1682921Y-35764D03*
Y-58764D03*
X1692921Y-35764D03*
Y-58764D03*
X1687921Y-35764D03*
Y-58764D03*
X1702005Y499163D03*
X1704596Y498876D03*
X1704544Y501627D03*
X1701874Y501795D03*
X1690121Y647556D03*
X1710121D03*
X1710106Y638753D03*
X1710121Y643156D03*
X1705121Y647556D03*
X1705106Y638753D03*
X1695121Y643156D03*
X1695106Y638753D03*
X1695121Y647556D03*
X1700121Y643156D03*
X1700106Y638753D03*
X1685121Y647556D03*
X1685106Y638753D03*
X1685121Y643156D03*
X1680121Y647556D03*
X1680106Y638753D03*
X1680121Y643156D03*
X1675121Y647556D03*
X1675106Y638753D03*
X1675121Y643156D03*
X1670121Y647556D03*
X1670106Y638753D03*
X1670121Y643156D03*
X1665121Y647556D03*
X1665106Y638753D03*
X1665121Y643156D03*
X1660121Y647556D03*
X1660106Y638753D03*
X1660121Y643156D03*
X1655121Y647556D03*
X1655106Y638753D03*
X1655121Y643156D03*
X1690121D03*
X1690106Y638753D03*
X1700121Y647556D03*
X1705121Y643156D03*
X1690121Y656356D03*
Y651956D03*
X1710121Y660756D03*
Y656356D03*
Y651956D03*
X1705121Y660756D03*
Y656356D03*
Y651956D03*
X1690121Y660756D03*
X1695121Y651956D03*
Y656356D03*
Y660756D03*
X1685121Y651956D03*
X1680121Y660756D03*
Y656356D03*
Y651956D03*
X1675121Y660756D03*
Y656356D03*
Y651956D03*
X1670121Y660756D03*
Y656356D03*
Y651956D03*
X1665121Y660756D03*
Y656356D03*
Y651956D03*
X1660121Y660756D03*
Y656356D03*
Y651956D03*
X1655121Y660756D03*
Y656356D03*
Y651956D03*
X1685121Y660756D03*
Y656356D03*
X1700121Y651956D03*
Y656356D03*
Y660756D03*
X1737921Y-50764D03*
X1722921Y-45764D03*
X1727921D03*
X1732921D03*
X1747921D03*
X1752921D03*
X1727921Y-54764D03*
X1757921D03*
X1717921D03*
X1722921D03*
X1767921Y-40764D03*
Y-50764D03*
X1762921D03*
X1757921D03*
X1762921Y-54764D03*
X1752921D03*
X1747921D03*
X1742921D03*
X1737921D03*
X1732921D03*
X1772921D03*
X1767921D03*
X1762921Y-40764D03*
X1772921D03*
X1722921Y-50764D03*
X1717921D03*
X1732921D03*
X1757921Y-40764D03*
X1717921Y-45764D03*
Y-58764D03*
X1742921Y-50764D03*
X1747921D03*
X1752921D03*
X1742921Y-58764D03*
X1737921Y-35764D03*
Y-58764D03*
X1732921Y-35764D03*
Y-58764D03*
X1727921Y-35764D03*
Y-58764D03*
X1722921Y-35764D03*
Y-58764D03*
X1717921Y-35764D03*
X1757921Y-45764D03*
X1762921D03*
X1742921D03*
X1752921Y-40764D03*
X1747921D03*
X1742921D03*
X1737921D03*
X1732921D03*
X1727921D03*
X1722921D03*
X1717921D03*
X1727921Y-50764D03*
X1767921Y-45764D03*
X1772921D03*
X1737921D03*
X1772921Y-35764D03*
Y-58764D03*
X1767921Y-35764D03*
Y-58764D03*
X1762921Y-35764D03*
Y-58764D03*
X1757921Y-35764D03*
Y-58764D03*
X1752921Y-35764D03*
Y-58764D03*
X1747921Y-35764D03*
Y-58764D03*
X1742921Y-35764D03*
X1772921Y-50764D03*
X1758324Y232657D03*
X1747227Y237314D03*
X1744308Y237295D03*
X1741668Y237314D03*
X1739044Y237284D03*
X1775121Y643156D03*
Y647556D03*
X1775106Y638753D03*
X1730121Y647556D03*
X1730106Y638753D03*
X1730121Y643156D03*
X1725121Y647556D03*
X1725106Y638753D03*
X1725121Y643156D03*
X1720121Y647556D03*
X1720106Y638753D03*
X1720121Y643156D03*
X1715121Y647556D03*
X1715106Y638753D03*
X1715121Y643156D03*
X1770121Y647556D03*
X1770106Y638753D03*
X1770121Y643156D03*
X1765121Y647556D03*
X1765106Y638753D03*
X1765121Y643156D03*
X1760121Y647556D03*
X1760106Y638753D03*
X1760121Y643156D03*
X1755121Y647556D03*
X1755106Y638753D03*
X1755121Y643156D03*
X1750121Y647556D03*
X1750106Y638753D03*
X1750121Y643156D03*
X1745121Y647556D03*
X1745106Y638753D03*
X1745121Y643156D03*
X1740121Y647556D03*
X1740106Y638753D03*
X1740121Y643156D03*
X1735121Y647556D03*
X1735106Y638753D03*
X1735121Y643156D03*
X1770121Y660756D03*
X1775121D03*
Y656356D03*
Y651956D03*
X1725121Y660756D03*
Y656356D03*
Y651956D03*
X1720121Y660756D03*
Y656356D03*
Y651956D03*
X1715121Y660756D03*
Y656356D03*
Y651956D03*
X1770121D03*
X1765121Y660756D03*
Y656356D03*
Y651956D03*
X1760121Y660756D03*
Y656356D03*
Y651956D03*
X1755121Y660756D03*
Y656356D03*
Y651956D03*
X1750121Y660756D03*
Y656356D03*
Y651956D03*
X1745121Y660756D03*
Y656356D03*
Y651956D03*
X1740121Y660756D03*
Y656356D03*
Y651956D03*
X1735121Y660756D03*
Y656356D03*
Y651956D03*
X1730121Y660756D03*
Y656356D03*
X1770121D03*
X1730121Y651956D03*
X1817921Y-40764D03*
X1832921Y-45764D03*
Y-54764D03*
X1827921D03*
X1822921D03*
X1817921D03*
X1812921D03*
X1807921D03*
X1802921D03*
X1797921D03*
X1792921D03*
X1787921D03*
X1782921D03*
X1777921D03*
X1832921Y-50764D03*
X1827921D03*
X1822921D03*
X1817921D03*
X1812921D03*
X1807921D03*
X1802921D03*
X1797921D03*
X1792921D03*
X1787921D03*
X1782921Y-40764D03*
X1792921D03*
X1802921D03*
X1807921D03*
X1822921D03*
X1827921D03*
X1832921D03*
X1812921D03*
X1797921D03*
X1777921Y-45764D03*
X1782921D03*
X1787921D03*
X1792921D03*
X1797921D03*
X1802921D03*
X1807921D03*
X1812921D03*
X1817921D03*
X1822921D03*
X1787921Y-40764D03*
X1832921Y-35764D03*
Y-58764D03*
X1827921Y-35764D03*
Y-58764D03*
X1822921Y-35764D03*
Y-58764D03*
X1817921Y-35764D03*
Y-58764D03*
X1812921Y-35764D03*
Y-58764D03*
X1807921Y-35764D03*
Y-58764D03*
X1802921Y-35764D03*
Y-58764D03*
X1797921Y-35764D03*
Y-58764D03*
X1792921Y-35764D03*
Y-58764D03*
X1787921Y-35764D03*
Y-58764D03*
X1782921Y-35764D03*
Y-58764D03*
X1777921Y-35764D03*
Y-58764D03*
X1782921Y-50764D03*
X1777921D03*
Y-40764D03*
X1827921Y-45764D03*
X1835121Y21532D03*
X1832071D03*
X1832771Y26818D03*
X1835921D03*
X1835714Y75029D03*
X1780121Y643156D03*
X1780106Y638753D03*
X1780121Y647556D03*
X1785121Y643156D03*
X1790121D03*
X1835121Y647556D03*
X1835106Y638753D03*
X1835121Y643156D03*
X1830121Y647556D03*
X1830106Y638753D03*
X1830121Y643156D03*
X1825121Y647556D03*
X1825106Y638753D03*
X1825121Y643156D03*
X1820121Y647556D03*
X1820106Y638753D03*
X1820121Y643156D03*
X1815121Y647556D03*
X1815106Y638753D03*
X1815121Y643156D03*
X1810121Y647556D03*
X1810106Y638753D03*
X1810121Y643156D03*
X1805121Y647556D03*
X1805106Y638753D03*
X1805121Y643156D03*
X1800121Y647556D03*
X1800106Y638753D03*
X1800121Y643156D03*
X1795121Y647556D03*
X1795106Y638753D03*
X1795121Y643156D03*
X1790121Y647556D03*
X1790106Y638753D03*
X1785121Y647556D03*
X1785106Y638753D03*
X1800121Y656356D03*
X1780121Y651956D03*
Y656356D03*
Y660756D03*
X1835121D03*
Y656356D03*
Y651956D03*
X1830121Y660756D03*
Y656356D03*
Y651956D03*
X1825121Y660756D03*
Y656356D03*
Y651956D03*
X1820121Y660756D03*
Y656356D03*
Y651956D03*
X1815121Y660756D03*
Y656356D03*
Y651956D03*
X1810121Y660756D03*
Y656356D03*
Y651956D03*
X1805121Y660756D03*
Y656356D03*
Y651956D03*
X1800121Y660756D03*
Y651956D03*
X1795121Y660756D03*
Y656356D03*
Y651956D03*
X1790121Y660756D03*
Y656356D03*
Y651956D03*
X1785121Y660756D03*
Y656356D03*
Y651956D03*
X1857921Y-45764D03*
X1837921D03*
X1897921D03*
X1892921D03*
X1887921D03*
X1882921D03*
X1877921D03*
X1872921D03*
X1867921D03*
X1862921D03*
X1842921Y-54764D03*
X1852921Y-45764D03*
X1847921D03*
X1842921D03*
X1897921Y-54764D03*
X1892921D03*
X1887921D03*
X1882921D03*
X1877921D03*
X1872921D03*
X1867921D03*
X1862921D03*
X1857921D03*
X1852921D03*
X1847921D03*
X1837921D03*
X1897921Y-50764D03*
X1892921D03*
X1887921D03*
X1882921D03*
X1877921D03*
X1872921D03*
X1867921D03*
X1862921D03*
X1857921D03*
X1852921D03*
X1847921D03*
X1842921D03*
X1837921D03*
X1892921Y-40764D03*
X1897921D03*
X1877921D03*
X1882921D03*
X1887921D03*
X1857921D03*
X1862921D03*
X1867921D03*
X1872921D03*
X1837921D03*
X1842921D03*
X1847921D03*
X1852921D03*
Y-35764D03*
Y-58764D03*
X1847921Y-35764D03*
Y-58764D03*
X1842921Y-35764D03*
Y-58764D03*
X1837921Y-35764D03*
Y-58764D03*
X1862921D03*
X1857921Y-35764D03*
Y-58764D03*
X1882921D03*
X1877921Y-35764D03*
Y-58764D03*
X1872921Y-35764D03*
Y-58764D03*
X1867921Y-35764D03*
Y-58764D03*
X1862921Y-35764D03*
X1897921D03*
Y-58764D03*
X1892921Y-35764D03*
Y-58764D03*
X1887921Y-35764D03*
Y-58764D03*
X1882921Y-35764D03*
X1838700Y26638D03*
X1838100Y21500D03*
X1862636Y26780D03*
X1851040Y24130D03*
X1855836Y21118D03*
X1852236D03*
X1859436D03*
X1862936D03*
X1865450Y22000D03*
X1860981Y23894D03*
X1857381D03*
X1853781D03*
X1864020Y24470D03*
X1851936Y26780D03*
X1859036D03*
X1855436D03*
X1837077Y77429D03*
X1837129Y72526D03*
X1837161Y69926D03*
X1838342Y75014D03*
X1846675Y67362D03*
X1844025D03*
X1849325D03*
X1839985Y77522D03*
X1842783Y77599D03*
X1842515Y70042D03*
X1839865D03*
X1845165D03*
X1842515Y72692D03*
X1839865D03*
X1844048Y75184D03*
X1846667Y75106D03*
X1841250Y75107D03*
X1845165Y72692D03*
X1883723Y263029D03*
Y260029D03*
X1880633Y260109D03*
Y263109D03*
X1886200Y454280D03*
X1882669Y454368D03*
X1886330Y448010D03*
X1892118Y454383D03*
X1888968D03*
X1888976Y448054D03*
X1892126D03*
X1895275D03*
X1895121Y647556D03*
X1895106Y638753D03*
X1895121Y643156D03*
X1890121Y647556D03*
X1890106Y638753D03*
X1890121Y643156D03*
X1885121Y647556D03*
X1885106Y638753D03*
X1885121Y643156D03*
X1880121Y647556D03*
X1880106Y638753D03*
X1880121Y643156D03*
X1875121Y647556D03*
X1875106Y638753D03*
X1875121Y643156D03*
X1870121Y647556D03*
X1870106Y638753D03*
X1870121Y643156D03*
X1865121Y647556D03*
X1865106Y638753D03*
X1865121Y643156D03*
X1860121Y647556D03*
X1860106Y638753D03*
X1860121Y643156D03*
X1855121Y647556D03*
X1855106Y638753D03*
X1855121Y643156D03*
X1850121Y647556D03*
X1850106Y638753D03*
X1850121Y643156D03*
X1845121Y647556D03*
X1845106Y638753D03*
X1845121Y643156D03*
X1840121Y647556D03*
X1840106Y638753D03*
X1840121Y643156D03*
X1895121Y660756D03*
Y656356D03*
Y651956D03*
X1890121Y660756D03*
Y656356D03*
Y651956D03*
X1885121Y660756D03*
Y656356D03*
Y651956D03*
X1880121Y660756D03*
Y656356D03*
Y651956D03*
X1875121Y660756D03*
Y656356D03*
Y651956D03*
X1870121Y660756D03*
Y656356D03*
Y651956D03*
X1865121Y660756D03*
Y656356D03*
Y651956D03*
X1860121Y660756D03*
Y656356D03*
Y651956D03*
X1855121Y660756D03*
Y656356D03*
Y651956D03*
X1850121Y660756D03*
Y656356D03*
Y651956D03*
X1845121Y660756D03*
Y656356D03*
Y651956D03*
X1840121Y660756D03*
Y656356D03*
Y651956D03*
X1927921Y-40764D03*
X1947921Y-45764D03*
X1942921D03*
X1937921D03*
X1932921D03*
X1927921D03*
X1922921D03*
X1917921D03*
X1912921D03*
X1907921D03*
X1902921D03*
X1927921Y-50764D03*
X1932921D03*
Y-40764D03*
X1937921D03*
X1942921D03*
X1947921D03*
X1907921Y-50764D03*
X1902921D03*
X1922921Y-40764D03*
X1917921D03*
X1912921D03*
X1907921D03*
X1902921D03*
X1922921Y-54764D03*
X1917921D03*
X1912921D03*
X1907921D03*
X1902921D03*
X1927921D03*
X1932921D03*
X1937921D03*
X1942921D03*
X1947921D03*
X1952921D03*
X1957921D03*
Y-50764D03*
X1952921D03*
X1947921D03*
X1942921D03*
X1937921D03*
X1922921D03*
X1917921D03*
X1912921D03*
X1957921Y-35764D03*
Y-58764D03*
X1952921Y-35764D03*
Y-58764D03*
X1947921Y-35764D03*
Y-58764D03*
X1942921Y-35764D03*
Y-58764D03*
X1937921Y-35764D03*
Y-58764D03*
X1932921Y-35764D03*
Y-58764D03*
X1927921Y-35764D03*
Y-58764D03*
X1922921Y-35764D03*
Y-58764D03*
X1917921Y-35764D03*
Y-58764D03*
X1912921Y-35764D03*
Y-58764D03*
X1907921Y-35764D03*
Y-58764D03*
X1902921Y-35764D03*
Y-58764D03*
X1938150Y70447D03*
X1937950Y73247D03*
X1940750Y73347D03*
X1929961Y73247D03*
X1935350D03*
X1932730Y73310D03*
X1942390Y76040D03*
X1943550Y73347D03*
X1946350Y73447D03*
X1948951Y73448D03*
X1945020Y76060D03*
X1954271Y80449D03*
X1936706Y75987D03*
X1939470Y76000D03*
X1930150Y70447D03*
X1932950D03*
X1935550D03*
X1940950Y70547D03*
X1943750D03*
X1917298Y466999D03*
X1914173Y467000D03*
X1910999D03*
X1960106Y638753D03*
X1955106D03*
X1950106D03*
X1945121Y647556D03*
Y643156D03*
X1945106Y638753D03*
X1940121Y647556D03*
Y643156D03*
X1940106Y638753D03*
X1935121Y647556D03*
Y643156D03*
X1935106Y638753D03*
X1930106D03*
X1925106D03*
X1920121Y647556D03*
X1910121Y643156D03*
X1910106Y638753D03*
X1905121Y647556D03*
Y643156D03*
X1905106Y638753D03*
X1900121Y647556D03*
X1900106Y638753D03*
X1900121Y643156D03*
X1920106Y638753D03*
X1915121Y647556D03*
X1920121Y643156D03*
X1910121Y647556D03*
X1915106Y638753D03*
X1915121Y643156D03*
X1960121Y656356D03*
Y660756D03*
X1955121Y656356D03*
Y660756D03*
X1950121Y651956D03*
Y656356D03*
Y660756D03*
X1945121Y651956D03*
Y656356D03*
Y660756D03*
X1940121Y651956D03*
Y656356D03*
Y660756D03*
X1935121Y651956D03*
Y656356D03*
Y660756D03*
X1930121Y651956D03*
Y656356D03*
Y660756D03*
X1925121Y651956D03*
Y656356D03*
Y660756D03*
X1920121Y651956D03*
Y656356D03*
X1905121Y651956D03*
Y656356D03*
Y660756D03*
X1900121D03*
Y656356D03*
Y651956D03*
X1915121D03*
Y656356D03*
Y660756D03*
X1920121D03*
X1910121D03*
Y656356D03*
Y651956D03*
X1967921Y-45764D03*
X1962921D03*
Y-40764D03*
X1967921D03*
Y-54764D03*
X1962921D03*
X1967921Y-50764D03*
X1962921D03*
X1967921Y-35764D03*
Y-58764D03*
X1962921Y-35764D03*
Y-58764D03*
X1970121Y647556D03*
Y643156D03*
X1970106Y638753D03*
X1965121Y647556D03*
Y643156D03*
X1965106Y638753D03*
X1970121Y651956D03*
Y656356D03*
Y660756D03*
X1965121Y651956D03*
Y656356D03*
Y660756D03*
G54D20*
G01X1627423Y321056D02*
X1634069Y314410D01*
Y289369D01*
X1628650Y283950D01*
Y277780D01*
X1632300Y274130D01*
Y229593D01*
X1634876Y227017D01*
Y218941D01*
X1643447Y210370D01*
X1651398D01*
X1653167Y212139D01*
X1656849D01*
X1659470Y209518D01*
X1666349D01*
X1672046Y203821D01*
X1675179D01*
X1675525Y203475D01*
X1675577D01*
X1675652Y203400D01*
X1710927D01*
X1722258Y214731D01*
X1731170D01*
X1745519Y229080D01*
X1754747D01*
X1758324Y232657D01*
G54D11*
X30500Y-42250D03*
Y-52250D03*
X50500Y-42250D03*
X70500D03*
X90500D03*
X110500D03*
X50500Y-52250D03*
X70500D03*
X90500D03*
X110500D03*
X130500Y-42250D03*
Y-52250D03*
X457246Y-52301D03*
Y-42301D03*
X477246Y-52301D03*
Y-42301D03*
X497246Y-52301D03*
Y-42301D03*
X517246Y-52301D03*
Y-42301D03*
X537246Y-52301D03*
Y-42301D03*
X557246Y-52301D03*
Y-42301D03*
X788984Y-52057D03*
Y-42057D03*
X808984Y-52057D03*
Y-42057D03*
X828984Y-52057D03*
Y-42057D03*
X848984Y-52057D03*
Y-42057D03*
X868984Y-52057D03*
Y-42057D03*
X888984Y-52057D03*
Y-42057D03*
X1125583Y-52285D03*
Y-42285D03*
X1145583Y-52285D03*
Y-42285D03*
X1382258Y-52257D03*
Y-42257D03*
X1402258Y-52257D03*
Y-42257D03*
X1422258Y-52257D03*
Y-42257D03*
X1442258Y-52257D03*
Y-42257D03*
G54D21*
G01X548049Y-193422D02*
Y-210922D01*
G01X543027Y-193422D02*
X553071D01*
G01X565549Y-199256D02*
Y-210922D01*
G01Y-194589D02*
X565112Y-194297D01*
Y-193714D01*
X565549Y-193422D01*
X565986Y-193714D01*
Y-194297D01*
X565549Y-194589D01*
G01X583049Y-210922D02*
X581739Y-210630D01*
X580429Y-209464D01*
X579555Y-207422D01*
X579119Y-205089D01*
X579555Y-202755D01*
X580429Y-200714D01*
X581739Y-199547D01*
X583049Y-199256D01*
X584359Y-199547D01*
X585669Y-200714D01*
X586542Y-202755D01*
X586761Y-205089D01*
X586542Y-207422D01*
X585669Y-209464D01*
X584359Y-210630D01*
X583049Y-210922D01*
G01X597492Y-215297D02*
X599021Y-216464D01*
X600767Y-216755D01*
X602295Y-216464D01*
X603606Y-215006D01*
X604479Y-212964D01*
Y-199256D01*
G01Y-201589D02*
X603606Y-200422D01*
X602295Y-199547D01*
X600767Y-199256D01*
X599021Y-199839D01*
X597929Y-201005D01*
X597055Y-203047D01*
X596619Y-205089D01*
X596837Y-206839D01*
X597711Y-208881D01*
X599021Y-210339D01*
X600767Y-210922D01*
X602077Y-210630D01*
X603606Y-209464D01*
X604479Y-208298D01*
G01X621979Y-210922D02*
Y-199256D01*
G01Y-201297D02*
X621106Y-200131D01*
X619795Y-199547D01*
X618267Y-199256D01*
X616739Y-199839D01*
X615429Y-201005D01*
X614555Y-202755D01*
X614119Y-205089D01*
X614555Y-207422D01*
X615429Y-209172D01*
X616739Y-210339D01*
X618267Y-210922D01*
X619795Y-210630D01*
X621106Y-209756D01*
X621979Y-208589D01*
G01X648682Y-210922D02*
Y-193422D01*
X653922D01*
X655669Y-194297D01*
X656979Y-196339D01*
X657416Y-198672D01*
X656979Y-201005D01*
X655887Y-202755D01*
X653922Y-203631D01*
X648682D01*
G01X674479Y-210922D02*
Y-199256D01*
G01Y-201297D02*
X673606Y-200131D01*
X672295Y-199547D01*
X670767Y-199256D01*
X669239Y-199839D01*
X667929Y-201005D01*
X667055Y-202755D01*
X666619Y-205089D01*
X667055Y-207422D01*
X667929Y-209172D01*
X669239Y-210339D01*
X670767Y-210922D01*
X672295Y-210630D01*
X673606Y-209756D01*
X674479Y-208589D01*
G01X684774Y-208881D02*
X685866Y-210047D01*
X687394Y-210922D01*
X688704D01*
X690014Y-210339D01*
X690887Y-209464D01*
X691324Y-208298D01*
X691106Y-206547D01*
X690232Y-205672D01*
X686302Y-203922D01*
X685429Y-201880D01*
X685866Y-200422D01*
X686739Y-199547D01*
X688049Y-199256D01*
X689359Y-199547D01*
X690669Y-200422D01*
G01X702274Y-208881D02*
X703366Y-210047D01*
X704894Y-210922D01*
X706204D01*
X707514Y-210339D01*
X708387Y-209464D01*
X708824Y-208298D01*
X708606Y-206547D01*
X707732Y-205672D01*
X703802Y-203922D01*
X702929Y-201880D01*
X703366Y-200422D01*
X704239Y-199547D01*
X705549Y-199256D01*
X706859Y-199547D01*
X708169Y-200422D01*
G01X735746Y-210922D02*
Y-193422D01*
X740112D01*
X741859Y-194297D01*
X743169Y-195464D01*
X744261Y-197213D01*
X745134Y-199256D01*
X745352Y-202172D01*
X745134Y-205089D01*
X744261Y-207131D01*
X743169Y-208881D01*
X741859Y-210047D01*
X740112Y-210922D01*
X735746D01*
G01X752590Y-193422D02*
X758049Y-210922D01*
X763508Y-193422D01*
G01X775549D02*
Y-210922D01*
G01X770527Y-193422D02*
X780571D01*
G01X804872Y-210922D02*
Y-193422D01*
X810549Y-208005D01*
X816226Y-193422D01*
Y-210922D01*
G01X829795Y-201589D02*
X830669Y-200714D01*
X831324Y-199256D01*
X831761Y-197213D01*
X831324Y-195464D01*
X830451Y-194297D01*
X828922Y-193422D01*
X823027D01*
Y-210922D01*
X830232D01*
X831761Y-209756D01*
X832634Y-208005D01*
X833071Y-205964D01*
X832634Y-203922D01*
X831324Y-202172D01*
X829795Y-201589D01*
X823027D01*
G01X647372Y-165922D02*
Y-148422D01*
X653049Y-163005D01*
X658726Y-148422D01*
Y-165922D01*
G01X670549D02*
X669239Y-165630D01*
X667929Y-164464D01*
X667055Y-162422D01*
X666619Y-160089D01*
X667055Y-157755D01*
X667929Y-155714D01*
X669239Y-154547D01*
X670549Y-154256D01*
X671859Y-154547D01*
X673169Y-155714D01*
X674042Y-157755D01*
X674261Y-160089D01*
X674042Y-162422D01*
X673169Y-164464D01*
X671859Y-165630D01*
X670549Y-165922D01*
G01X691979Y-148422D02*
Y-165922D01*
G01Y-163298D02*
X691106Y-164756D01*
X689795Y-165630D01*
X688267Y-165922D01*
X686521Y-165339D01*
X685211Y-163881D01*
X684337Y-162131D01*
X684119Y-160089D01*
X684337Y-158047D01*
X685211Y-156297D01*
X686521Y-154839D01*
X688267Y-154256D01*
X689795Y-154547D01*
X690887Y-155131D01*
X691979Y-156297D01*
G01X702274Y-158047D02*
X709261D01*
X708606Y-156005D01*
X707514Y-154839D01*
X705986Y-154256D01*
X704457Y-154547D01*
X703147Y-155422D01*
X702274Y-157464D01*
X701837Y-159214D01*
Y-160964D01*
X702274Y-162714D01*
X703366Y-164464D01*
X704676Y-165630D01*
X706204Y-165922D01*
X707732Y-165339D01*
X709261Y-163589D01*
G01X723049Y-165922D02*
Y-148422D01*
G01X975549Y-210922D02*
Y-193422D01*
X972929Y-196922D01*
G01Y-210922D02*
X978169D01*
G01X988246Y-208298D02*
X989555Y-209756D01*
X991084Y-210630D01*
X993049Y-210922D01*
X995014Y-210339D01*
X996542Y-209172D01*
X997634Y-207131D01*
X997852Y-204797D01*
X997416Y-202464D01*
X996324Y-201005D01*
X994795Y-199839D01*
X993267Y-199547D01*
X991739Y-199839D01*
X989774Y-201005D01*
X990429Y-193422D01*
X996324D01*
G01X1010549Y-210922D02*
Y-193422D01*
X1007929Y-196922D01*
G01Y-210922D02*
X1013169D01*
G01X1023901Y-196339D02*
X1025211Y-194589D01*
X1026739Y-193714D01*
X1028486Y-193422D01*
X1030669Y-194005D01*
X1032197Y-195464D01*
X1032634Y-197213D01*
X1032416Y-198964D01*
X1031542Y-200422D01*
X1027176Y-203339D01*
X1025211Y-205380D01*
X1023901Y-208298D01*
X1023464Y-210922D01*
X1032634D01*
G01X1041401Y-203631D02*
X1042929Y-201589D01*
X1044239Y-200422D01*
X1045986Y-199839D01*
X1047514Y-200422D01*
X1048606Y-201589D01*
X1049479Y-203339D01*
X1049697Y-205380D01*
X1049479Y-207131D01*
X1048606Y-208881D01*
X1047295Y-210339D01*
X1045767Y-210922D01*
X1044021Y-210339D01*
X1042492Y-208589D01*
X1041619Y-205964D01*
X1041401Y-203047D01*
X1041837Y-199256D01*
X1042492Y-197213D01*
X1043584Y-195172D01*
X1045112Y-193714D01*
X1046641Y-193422D01*
X1048169Y-194005D01*
X1049261Y-195464D01*
G01X962432Y-165922D02*
Y-148422D01*
X967672D01*
X969419Y-149297D01*
X970729Y-151339D01*
X971166Y-153672D01*
X970729Y-156005D01*
X969637Y-157755D01*
X967672Y-158631D01*
X962432D01*
G01X989102Y-149881D02*
X987792Y-149005D01*
X986264Y-148422D01*
X984517D01*
X982552Y-149297D01*
X981024Y-150755D01*
X979932Y-152506D01*
X979059Y-155422D01*
X978840Y-158047D01*
X979277Y-160672D01*
X979932Y-162422D01*
X981242Y-164172D01*
X982771Y-165339D01*
X984299Y-165922D01*
X985827D01*
X987356Y-165339D01*
X988666Y-164464D01*
X989758Y-163298D01*
G01X1003545Y-156589D02*
X1004419Y-155714D01*
X1005074Y-154256D01*
X1005511Y-152213D01*
X1005074Y-150464D01*
X1004201Y-149297D01*
X1002672Y-148422D01*
X996777D01*
Y-165922D01*
X1003982D01*
X1005511Y-164756D01*
X1006384Y-163005D01*
X1006821Y-160964D01*
X1006384Y-158922D01*
X1005074Y-157172D01*
X1003545Y-156589D01*
X996777D01*
G01X1012749Y-171755D02*
X1025849D01*
G01X1031777Y-165922D02*
Y-148422D01*
X1041821Y-165922D01*
Y-148422D01*
G01X1054299Y-165922D02*
X1052552Y-165630D01*
X1051024Y-164464D01*
X1049714Y-162714D01*
X1048840Y-160672D01*
X1048404Y-158339D01*
Y-156005D01*
X1048840Y-153672D01*
X1049714Y-151630D01*
X1051024Y-149881D01*
X1052552Y-148714D01*
X1054299Y-148422D01*
X1056045Y-148714D01*
X1057574Y-149881D01*
X1058884Y-151630D01*
X1059758Y-153672D01*
X1060194Y-156005D01*
Y-158339D01*
X1059758Y-160672D01*
X1058884Y-162714D01*
X1057574Y-164464D01*
X1056045Y-165630D01*
X1054299Y-165922D01*
G01X1128099Y-210922D02*
Y-193422D01*
X1125479Y-196922D01*
G01Y-210922D02*
X1130719D01*
G01X1147345Y-201589D02*
X1148219Y-200714D01*
X1148874Y-199256D01*
X1149311Y-197213D01*
X1148874Y-195464D01*
X1148001Y-194297D01*
X1146472Y-193422D01*
X1140577D01*
Y-210922D01*
X1147782D01*
X1149311Y-209756D01*
X1150184Y-208005D01*
X1150621Y-205964D01*
X1150184Y-203922D01*
X1148874Y-202172D01*
X1147345Y-201589D01*
X1140577D01*
G01X1105140Y-148422D02*
X1110599Y-165922D01*
X1116058Y-148422D01*
G01X1132466Y-165922D02*
X1123732D01*
Y-148422D01*
X1132466D01*
G01X1128972Y-156880D02*
X1123732D01*
G01X1141232Y-165922D02*
Y-148422D01*
X1146691D01*
X1148437Y-149297D01*
X1149529Y-150464D01*
X1149966Y-152797D01*
X1149529Y-155131D01*
X1148219Y-156589D01*
X1146691Y-157464D01*
X1141232D01*
G01X1146691D02*
X1149966Y-165922D01*
G01X1163099Y-166505D02*
X1162662Y-166214D01*
Y-165630D01*
X1163099Y-165339D01*
X1163536Y-165630D01*
Y-166214D01*
X1163099Y-166505D01*
G01X1238682Y-193422D02*
Y-210922D01*
X1247416D01*
G01X1260112D02*
X1260549Y-207131D01*
X1261204Y-203922D01*
X1262077Y-201005D01*
X1263169Y-197797D01*
X1264916Y-193422D01*
X1256182D01*
G01X1272590D02*
X1278049Y-210922D01*
X1283508Y-193422D01*
G01X1300352Y-194881D02*
X1299042Y-194005D01*
X1297514Y-193422D01*
X1295767D01*
X1293802Y-194297D01*
X1292274Y-195755D01*
X1291182Y-197506D01*
X1290309Y-200422D01*
X1290090Y-203047D01*
X1290527Y-205672D01*
X1291182Y-207422D01*
X1292492Y-209172D01*
X1294021Y-210339D01*
X1295549Y-210922D01*
X1297077D01*
X1298606Y-210339D01*
X1299916Y-209464D01*
X1301008Y-208298D01*
G01X1317852Y-194881D02*
X1316542Y-194005D01*
X1315014Y-193422D01*
X1313267D01*
X1311302Y-194297D01*
X1309774Y-195755D01*
X1308682Y-197506D01*
X1307809Y-200422D01*
X1307590Y-203047D01*
X1308027Y-205672D01*
X1308682Y-207422D01*
X1309992Y-209172D01*
X1311521Y-210339D01*
X1313049Y-210922D01*
X1314577D01*
X1316106Y-210339D01*
X1317416Y-209464D01*
X1318508Y-208298D01*
G01X1238682Y-148422D02*
Y-165922D01*
X1247416D01*
G01X1264479D02*
Y-154256D01*
G01Y-156297D02*
X1263606Y-155131D01*
X1262295Y-154547D01*
X1260767Y-154256D01*
X1259239Y-154839D01*
X1257929Y-156005D01*
X1257055Y-157755D01*
X1256619Y-160089D01*
X1257055Y-162422D01*
X1257929Y-164172D01*
X1259239Y-165339D01*
X1260767Y-165922D01*
X1262295Y-165630D01*
X1263606Y-164756D01*
X1264479Y-163589D01*
G01X1273464Y-171172D02*
X1274774Y-171755D01*
X1276521Y-171172D01*
X1277612Y-170006D01*
X1278486Y-168547D01*
X1279795Y-163881D01*
X1282634Y-154256D01*
G01X1275647D02*
X1279795Y-163881D01*
G01X1292274Y-158047D02*
X1299261D01*
X1298606Y-156005D01*
X1297514Y-154839D01*
X1295986Y-154256D01*
X1294457Y-154547D01*
X1293147Y-155422D01*
X1292274Y-157464D01*
X1291837Y-159214D01*
Y-160964D01*
X1292274Y-162714D01*
X1293366Y-164464D01*
X1294676Y-165630D01*
X1296204Y-165922D01*
X1297732Y-165339D01*
X1299261Y-163589D01*
G01X1309992Y-165922D02*
Y-154256D01*
G01Y-156589D02*
X1311084Y-155422D01*
X1312176Y-154547D01*
X1313704Y-154256D01*
X1314795Y-154547D01*
X1316106Y-155422D01*
G01X1380796Y-165922D02*
Y-148422D01*
X1385162D01*
X1386909Y-149297D01*
X1388219Y-150464D01*
X1389311Y-152213D01*
X1390184Y-154256D01*
X1390402Y-157172D01*
X1390184Y-160089D01*
X1389311Y-162131D01*
X1388219Y-163881D01*
X1386909Y-165047D01*
X1385162Y-165922D01*
X1380796D01*
G01X1399824Y-158047D02*
X1406811D01*
X1406156Y-156005D01*
X1405064Y-154839D01*
X1403536Y-154256D01*
X1402007Y-154547D01*
X1400697Y-155422D01*
X1399824Y-157464D01*
X1399387Y-159214D01*
Y-160964D01*
X1399824Y-162714D01*
X1400916Y-164464D01*
X1402226Y-165630D01*
X1403754Y-165922D01*
X1405282Y-165339D01*
X1406811Y-163589D01*
G01X1417324Y-163881D02*
X1418416Y-165047D01*
X1419944Y-165922D01*
X1421254D01*
X1422564Y-165339D01*
X1423437Y-164464D01*
X1423874Y-163298D01*
X1423656Y-161547D01*
X1422782Y-160672D01*
X1418852Y-158922D01*
X1417979Y-156880D01*
X1418416Y-155422D01*
X1419289Y-154547D01*
X1420599Y-154256D01*
X1421909Y-154547D01*
X1423219Y-155422D01*
G01X1438099Y-154256D02*
Y-165922D01*
G01Y-149589D02*
X1437662Y-149297D01*
Y-148714D01*
X1438099Y-148422D01*
X1438536Y-148714D01*
Y-149297D01*
X1438099Y-149589D01*
G01X1452542Y-170297D02*
X1454071Y-171464D01*
X1455817Y-171755D01*
X1457345Y-171464D01*
X1458656Y-170006D01*
X1459529Y-167964D01*
Y-154256D01*
G01Y-156589D02*
X1458656Y-155422D01*
X1457345Y-154547D01*
X1455817Y-154256D01*
X1454071Y-154839D01*
X1452979Y-156005D01*
X1452105Y-158047D01*
X1451669Y-160089D01*
X1451887Y-161839D01*
X1452761Y-163881D01*
X1454071Y-165339D01*
X1455817Y-165922D01*
X1457127Y-165630D01*
X1458656Y-164464D01*
X1459529Y-163298D01*
G01X1469387Y-165922D02*
Y-154256D01*
G01Y-157172D02*
X1470261Y-155714D01*
X1471571Y-154547D01*
X1473317Y-154256D01*
X1474845Y-154547D01*
X1476156Y-155714D01*
X1476811Y-157755D01*
Y-165922D01*
G01X1487324Y-158047D02*
X1494311D01*
X1493656Y-156005D01*
X1492564Y-154839D01*
X1491036Y-154256D01*
X1489507Y-154547D01*
X1488197Y-155422D01*
X1487324Y-157464D01*
X1486887Y-159214D01*
Y-160964D01*
X1487324Y-162714D01*
X1488416Y-164464D01*
X1489726Y-165630D01*
X1491254Y-165922D01*
X1492782Y-165339D01*
X1494311Y-163589D01*
G01X1505042Y-165922D02*
Y-154256D01*
G01Y-156589D02*
X1506134Y-155422D01*
X1507226Y-154547D01*
X1508754Y-154256D01*
X1509845Y-154547D01*
X1511156Y-155422D01*
G01X1426729Y-193422D02*
X1431969D01*
G01X1429349D02*
Y-210922D01*
G01X1426729D02*
X1431969D01*
G01X1441390Y-193422D02*
X1446849Y-210922D01*
X1452308Y-193422D01*
G01X1464349Y-210922D02*
Y-203047D01*
X1459982Y-193422D01*
G01X1468716D02*
X1464349Y-203047D01*
G01X1551799Y-193422D02*
X1550052Y-194005D01*
X1548742Y-195464D01*
X1547869Y-197213D01*
X1547214Y-199547D01*
X1546996Y-202172D01*
X1547214Y-204797D01*
X1547869Y-207131D01*
X1548742Y-208881D01*
X1550052Y-210339D01*
X1551799Y-210922D01*
X1553545Y-210339D01*
X1554856Y-208881D01*
X1555729Y-207131D01*
X1556384Y-204797D01*
X1556602Y-202172D01*
X1556384Y-199547D01*
X1555729Y-197213D01*
X1554856Y-195464D01*
X1553545Y-194005D01*
X1551799Y-193422D01*
G01X1565151Y-196339D02*
X1566461Y-194589D01*
X1567989Y-193714D01*
X1569736Y-193422D01*
X1571919Y-194005D01*
X1573447Y-195464D01*
X1573884Y-197213D01*
X1573666Y-198964D01*
X1572792Y-200422D01*
X1568426Y-203339D01*
X1566461Y-205380D01*
X1565151Y-208298D01*
X1564714Y-210922D01*
X1573884D01*
G01X1582869Y-211505D02*
X1590729Y-193422D01*
G01X1604299Y-210922D02*
Y-193422D01*
X1601679Y-196922D01*
G01Y-210922D02*
X1606919D01*
G01X1621799Y-193422D02*
X1620052Y-194005D01*
X1618742Y-195464D01*
X1617869Y-197213D01*
X1617214Y-199547D01*
X1616996Y-202172D01*
X1617214Y-204797D01*
X1617869Y-207131D01*
X1618742Y-208881D01*
X1620052Y-210339D01*
X1621799Y-210922D01*
X1623545Y-210339D01*
X1624856Y-208881D01*
X1625729Y-207131D01*
X1626384Y-204797D01*
X1626602Y-202172D01*
X1626384Y-199547D01*
X1625729Y-197213D01*
X1624856Y-195464D01*
X1623545Y-194005D01*
X1621799Y-193422D01*
G01X1635369Y-211505D02*
X1643229Y-193422D01*
G01X1652651Y-196339D02*
X1653961Y-194589D01*
X1655489Y-193714D01*
X1657236Y-193422D01*
X1659419Y-194005D01*
X1660947Y-195464D01*
X1661384Y-197213D01*
X1661166Y-198964D01*
X1660292Y-200422D01*
X1655926Y-203339D01*
X1653961Y-205380D01*
X1652651Y-208298D01*
X1652214Y-210922D01*
X1661384D01*
G01X1674299Y-193422D02*
X1672552Y-194005D01*
X1671242Y-195464D01*
X1670369Y-197213D01*
X1669714Y-199547D01*
X1669496Y-202172D01*
X1669714Y-204797D01*
X1670369Y-207131D01*
X1671242Y-208881D01*
X1672552Y-210339D01*
X1674299Y-210922D01*
X1676045Y-210339D01*
X1677356Y-208881D01*
X1678229Y-207131D01*
X1678884Y-204797D01*
X1679102Y-202172D01*
X1678884Y-199547D01*
X1678229Y-197213D01*
X1677356Y-195464D01*
X1676045Y-194005D01*
X1674299Y-193422D01*
G01X1691799Y-210922D02*
Y-193422D01*
X1689179Y-196922D01*
G01Y-210922D02*
X1694419D01*
G01X1708862D02*
X1709299Y-207131D01*
X1709954Y-203922D01*
X1710827Y-201005D01*
X1711919Y-197797D01*
X1713666Y-193422D01*
X1704932D01*
G01X1599496Y-165922D02*
Y-148422D01*
X1603862D01*
X1605609Y-149297D01*
X1606919Y-150464D01*
X1608011Y-152213D01*
X1608884Y-154256D01*
X1609102Y-157172D01*
X1608884Y-160089D01*
X1608011Y-162131D01*
X1606919Y-163881D01*
X1605609Y-165047D01*
X1603862Y-165922D01*
X1599496D01*
G01X1625729D02*
Y-154256D01*
G01Y-156297D02*
X1624856Y-155131D01*
X1623545Y-154547D01*
X1622017Y-154256D01*
X1620489Y-154839D01*
X1619179Y-156005D01*
X1618305Y-157755D01*
X1617869Y-160089D01*
X1618305Y-162422D01*
X1619179Y-164172D01*
X1620489Y-165339D01*
X1622017Y-165922D01*
X1623545Y-165630D01*
X1624856Y-164756D01*
X1625729Y-163589D01*
G01X1639299Y-148422D02*
Y-165922D01*
G01X1636242Y-154256D02*
X1642356D01*
G01X1653524Y-158047D02*
X1660511D01*
X1659856Y-156005D01*
X1658764Y-154839D01*
X1657236Y-154256D01*
X1655707Y-154547D01*
X1654397Y-155422D01*
X1653524Y-157464D01*
X1653087Y-159214D01*
Y-160964D01*
X1653524Y-162714D01*
X1654616Y-164464D01*
X1655926Y-165630D01*
X1657454Y-165922D01*
X1658982Y-165339D01*
X1660511Y-163589D01*
G54D12*
G01X430749Y-124922D02*
G02I-12000J0D01*
G01X425599D02*
G02I-6850J0D01*
G01X434749D02*
X402749D01*
G01X434749Y-140922D02*
Y-220922D01*
G01D02*
X1729349D01*
G01X434749Y-176422D02*
X1729349D01*
G01X418749Y-140922D02*
Y-108922D01*
G01X434749Y-140922D02*
X1729349D01*
G01X672800Y31800D02*
X667900D01*
X667800Y31900D01*
G01X941849Y-140922D02*
Y-220922D01*
G01X1079349Y-140922D02*
Y-220922D01*
G01X1194349Y-140922D02*
Y-220922D01*
G01X1361849Y-140922D02*
Y-220922D01*
G01X1435400Y239400D02*
X1470100D01*
X1472200Y241500D01*
Y243000D01*
G01X1531849Y-140922D02*
Y-220922D01*
G01X1729349Y-140922D02*
Y-220922D01*
G01X1757349Y-124922D02*
G02I-12000J0D01*
G01X1752199D02*
G02I-6850J0D01*
G01X1745349Y-140922D02*
Y-108922D01*
G01X1761349Y-124922D02*
X1729349D01*
X3100Y65900D03*
X-8318Y542216D03*
X6200Y531300D03*
X-8200Y578600D03*
X6200Y567300D03*
X77000Y25992D03*
X74000D03*
X62000Y28500D03*
X65000D03*
X68000D03*
X71000D03*
X74000D03*
X77000D03*
X80000Y29000D03*
Y26000D03*
X65000D03*
X71000Y25992D03*
X68000D03*
X52389Y-14258D03*
X60035Y7508D03*
X82013Y14129D03*
X79372Y14895D03*
X79096Y9886D03*
X79116Y12361D03*
X81669Y11693D03*
X81610Y9159D03*
X61446Y18238D03*
X60500Y79000D03*
X70500Y70500D03*
X73000D03*
X78000D03*
X75500D03*
X81000Y61500D03*
Y58500D03*
X63000Y74000D03*
X60500D03*
X63000Y76500D03*
X60500D03*
X67500Y49500D03*
X70500D03*
X73500D03*
X79500D03*
X61500Y43500D03*
X59000D03*
X64500D03*
X67500D03*
X70500D03*
X60500Y70500D03*
X63000D03*
X61500Y58500D03*
Y49500D03*
X59000Y56000D03*
X61500D03*
X59000Y49500D03*
X76500Y43500D03*
X79500Y82000D03*
Y46500D03*
X76500D03*
X73500D03*
X70500D03*
X67500D03*
X64500D03*
X59000D03*
X61500D03*
X68000Y70500D03*
X65500D03*
X79500Y43500D03*
X63000Y81500D03*
X59000Y58500D03*
X61500Y61000D03*
X59000D03*
X76500Y49500D03*
X73500Y43500D03*
X64500Y49500D03*
X79500Y79000D03*
X63000D03*
X79500Y72500D03*
X79725Y75993D03*
X76143Y183019D03*
X97900Y194500D03*
X104820Y198800D03*
X97800Y197600D03*
X104820Y202100D03*
Y195700D03*
X97800Y200800D03*
X81324Y316119D03*
X82500Y341400D03*
X65800Y338900D03*
X90518Y388828D03*
X66016Y468350D03*
X77960Y541468D03*
Y538468D03*
X75461Y541468D03*
Y538468D03*
X73009Y541444D03*
Y538444D03*
X71500Y575000D03*
Y578000D03*
Y582000D03*
X81500Y575000D03*
X78500D03*
X81500Y578000D03*
X78500D03*
X74500Y575000D03*
Y578000D03*
Y582000D03*
X81500D03*
X78500D03*
X75500Y557500D03*
X72500Y561500D03*
Y557500D03*
X69500Y561500D03*
Y557500D03*
X75500Y561500D03*
X78500D03*
X81500D03*
Y557500D03*
X78500D03*
X66500Y554500D03*
X70521Y538403D03*
X68500Y535500D03*
X70498Y541394D03*
X75500Y554500D03*
X72500D03*
X69500D03*
X81500D03*
X78500D03*
X80389Y541468D03*
Y538468D03*
X66500Y557500D03*
Y561500D03*
X78500Y615500D03*
X81500D03*
X75500D03*
X72500D03*
X69500D03*
X78500Y602000D03*
X72500D03*
X69500Y596000D03*
X81500Y599000D03*
X78500D03*
X81500Y596000D03*
Y612000D03*
X78500D03*
X69500Y599000D03*
Y602000D03*
X75500D03*
X78500Y596000D03*
X72500D03*
X66500Y599000D03*
Y602000D03*
Y596000D03*
X81500Y602000D03*
X75500Y596000D03*
X72500Y599000D03*
X75500D03*
X114680Y17320D03*
X112007Y93139D03*
X114082Y55100D03*
X117600Y193805D03*
X141263Y215216D03*
X137763Y217716D03*
X141263D03*
X137763Y215216D03*
X169150Y223600D03*
Y227600D03*
X141263Y234216D03*
X141200Y229600D03*
X141211Y225615D03*
X141300Y221700D03*
X139763Y231700D03*
Y227600D03*
Y223700D03*
X139582Y219800D03*
X125563Y234316D03*
X125663Y230716D03*
X125563Y227116D03*
X141263Y249716D03*
Y247216D03*
X137763D03*
Y249716D03*
X125563Y259116D03*
X125663Y262716D03*
X125563Y266316D03*
X141300Y253700D03*
X139631Y251900D03*
X137763Y279216D03*
X141263Y266216D03*
X139763Y255700D03*
Y259600D03*
X139800Y263700D03*
X141313Y257533D03*
X141263Y279216D03*
X141200Y261600D03*
X137300Y337200D03*
X125663Y294716D03*
X125563Y298316D03*
Y291116D03*
X141263Y311216D03*
X137763D03*
X141263Y281716D03*
X139730Y284200D03*
X139763Y288200D03*
Y292000D03*
Y296000D03*
X141200Y286100D03*
X141261Y290076D03*
X141300Y294000D03*
X141263Y298216D03*
X137763Y281716D03*
X141211Y325515D03*
X141263Y330216D03*
X139763Y327800D03*
X141300Y317500D03*
Y321500D03*
X139582Y315800D03*
X139763Y319400D03*
X125563Y323116D03*
X125663Y326716D03*
X125563Y330316D03*
X141263Y313716D03*
X137763D03*
X139763Y323600D03*
X141289Y349488D03*
X141300Y353300D03*
X141200Y357200D03*
X137763Y345716D03*
X141263D03*
Y343216D03*
X137763D03*
X125563Y362316D03*
Y355116D03*
X125663Y358716D03*
X141263Y362216D03*
X139582Y347800D03*
X139763Y351400D03*
Y355200D03*
Y359500D03*
X141300Y381800D03*
X139763Y384000D03*
X141263Y394216D03*
Y390416D03*
X141261Y385876D03*
X139736Y392300D03*
X125663Y390716D03*
X125563Y387116D03*
Y394316D03*
X137763Y375216D03*
X141263D03*
Y377716D03*
X137763D03*
X139631Y379900D03*
X139900Y388000D03*
X114792Y528600D03*
X113692Y566000D03*
X114792Y604600D03*
X206800Y246500D03*
X203947Y280933D03*
X206600Y372400D03*
X195233Y348402D03*
X271239Y211060D03*
X284759Y207159D03*
X291519D03*
X274619Y213009D03*
Y216909D03*
X277999Y211060D03*
Y214960D03*
Y203260D03*
Y207159D03*
X281379Y213009D03*
X288139Y216909D03*
X284759Y214960D03*
X291519D03*
Y218860D03*
X267859Y244209D03*
Y240309D03*
X271239Y238360D03*
X264179D03*
X264092Y222710D03*
X264179Y226660D03*
X271239Y277360D03*
X267392Y276000D03*
X267359Y279310D03*
X291519Y238360D03*
X284759Y234460D03*
X288139Y232509D03*
X281379D03*
X277999Y234460D03*
X274619Y232509D03*
Y220809D03*
Y224709D03*
Y228610D03*
X277999Y230559D03*
X274619Y244209D03*
Y240309D03*
Y236409D03*
X291519Y246160D03*
X284759D03*
X291519Y242260D03*
X281379Y220809D03*
X284759Y226660D03*
X288139Y236409D03*
X291519Y234460D03*
Y222760D03*
Y230559D03*
Y226660D03*
X281379Y240309D03*
X288139Y279310D03*
X274619D03*
X281379D03*
X239778Y274478D03*
X271239Y320260D03*
Y324160D03*
X270939Y316160D03*
X267359Y318309D03*
X267859Y326110D03*
X267392Y322000D03*
X270892Y304660D03*
Y311960D03*
Y300760D03*
Y308560D03*
Y292959D03*
Y289060D03*
X271239Y281260D03*
X270892Y285500D03*
Y296860D03*
X267359Y283209D03*
X281379Y302709D03*
X288139D03*
X291519Y304660D03*
X281379Y306609D03*
Y310509D03*
X288139Y306609D03*
Y310509D03*
X284759Y304660D03*
X281379Y287109D03*
X288139Y291009D03*
X284759Y289060D03*
Y281260D03*
X291519Y289060D03*
Y281260D03*
Y296860D03*
X288139Y298809D03*
X274619Y306609D03*
Y310509D03*
X277999Y304660D03*
X274619Y302709D03*
Y298809D03*
Y294909D03*
X277999Y289060D03*
Y281260D03*
X274619Y283209D03*
Y287109D03*
Y291009D03*
X277999Y296860D03*
X288139Y283209D03*
Y287109D03*
X281379Y298809D03*
Y294909D03*
X288139D03*
X284759Y296860D03*
X281379Y291009D03*
Y283209D03*
X291519Y312460D03*
X284759D03*
X277999D03*
X274619Y314409D03*
X281379D03*
X288139D03*
X274619Y318309D03*
X267559Y369010D03*
X267492Y380709D03*
X271239Y390460D03*
X267859Y388509D03*
X271239Y382660D03*
X291519Y359260D03*
Y355360D03*
Y351460D03*
X277999Y367060D03*
X274619Y369010D03*
X288139Y365109D03*
X281379D03*
X284759Y363160D03*
X291519D03*
X284759Y370959D03*
X291519Y367060D03*
Y370959D03*
X288139Y361209D03*
Y380709D03*
Y400209D03*
X274619Y380709D03*
X277999Y394359D03*
X274619Y392410D03*
X277999Y390460D03*
Y386560D03*
X274619Y376809D03*
Y372909D03*
X291519Y374860D03*
X277999Y382660D03*
X284759Y398260D03*
X281379Y396309D03*
X291519Y398260D03*
X284759Y390460D03*
X291519D03*
X281379Y376809D03*
Y384609D03*
X284759Y382660D03*
X291519D03*
Y378760D03*
X321061Y-1743D03*
X314368Y-1843D03*
X331100Y-4536D03*
X327754Y-7108D03*
X317714Y-9786D03*
X311021D03*
X314368Y9114D03*
X321061D03*
X331100D03*
X311021Y28014D03*
X317714D03*
X311021Y17057D03*
X317714D03*
X327754D03*
Y28014D03*
X347833Y-7108D03*
X351179Y9122D03*
Y-4536D03*
X341140Y-1743D03*
X337793Y-9901D03*
X341140Y9122D03*
X347833Y17057D03*
Y28022D03*
X337793Y17057D03*
Y28014D03*
X311021Y65814D03*
X317714D03*
X321061Y35957D03*
X314368D03*
Y46914D03*
X311021Y54857D03*
X317714D03*
X321061Y46914D03*
X331100D03*
X327754Y65814D03*
X331100Y35957D03*
X327754Y54857D03*
Y92757D03*
X331100Y84714D03*
Y73757D03*
X314368D03*
Y87392D03*
X311021Y89964D03*
X317714D03*
X321061Y87392D03*
Y73757D03*
X341140Y35957D03*
X337793Y65814D03*
Y54857D03*
X351179Y46922D03*
X347833Y54857D03*
X341140Y46922D03*
X347833Y65822D03*
X351179Y35957D03*
X347833Y92757D03*
X351179Y84599D03*
Y73757D03*
X337793Y89964D03*
X341140Y87392D03*
Y73757D03*
X294899Y213009D03*
X332078Y218860D03*
X329818Y214958D03*
X298279Y218860D03*
X311798Y211060D03*
Y218860D03*
Y214960D03*
X308418Y213009D03*
X305039Y211060D03*
Y218860D03*
X312918Y205210D03*
X315178Y209109D03*
X298279Y207159D03*
Y203260D03*
Y211060D03*
X318558Y218860D03*
X315178Y216909D03*
Y213009D03*
X301659Y209109D03*
X325318Y211060D03*
X348978Y209109D03*
X352357Y211060D03*
X338838Y211058D03*
X335458Y216909D03*
X355737Y209109D03*
X294899Y224709D03*
X332078Y242260D03*
X328698Y232509D03*
Y220809D03*
X332078Y234460D03*
X298279Y246160D03*
X305039D03*
X308418Y244209D03*
X294899D03*
X325318Y242260D03*
Y226660D03*
X298279Y234460D03*
X308418Y228610D03*
Y224709D03*
X305039Y230559D03*
X311798Y222760D03*
X308418Y232509D03*
X294899Y228610D03*
X325318Y234460D03*
Y230559D03*
Y222760D03*
X318558Y246160D03*
X308418Y240309D03*
X315178D03*
X301659D03*
X318558Y242260D03*
X298279Y226660D03*
X318558D03*
X315178Y220809D03*
X321938D03*
X315178Y232509D03*
X301659Y228610D03*
X308418Y236409D03*
X321938D03*
X311798Y238360D03*
X318558D03*
X305039Y226660D03*
X301659Y279310D03*
X308418D03*
X294899D03*
X348978Y220809D03*
X352357Y238360D03*
X345598D03*
X342218Y220809D03*
X338838Y246160D03*
Y242260D03*
Y234460D03*
X335458Y236409D03*
X338838Y238360D03*
X335458Y224709D03*
X355737Y220809D03*
X348978Y267609D03*
X345598Y277360D03*
X348978Y279310D03*
Y275409D03*
Y271509D03*
X352357Y265660D03*
X355737Y263709D03*
X335458Y322209D03*
X308418Y306609D03*
X301659Y310509D03*
Y306609D03*
X311798Y304660D03*
X305039D03*
X321938Y306609D03*
X325318Y304660D03*
Y308560D03*
X298279Y304660D03*
X294899Y302709D03*
X308418D03*
X301659D03*
X315178D03*
X321938D03*
X294899Y310509D03*
Y306609D03*
X318558Y304660D03*
Y308560D03*
X321938Y291009D03*
X318558Y296860D03*
X315178Y294909D03*
X321938D03*
X301659D03*
X325318Y285160D03*
Y289060D03*
Y296860D03*
X298279D03*
Y289060D03*
Y281260D03*
X308418Y298809D03*
X301659D03*
X308418Y283209D03*
X305039Y281260D03*
Y289060D03*
X308418Y291009D03*
Y287109D03*
X311798Y281260D03*
Y289060D03*
X308418Y294909D03*
X311798Y296860D03*
X305039D03*
X315178Y287109D03*
X318558Y285160D03*
X321938Y287109D03*
X301659Y283209D03*
Y287109D03*
Y291009D03*
X294899Y298809D03*
Y294909D03*
Y291009D03*
Y283209D03*
Y287109D03*
X315178Y298809D03*
X321938D03*
X318558Y289060D03*
X315178Y291009D03*
X332078Y308560D03*
Y304660D03*
X328698Y302709D03*
Y306609D03*
Y287109D03*
Y291009D03*
Y294909D03*
Y298809D03*
X332078Y296860D03*
Y285160D03*
Y289060D03*
X315178Y306609D03*
X308418Y310509D03*
X311798Y312460D03*
X305039D03*
X298279D03*
X294899Y314409D03*
X308418D03*
X301659D03*
X328698D03*
X321938D03*
X332078Y328060D03*
X328698Y322209D03*
Y318309D03*
X332078Y324160D03*
Y320260D03*
Y316360D03*
X325318Y320260D03*
X305039D03*
X321938Y318309D03*
X315178D03*
X318558Y316360D03*
X301659Y322209D03*
X325318Y316360D03*
X305039Y324160D03*
X311798Y320260D03*
X308418Y322209D03*
X301659Y326110D03*
X335458Y298809D03*
X348978Y287109D03*
X345598Y285160D03*
Y281260D03*
X348978Y283209D03*
Y298809D03*
Y291009D03*
X345598Y289060D03*
Y292959D03*
Y296860D03*
X348978Y294909D03*
X345598Y300760D03*
X348978Y302709D03*
Y306609D03*
X345598Y304660D03*
Y308560D03*
X348978Y310509D03*
X342218Y302709D03*
Y306609D03*
Y291009D03*
Y287109D03*
Y294909D03*
Y298809D03*
X338838Y308560D03*
X335458Y302709D03*
X338838Y304660D03*
X335458Y306609D03*
Y287109D03*
X338838Y289060D03*
Y285160D03*
X335458Y291009D03*
X338838Y296860D03*
X335458Y294909D03*
X348978Y314409D03*
X345598Y312460D03*
X348978Y322209D03*
X355737Y333909D03*
X345598Y316360D03*
X348978Y318309D03*
Y330009D03*
X352357Y331960D03*
X348978Y326110D03*
X335458Y314409D03*
Y326110D03*
Y318309D03*
X338838Y320260D03*
Y324160D03*
Y328060D03*
X308418Y357309D03*
X311798Y359260D03*
X298279Y351460D03*
X294899Y349509D03*
Y353409D03*
X321938Y349509D03*
X318558Y359260D03*
X321938Y361209D03*
X315178Y357309D03*
X301659D03*
Y349509D03*
X308418Y361209D03*
Y353409D03*
X325318Y343660D03*
Y347560D03*
X328698Y365109D03*
X332078Y363160D03*
X328698Y345609D03*
X325318Y355360D03*
X332078Y347560D03*
Y355360D03*
X294899Y369010D03*
X325318Y367060D03*
Y370959D03*
X318558D03*
X308418Y365109D03*
X315178D03*
X325318Y363160D03*
X298279D03*
X305039Y370959D03*
X308418Y369010D03*
X305039Y367060D03*
X301659Y369010D03*
X298279Y370959D03*
X318558Y351460D03*
Y355360D03*
X305039Y351460D03*
X301659Y388509D03*
X308418D03*
X318558Y394359D03*
X324458Y399911D03*
X332078Y378760D03*
X318558Y386560D03*
X325318D03*
X311798Y374860D03*
X325318D03*
X294899Y372909D03*
X308418D03*
X321938Y376809D03*
X318558Y382660D03*
Y378760D03*
X298279D03*
X305039D03*
X308418Y384609D03*
X311798Y382660D03*
Y378760D03*
X315178Y376809D03*
X328698D03*
X294899Y384609D03*
X318558Y390460D03*
X320808Y401941D03*
X298279Y386560D03*
Y390460D03*
X315178Y392410D03*
Y388509D03*
X311798Y386560D03*
X298279Y398260D03*
Y394359D03*
X294899Y396309D03*
X325318Y378760D03*
X321938Y380709D03*
X305039Y394359D03*
X302608Y402421D03*
X352357Y359260D03*
X338838Y347560D03*
X335458Y361209D03*
X338838Y359260D03*
Y355360D03*
Y351460D03*
X335458Y349509D03*
X345598Y359260D03*
X348978Y349509D03*
X345598Y343660D03*
X342218Y345609D03*
X355737Y349509D03*
Y376809D03*
Y388509D03*
X348978Y376809D03*
X342218Y388509D03*
Y376809D03*
X335458Y372909D03*
Y384609D03*
Y380709D03*
X345598Y390460D03*
X352357Y386560D03*
X317714Y515364D03*
X321061Y512792D03*
X331100Y510114D03*
X327754Y518157D03*
X314368Y512792D03*
X311021Y515364D03*
X337793D03*
X350882Y509999D03*
X347833Y518157D03*
X341140Y512792D03*
X321061Y536957D03*
X317714Y529014D03*
X331100Y547914D03*
Y536957D03*
X327754Y529014D03*
X321061Y547914D03*
X314368D03*
Y536957D03*
X311021Y529014D03*
X327754Y555857D03*
X317714D03*
X311021D03*
X327754Y566814D03*
X331100Y574757D03*
Y585714D03*
X314368D03*
Y574757D03*
X317714Y566814D03*
X311021D03*
X321061Y585714D03*
Y574757D03*
X337793Y529014D03*
X351179Y547922D03*
Y536957D03*
X347833Y529022D03*
X341140Y547922D03*
Y536957D03*
X337793Y555857D03*
X347833D03*
X337793Y566814D03*
X341140Y574757D03*
Y585722D03*
X351179Y574757D03*
Y585722D03*
X347833Y566822D03*
X327754Y607292D03*
X331100Y609864D03*
X327754Y593657D03*
X317714D03*
X311021D03*
X317714Y604614D03*
X311021D03*
X314368Y612457D03*
X321061D03*
X337793Y593657D03*
Y604499D03*
X352109Y609918D03*
X347833Y607292D03*
X341140Y612457D03*
X347833Y593657D03*
X357872Y-9786D03*
X367911D03*
Y-1858D03*
X357872D03*
X367911Y9114D03*
X357672D03*
X357872Y28014D03*
X367911D03*
Y17042D03*
X357872Y17014D03*
X398029Y-4536D03*
X401375Y-7108D03*
X408068Y-1743D03*
X411415Y-9786D03*
X398029Y9107D03*
X408069D03*
X411416Y17057D03*
X401376Y17042D03*
X367911Y46914D03*
Y54842D03*
Y35942D03*
X358619Y36031D03*
X358618Y54842D03*
X357872Y65736D03*
X366992Y65950D03*
X357872Y46914D03*
X357965Y92500D03*
X367911Y87500D03*
X368311Y92500D03*
X367742Y73450D03*
X357872Y87500D03*
X358491Y73479D03*
X408069Y35942D03*
X401376Y54842D03*
X408069Y46907D03*
X398029Y35942D03*
Y46907D03*
X411416Y54857D03*
X401375Y92757D03*
X398029Y84800D03*
Y73742D03*
X408068Y87392D03*
X411415Y89964D03*
X408069Y73742D03*
X362497Y209109D03*
X382777D03*
X376017D03*
X389537D03*
X396296D03*
X407706D03*
X379397Y238360D03*
X362497Y220809D03*
X369257D03*
X382777D03*
X376017D03*
X386157Y238360D03*
X389537Y248109D03*
Y220809D03*
X382777Y248109D03*
X386157Y250060D03*
X359117Y238360D03*
X365877D03*
X372637D03*
Y253960D03*
X376017Y252009D03*
X357057Y277360D03*
X368127Y264300D03*
X364747Y266300D03*
X361492Y268100D03*
X362497Y259809D03*
X365877Y257860D03*
X369257Y255909D03*
X357092Y270700D03*
X391787Y254259D03*
X388407Y256500D03*
X359648Y269777D03*
X374887Y260300D03*
X385027Y254259D03*
X359117Y261760D03*
X371507Y262300D03*
X381647Y256400D03*
X378267Y258400D03*
X357057Y273460D03*
X392916Y250060D03*
Y238360D03*
X396296Y248109D03*
Y220809D03*
X399676Y250060D03*
X407706Y248109D03*
Y220809D03*
X395166Y256400D03*
X398546Y254259D03*
X405306Y254500D03*
X401926Y256500D03*
X357057Y281260D03*
Y296860D03*
Y285160D03*
Y292959D03*
Y300760D03*
Y308560D03*
Y304660D03*
Y289060D03*
Y312460D03*
X364747Y331509D03*
X361367Y329560D03*
X357987Y327609D03*
X371507Y335409D03*
X362497Y337809D03*
X369257Y341709D03*
X368127Y333460D03*
X365877Y339760D03*
X374887Y337360D03*
X381647Y341260D03*
X378267Y339309D03*
X359117Y335860D03*
X357057Y320260D03*
Y324160D03*
Y316360D03*
X414294Y292904D03*
X411294D03*
Y309904D03*
X414294D03*
X379397Y359260D03*
X391787Y347109D03*
X388407Y345160D03*
X372637Y343660D03*
X385027Y343209D03*
X386157Y351460D03*
Y359260D03*
X389537Y353409D03*
X372637Y359260D03*
X365877D03*
X359117D03*
X376017Y376809D03*
X369257D03*
X382777Y388509D03*
X369257D03*
X362497D03*
X376017D03*
X389537D03*
Y376809D03*
X382777D03*
X362497D03*
X396296Y353409D03*
X399676Y351460D03*
X395166Y345160D03*
X398546Y347109D03*
X401926Y345160D03*
X392916Y351460D03*
Y359260D03*
X396296Y388509D03*
Y376809D03*
X411086Y374860D03*
X403056Y376809D03*
Y388509D03*
X386630Y521860D03*
X359042Y515200D03*
X358918Y510114D03*
X366865D03*
Y515152D03*
X401375Y518157D03*
X398029Y509999D03*
X411415Y515364D03*
X408068Y512792D03*
X370080Y555700D03*
X366890Y586000D03*
X367692Y547914D03*
X357672D03*
X357872Y528942D03*
X367911Y529057D03*
X367692Y536200D03*
X357910Y536727D03*
X367211Y555842D03*
X357910D03*
X367192Y566814D03*
X357910D03*
X367192Y574742D03*
X357872D03*
X357025Y585714D03*
X398029Y536942D03*
X408069Y547907D03*
Y536942D03*
X398029Y547907D03*
X401376Y555842D03*
X411416Y555857D03*
X398029Y574742D03*
Y585707D03*
X408069D03*
Y574742D03*
X408068Y612657D03*
X357872Y604614D03*
X367170Y611759D03*
X357872Y612242D03*
X367911Y593642D03*
X357026D03*
X367911Y604614D03*
X398029Y609864D03*
X401376Y593642D03*
X401375Y607292D03*
X411416Y593657D03*
X411415Y604614D03*
X418108Y-4536D03*
X431494D03*
X424801D03*
X428147Y-7108D03*
X434840D03*
X431494Y9107D03*
X424801D03*
X418108D03*
Y-9701D03*
X441533Y-1843D03*
Y9107D03*
X434842Y17057D03*
X441533Y17042D03*
X418108D03*
X428149Y17057D03*
X418108Y28007D03*
X441533D03*
X434842Y54857D03*
X441533Y54842D03*
X424801Y46907D03*
X431494D03*
X428149Y54857D03*
X441533Y46907D03*
X418108Y65807D03*
Y54842D03*
X441533Y65807D03*
X431494Y35942D03*
X441533D03*
X424801D03*
X418108D03*
Y46907D03*
X428147Y92500D03*
X424801Y84800D03*
X431400D03*
X431494Y73742D03*
X441533Y87392D03*
Y92500D03*
Y73742D03*
X418108Y89964D03*
Y84599D03*
Y73742D03*
X424801D03*
X434840Y92500D03*
X476672Y262996D03*
Y266896D03*
X473292Y268847D03*
Y264947D03*
X442020Y339220D03*
X438240Y339380D03*
X449500Y309800D03*
X451648Y308341D03*
X447000Y309800D03*
X421494Y292904D03*
X435894D03*
X432894D03*
X440094D03*
X443094D03*
X425694D03*
X418494D03*
X428694D03*
X418494Y309904D03*
X421494D03*
X425694D03*
X428694D03*
X432894D03*
X435894D03*
X440094Y309841D03*
X443148D03*
X454148Y310341D03*
Y307841D03*
X474413Y329296D03*
X468783Y332897D03*
X474413Y333196D03*
Y325396D03*
X477792Y323446D03*
Y331247D03*
Y335147D03*
Y339047D03*
X443993Y358547D03*
X437233D03*
X450753Y366347D03*
Y358547D03*
X437233Y362447D03*
X423714D03*
X433854Y368296D03*
X427094D03*
X440613Y364396D03*
X427094Y372197D03*
X447373D03*
Y368296D03*
X440613Y372197D03*
Y368296D03*
X443993Y366347D03*
X427094Y356596D03*
X437233Y354647D03*
X423714D03*
X430474D03*
X427094Y360496D03*
X433854D03*
X451883Y342646D03*
X448503Y344597D03*
X421464Y348497D03*
X438363Y346546D03*
X424844D03*
X434983Y348497D03*
X428224D03*
X431604Y346546D03*
X430474Y385847D03*
X450753Y397547D03*
X440613Y395595D03*
X429354Y399496D03*
X433854Y379996D03*
X423714Y374146D03*
X437233D03*
X430474Y378047D03*
X433854Y376096D03*
X443993Y397546D03*
Y401447D03*
Y393647D03*
X440613Y391696D03*
X443993Y385847D03*
X427094Y376096D03*
X437233Y381947D03*
X447373Y376096D03*
X440613Y379996D03*
X443993Y378047D03*
X423715Y397548D03*
X430474Y393647D03*
X433854Y391696D03*
X423715Y401449D03*
X450753Y385847D03*
Y393647D03*
Y378047D03*
X437233Y389747D03*
Y385847D03*
X423714D03*
X443993Y405347D03*
X441533Y512792D03*
Y518057D03*
X434840Y518157D03*
X431494Y509999D03*
X424801Y510114D03*
X418108Y515364D03*
Y509999D03*
X428147Y518157D03*
X418108Y536942D03*
Y547907D03*
X431494D03*
X424801D03*
X441533D03*
X418108Y529007D03*
X431494Y536942D03*
X424801D03*
X441533Y536957D03*
Y529007D03*
X418108Y555842D03*
X428149Y555857D03*
X434842D03*
X441533Y555842D03*
Y585707D03*
Y574742D03*
X418108Y566807D03*
X441533D03*
X424801Y574742D03*
X418108Y585599D03*
Y574742D03*
X431494D03*
Y585707D03*
X424801D03*
X441533Y612557D03*
Y607292D03*
X434840D03*
X428147D03*
X418108Y609864D03*
X424801D03*
X431494D03*
X418108Y593642D03*
X434842Y593657D03*
X428149D03*
X441533Y593642D03*
X418108Y604499D03*
X504832Y264947D03*
X487932Y270796D03*
X498072Y268847D03*
X491312D03*
X487932Y266896D03*
X491312Y264947D03*
X480052D03*
X481172Y270796D03*
X494692Y262996D03*
Y305896D03*
X491312Y311747D03*
X501452Y301996D03*
X491312Y307847D03*
X498072Y311747D03*
X511592Y296147D03*
X501452Y294196D03*
X498072Y296147D03*
X504832D03*
X508212Y298096D03*
X498072Y300047D03*
X484552Y307847D03*
X508212Y340996D03*
X498072Y339047D03*
X501452Y313696D03*
X494692D03*
X501452Y329296D03*
X487932Y340996D03*
Y329296D03*
X494692D03*
X491312Y327347D03*
X498072Y331247D03*
X484552Y335147D03*
X481172Y337096D03*
X501452Y321496D03*
X481172Y340996D03*
X484552Y339047D03*
X487932Y337096D03*
Y333196D03*
X491312Y335147D03*
X494692Y333196D03*
X498072Y335147D03*
X491312Y319547D03*
X494692Y321496D03*
X501452Y317596D03*
X498072Y315647D03*
Y323446D03*
X494692Y325396D03*
X501452D03*
X514972Y298096D03*
X518352Y292245D03*
Y288347D03*
X521731Y286396D03*
Y290296D03*
Y298096D03*
X525111Y292245D03*
Y296147D03*
X528491Y290296D03*
X525111Y288347D03*
X521731Y294196D03*
X518352Y300047D03*
Y296147D03*
X514972Y340996D03*
X525111Y339047D03*
X535251Y333196D03*
Y325396D03*
X484552Y342947D03*
X508212Y344896D03*
Y348796D03*
X511592Y346847D03*
Y350747D03*
Y342947D03*
X504832Y362447D03*
X494692Y368296D03*
Y352696D03*
X508212Y356596D03*
X504832Y350747D03*
X487932Y348796D03*
X481172Y356596D03*
X484552Y358547D03*
Y350747D03*
Y354647D03*
X487932Y352696D03*
Y344896D03*
X511592Y374146D03*
X501452Y383896D03*
X498072Y389747D03*
X494692Y376096D03*
X508212Y379996D03*
X521731Y368296D03*
X518352Y366347D03*
X514972Y348796D03*
Y344896D03*
Y352696D03*
X518352Y358547D03*
X521731Y344896D03*
X538631Y370247D03*
X525111Y350747D03*
X514972Y399496D03*
X538631Y381947D03*
X531871Y385847D03*
X528491Y391696D03*
X525111Y397546D03*
X531871Y405347D03*
X590500Y215800D03*
Y213000D03*
X599773Y199596D03*
X600286Y202921D03*
X600400Y226800D03*
X592300Y220500D03*
X548771Y337096D03*
Y329296D03*
X542011Y364396D03*
Y372197D03*
Y352696D03*
X545391Y342947D03*
X559212Y385847D03*
X663699Y3861D03*
X661494Y32946D03*
X656300Y22800D03*
X653800D03*
X656600Y31500D03*
X663300Y10000D03*
X609860Y201356D03*
X613082Y200676D03*
X613773Y196796D03*
X610273Y197496D03*
X606400Y201000D03*
X606773Y198196D03*
X603273Y198896D03*
X613648Y204494D03*
X608648D03*
X604453Y202983D03*
X623648Y209494D03*
Y216994D03*
Y211994D03*
Y214494D03*
X613648Y209494D03*
Y211994D03*
X618648Y209494D03*
Y214494D03*
X621148Y211994D03*
Y216994D03*
X613648Y214494D03*
Y216994D03*
X623648Y206994D03*
X611148D03*
X618648D03*
X621148D03*
X616148D03*
Y211994D03*
Y216994D03*
Y221994D03*
X623648Y224494D03*
Y226994D03*
X611148Y224494D03*
X613648D03*
X618648D03*
Y226994D03*
X621148D03*
X616148D03*
X608648D03*
Y224494D03*
X603300Y226700D03*
X613648Y226994D03*
Y229494D03*
X621148D03*
X618648D03*
X611148D03*
X623648Y221994D03*
Y219494D03*
X611148Y221994D03*
X618648Y219494D03*
X621148Y221994D03*
X613648Y219494D03*
Y221994D03*
X662800Y248600D03*
X639320Y268000D03*
X652500Y273600D03*
X659900Y256900D03*
Y269200D03*
X606148Y229494D03*
X652000Y284500D03*
X663200Y298600D03*
X644800Y292150D03*
X654500Y298600D03*
X652100Y288300D03*
X639045Y299555D03*
X639100Y309500D03*
X649000Y339400D03*
X638790Y329500D03*
X639350Y339980D03*
X639100Y319500D03*
X655900Y307700D03*
X656300Y312300D03*
X660700Y307700D03*
X655900Y316500D03*
X656000Y329800D03*
X655900Y320500D03*
X656000Y325100D03*
X660900Y329800D03*
X664100Y348000D03*
X648800D03*
X658900D03*
X662936Y367171D03*
X659936Y364171D03*
X662936D03*
X654000Y348000D03*
X649600Y391200D03*
X624600Y419400D03*
X626737Y421000D03*
X619800Y416200D03*
X624300Y422100D03*
X627000Y423436D03*
X622900Y424200D03*
X619680Y422600D03*
X625200Y425400D03*
X621800Y421100D03*
X619700Y419500D03*
X629600Y425100D03*
X622100Y417900D03*
X661500Y569800D03*
X658900D03*
X650050Y568623D03*
X647350D03*
X663100Y574200D03*
X665942Y4716D03*
X689900Y20800D03*
X666100Y10000D03*
X710263Y-14500D03*
X723715Y23462D03*
X714823Y23610D03*
X708000Y26600D03*
X709341Y190507D03*
X709182Y203948D03*
X709200Y201300D03*
X711800Y203100D03*
X706600Y201300D03*
X716480Y194700D03*
X709400Y195763D03*
X701956Y195294D03*
X705292Y195729D03*
X714137Y195682D03*
X711886Y194714D03*
X719686Y195421D03*
X722117Y195399D03*
X697568Y196197D03*
X707529Y193200D03*
X704907Y191638D03*
X701129Y192106D03*
X697746Y193205D03*
X706500Y207800D03*
X706561Y211417D03*
Y204217D03*
X719315Y239104D03*
X669900Y224000D03*
X672500Y224100D03*
X678454Y278000D03*
X675380Y246340D03*
X678000Y246400D03*
X668100Y232200D03*
X667240Y246600D03*
X672530Y246300D03*
X677400Y232300D03*
X674300Y232200D03*
X675200Y224100D03*
X667600Y250200D03*
X688643Y225980D03*
X688388Y231280D03*
X678400Y224100D03*
X690380Y252240D03*
X690939Y266630D03*
X693530Y261240D03*
X690660Y264000D03*
X690704Y271324D03*
X671100Y232200D03*
X701800Y246480D03*
X669750Y246350D03*
X710572Y244773D03*
X719360Y241504D03*
X710627Y242061D03*
X702000Y243900D03*
X710900Y231660D03*
X700000Y233700D03*
X700900Y264100D03*
X694361Y223317D03*
Y220817D03*
X690861D03*
Y223317D03*
X672300Y269200D03*
X672200Y256800D03*
X719900Y269300D03*
X725500Y279300D03*
X725300Y269400D03*
X719600Y279400D03*
X704175Y287275D03*
X704214Y290775D03*
X680000Y281900D03*
X672150Y288350D03*
X695300Y338100D03*
X695400Y328000D03*
X684100Y338200D03*
X695400Y318000D03*
X695800Y308000D03*
X696088Y297069D03*
X704500Y293800D03*
X707130Y310150D03*
X718200Y295000D03*
X706300Y318400D03*
X678200Y307800D03*
X672700Y307700D03*
X667100D03*
X678100Y324800D03*
X672200Y329800D03*
X678100Y329600D03*
X666900Y329700D03*
X678200Y313700D03*
Y319300D03*
X679000Y348000D03*
X688600Y365100D03*
X671936Y367171D03*
X665936Y370171D03*
X684900Y348000D03*
X674600D03*
X671936Y370171D03*
X665936Y367171D03*
X668936Y370171D03*
Y367171D03*
X665936Y364171D03*
X668936D03*
X669093Y348120D03*
X671936Y373171D03*
X668936D03*
X670300Y375600D03*
X713900Y347800D03*
X698560Y374430D03*
X713900Y342800D03*
Y352800D03*
Y350300D03*
Y345300D03*
X689825Y491755D03*
X693604Y491803D03*
X689825Y494255D03*
X693604Y494303D03*
X707511Y483439D03*
X710137Y483583D03*
X665700Y574200D03*
X722200Y571300D03*
X712000Y597000D03*
Y599500D03*
X708800Y599300D03*
Y596700D03*
X734500Y-5700D03*
X734916Y-1587D03*
X732316D03*
X732191Y-4087D03*
X735020Y-8858D03*
X764100Y17100D03*
Y55100D03*
X761650Y94550D03*
X766500Y102900D03*
X733564Y189288D03*
X742091Y188333D03*
X747469Y188368D03*
X755248D03*
X739641Y190634D03*
X752708Y188455D03*
X750167Y188490D03*
X744928Y188438D03*
X737319Y189766D03*
X739359Y188125D03*
X735626Y187965D03*
X731155Y189256D03*
X737536Y192392D03*
X766368Y183636D03*
X765227Y186164D03*
X765007Y188583D03*
X762667Y186186D03*
X762533Y188626D03*
X763881Y184103D03*
X760084Y188508D03*
X760258Y186077D03*
X767692Y185654D03*
X767476Y188323D03*
X757654Y188464D03*
X779932Y212033D03*
X770300Y204930D03*
X769044Y191348D03*
X787371Y215216D03*
Y217716D03*
X727997Y239195D03*
X737837Y222364D03*
Y224964D03*
X740300Y228100D03*
X742937Y221174D03*
Y223774D03*
X740437Y224964D03*
Y222364D03*
X731100Y269300D03*
Y279300D03*
X775200Y230500D03*
X775171Y227116D03*
Y234316D03*
X787371Y247216D03*
Y249716D03*
X775271Y262716D03*
X775171Y259116D03*
Y266316D03*
X787371Y279216D03*
X749126Y220843D03*
X742897Y226773D03*
X727300Y302910D03*
X727474Y338363D03*
Y335363D03*
X732474D03*
Y338363D03*
X729974D03*
Y335363D03*
X775271Y294716D03*
X775171Y291116D03*
Y298316D03*
X787371Y281716D03*
Y311216D03*
X775271Y326716D03*
X775171Y323116D03*
Y330316D03*
X787371Y313716D03*
X727474Y344663D03*
Y367463D03*
X732474D03*
X729974D03*
X727474Y364863D03*
X732474D03*
X729974D03*
Y347663D03*
X727474D03*
X732474D03*
Y344663D03*
X727574Y373463D03*
X732574D03*
X730074D03*
X732574Y376063D03*
X730074D03*
X729974Y344663D03*
X731100Y362300D03*
X772300Y403520D03*
X775171Y362316D03*
X775271Y358716D03*
X775171Y355116D03*
X787371Y343216D03*
Y345716D03*
X787321Y374916D03*
Y377316D03*
X775121Y394316D03*
X775221Y390716D03*
X775121Y387116D03*
X755487Y409903D03*
Y412403D03*
X748085Y412338D03*
X750585D03*
X753085D03*
Y409838D03*
X750585D03*
X748085D03*
X760326Y414167D03*
Y411667D03*
X757826D03*
Y414167D03*
X764400Y528600D03*
X763300Y566000D03*
X764400Y604600D03*
X822400Y212400D03*
X790871Y215216D03*
Y217716D03*
X789500Y231800D03*
X790900Y234000D03*
Y229700D03*
X790846Y225774D03*
X790882Y221723D03*
X790871Y247216D03*
Y249716D03*
X789471Y227742D03*
X789576Y223737D03*
X789554Y219723D03*
X790900Y253900D03*
X789432Y252000D03*
X790871Y266216D03*
X789432Y255800D03*
X790867Y257724D03*
X789432Y259800D03*
X789500Y263900D03*
X790885Y261711D03*
X790871Y279216D03*
Y311216D03*
X789432Y284200D03*
Y288300D03*
Y292400D03*
X789400Y296200D03*
X790871Y298216D03*
X790937Y294270D03*
X790900Y290300D03*
Y286200D03*
X790871Y281716D03*
Y313716D03*
X789432Y319900D03*
Y323900D03*
X790900Y322000D03*
Y326000D03*
X790871Y330216D03*
X789500Y328000D03*
X789478Y315671D03*
X790800Y317700D03*
X789432Y348100D03*
Y352100D03*
X789597Y356105D03*
X789500Y360200D03*
X790900Y358200D03*
X790835Y354048D03*
X790867Y350024D03*
X790871Y345716D03*
Y343216D03*
Y362216D03*
X790821Y374916D03*
X790900Y389300D03*
X789500Y391300D03*
X790900Y393400D03*
Y381100D03*
X789582Y383200D03*
X790900Y385300D03*
X789500Y387300D03*
X790821Y377316D03*
X789282Y379200D03*
X797780Y423484D03*
X882008Y321100D03*
X851430Y367468D03*
X960629Y-9786D03*
X963976Y-1843D03*
X970669Y-1743D03*
X967322Y-9786D03*
X963976Y9114D03*
X970669D03*
X967322Y28014D03*
X960629Y17057D03*
Y28014D03*
X967322Y17057D03*
Y65814D03*
X960629D03*
X970669Y35957D03*
Y46914D03*
X967322Y54857D03*
X963976Y35957D03*
Y46914D03*
X960629Y54857D03*
X963976Y73757D03*
X960629Y89964D03*
X963976Y87392D03*
X967322Y89964D03*
X970669Y87392D03*
Y73757D03*
X927607Y203260D03*
Y207159D03*
X934367D03*
Y214960D03*
X930987Y213009D03*
X920847Y211060D03*
X927607Y214960D03*
Y211060D03*
X937747Y216909D03*
X924227D03*
Y213009D03*
X968166Y218860D03*
X947887Y203260D03*
Y207159D03*
X944507Y213009D03*
X941127Y207159D03*
X947887Y211060D03*
Y218860D03*
X941127D03*
Y214960D03*
X962526Y205210D03*
X961406Y214960D03*
Y211060D03*
Y218860D03*
X951267Y209109D03*
X958026Y213009D03*
X954647Y211060D03*
Y218860D03*
X964786Y213009D03*
Y216909D03*
Y209109D03*
X934367Y226660D03*
X924227Y236409D03*
X920847Y238360D03*
X913787Y226660D03*
X913700Y222710D03*
X913787Y238360D03*
X924227Y232509D03*
X927607Y230559D03*
Y234460D03*
X930987Y232509D03*
X934367Y234460D03*
X924227Y228610D03*
X930987Y220809D03*
X924227Y224709D03*
X937747Y232509D03*
Y236409D03*
X924227Y240309D03*
X917467D03*
X930987D03*
X924227Y244209D03*
X917467D03*
X934367Y246160D03*
X924227Y220809D03*
X937747Y279310D03*
X917000Y276000D03*
X920847Y277360D03*
X924227Y279310D03*
X916967D03*
X930987D03*
X958026Y244209D03*
X968166Y242260D03*
X944507Y228610D03*
Y224709D03*
Y244209D03*
X941127Y242260D03*
Y246160D03*
X947887D03*
X941127Y222760D03*
X947887Y226660D03*
Y234460D03*
X941127Y238360D03*
Y234460D03*
Y230559D03*
Y226660D03*
X968166Y246160D03*
X951267Y240309D03*
X958026D03*
X964786D03*
X954647Y246160D03*
X958026Y228610D03*
Y236409D03*
X961406Y238360D03*
X951267Y228610D03*
X954647Y226660D03*
X958026Y224709D03*
Y232509D03*
X954647Y230559D03*
X961406Y222760D03*
X968166Y226660D03*
X971546Y236409D03*
X968166Y238360D03*
X971546Y220809D03*
X964786Y232509D03*
Y220809D03*
X944507Y279310D03*
X958026D03*
X951267D03*
X937747Y287109D03*
X920500Y304660D03*
Y300760D03*
X930987Y302709D03*
X924227D03*
X920500Y311960D03*
X927607Y304660D03*
X924227Y306609D03*
X930987D03*
Y310509D03*
X934367Y304660D03*
X924227Y310509D03*
X920500Y308560D03*
Y289060D03*
X934367Y296860D03*
X930987Y294909D03*
X920500Y296860D03*
Y292959D03*
X927607Y296860D03*
X924227Y298809D03*
X930987D03*
X924227Y283209D03*
X927607Y281260D03*
X920500Y285500D03*
X924227Y287109D03*
X920847Y281260D03*
X930987Y287109D03*
X934367Y289060D03*
Y281260D03*
X930987Y283209D03*
X924227Y291009D03*
X930987D03*
X927607Y289060D03*
X937747Y302709D03*
Y306609D03*
Y310509D03*
Y283209D03*
Y291009D03*
Y294909D03*
Y298809D03*
Y314409D03*
X924227D03*
X930987D03*
X934367Y312460D03*
X927607D03*
X920847Y324160D03*
X924227Y318309D03*
X920547Y316160D03*
X917167Y318309D03*
Y322209D03*
X917467Y326110D03*
X920847Y320260D03*
X971546Y294909D03*
X944507Y283209D03*
X964786Y291009D03*
X954647Y281260D03*
X958026Y283209D03*
X951267Y287109D03*
X958026D03*
X951267Y283209D03*
X961406Y281260D03*
Y296860D03*
X964786Y298809D03*
Y302709D03*
X971546D03*
X961406Y304660D03*
X958026Y302709D03*
X951267D03*
X968166Y308560D03*
X964786Y306609D03*
X968166Y304660D03*
X971546Y306609D03*
X951267Y310509D03*
X954647Y304660D03*
X958026Y306609D03*
Y310509D03*
X951267Y306609D03*
X944507Y302709D03*
Y306609D03*
Y310509D03*
X941127Y304660D03*
X947887D03*
X944507Y294909D03*
Y287109D03*
X971546Y298809D03*
X968166Y285160D03*
X964786Y287109D03*
X944507Y291009D03*
X941127Y281260D03*
Y289060D03*
Y296860D03*
X944507Y298809D03*
X947887Y289060D03*
Y296860D03*
Y281260D03*
X968166Y296860D03*
X964786Y294909D03*
X971546Y291009D03*
Y287109D03*
X968166Y289060D03*
X961406D03*
X958026Y298809D03*
X951267D03*
Y291009D03*
X958026D03*
X954647Y289060D03*
Y296860D03*
X958026Y294909D03*
X951267D03*
X944507Y314409D03*
X951267D03*
X958026D03*
X961406Y312460D03*
X954647D03*
X941127D03*
X947887D03*
X971546Y314409D03*
Y318309D03*
X964786D03*
X951267Y322209D03*
X954647Y324160D03*
X961406Y320260D03*
X954647D03*
X958026Y322209D03*
X951267Y326110D03*
X968166Y316360D03*
X937747Y365109D03*
Y361209D03*
X930987Y365109D03*
X927607Y367060D03*
X934367Y370959D03*
Y363160D03*
X924227Y369010D03*
X917167D03*
X934367Y382660D03*
X930987Y384609D03*
Y376809D03*
X934367Y390460D03*
X927607Y386560D03*
Y390460D03*
X930987Y396309D03*
X934367Y398260D03*
X927607Y394359D03*
X917467Y388509D03*
X924227Y392410D03*
X920847Y390460D03*
X924227Y372909D03*
X937747Y400209D03*
X917100Y380709D03*
X937747D03*
X924227D03*
X920847Y382660D03*
X924227Y376809D03*
X927607Y382660D03*
X968166Y370959D03*
X958026Y361209D03*
X961406Y359260D03*
X958026Y357309D03*
X951267D03*
X941127Y355360D03*
X951267Y349509D03*
X954647Y351460D03*
X958026Y353409D03*
X968166Y355360D03*
Y351460D03*
X964786Y357309D03*
X971546Y361209D03*
X968166Y359260D03*
X958026Y365109D03*
X964786D03*
X954647Y370959D03*
Y367060D03*
X958026Y369010D03*
X951267D03*
X971546Y349509D03*
X947887Y363160D03*
X941127D03*
X947887Y370959D03*
X941127D03*
Y367060D03*
X944507Y369010D03*
X941127Y359260D03*
X944507Y349509D03*
Y353409D03*
X947887Y351460D03*
X958026Y372909D03*
X941127Y374860D03*
X961406D03*
X944507Y372909D03*
X941127Y382660D03*
Y378760D03*
X947887D03*
X944507Y384609D03*
X947887Y390460D03*
Y386560D03*
X941127Y390460D03*
X947887Y398260D03*
X941127D03*
X944507Y396309D03*
X947887Y394359D03*
X964786Y376809D03*
X971546D03*
X968166Y378760D03*
Y386560D03*
X964786Y392410D03*
X968166Y390460D03*
Y394359D03*
X964786Y388509D03*
X961406Y378760D03*
X954647D03*
X958026Y384609D03*
X961406Y382660D03*
X951267Y388509D03*
X958026D03*
X954647Y394359D03*
X961406Y386560D03*
X952216Y402421D03*
X970416Y401941D03*
X971546Y380709D03*
X968166Y382660D03*
X970669Y512792D03*
X967322Y515364D03*
X963976Y512792D03*
X960629Y515364D03*
Y529014D03*
X963976Y536957D03*
X970669D03*
X967322Y529014D03*
X963976Y547914D03*
X970669D03*
X967322Y555857D03*
X960629D03*
X970669Y585714D03*
Y574757D03*
X960629Y566814D03*
X963976Y585714D03*
Y574757D03*
X967322Y566814D03*
Y593657D03*
X963976Y612457D03*
X970669D03*
X960629Y604614D03*
X967322D03*
X960629Y593657D03*
X980708Y-4536D03*
X987401Y-9901D03*
X997441Y-7108D03*
X990748Y-1743D03*
X977362Y-7108D03*
X980708Y9114D03*
X990748Y9122D03*
X977362Y28014D03*
X987401D03*
Y17057D03*
X977362D03*
X997441Y28022D03*
Y17057D03*
X1000787Y-4536D03*
Y9122D03*
X1017519Y-1858D03*
Y-9786D03*
X1007480Y-1858D03*
X1007280Y9114D03*
X1017519D03*
X1007480Y-9786D03*
Y17014D03*
Y28014D03*
X1017519D03*
Y17042D03*
X987401Y65814D03*
X977362D03*
X987401Y54857D03*
X977362D03*
X990748Y46922D03*
Y35957D03*
X980708D03*
Y46914D03*
X997441Y65822D03*
Y54857D03*
Y92757D03*
X990748Y73757D03*
Y87392D03*
X977362Y92757D03*
X987401Y89964D03*
X980708Y84714D03*
Y73757D03*
X1000787Y35957D03*
Y46922D03*
X1017519Y54842D03*
X1007480Y46914D03*
X1008226Y54842D03*
X1008217Y35942D03*
X1007480Y65736D03*
X1016600Y65950D03*
X1017519Y35942D03*
Y46914D03*
X1017919Y92500D03*
X1017519Y87500D03*
X1000787Y84599D03*
Y73757D03*
X1007480Y87500D03*
X1007573Y92500D03*
X1008099Y73479D03*
X1017350Y73450D03*
X998586Y209109D03*
X981686Y218860D03*
X974926Y211060D03*
X985066Y216909D03*
X988446Y211058D03*
X979426Y214958D03*
X1005345Y209109D03*
X1001965Y211060D03*
X1025625Y209109D03*
X1012105D03*
X1032385D03*
X995206Y238360D03*
X988446Y234460D03*
X998586Y220809D03*
X988446Y246160D03*
X981686Y242260D03*
X974926D03*
X988446D03*
Y238360D03*
X985066Y236409D03*
X981686Y234460D03*
X974926Y226660D03*
X991826Y220809D03*
X974926Y230559D03*
Y234460D03*
Y222760D03*
X985066Y224709D03*
X978306Y232509D03*
Y220809D03*
X995206Y277360D03*
X998586Y267609D03*
Y271509D03*
Y275409D03*
Y279310D03*
X1029005Y238360D03*
X1008725D03*
X1001965D03*
X1005345Y220809D03*
X1032385Y248109D03*
X1025625Y220809D03*
X1012105D03*
X1015485Y238360D03*
X1022245D03*
X1018865Y220809D03*
X1032385D03*
X1022245Y253960D03*
X1025625Y252009D03*
X1017735Y264300D03*
X1014355Y266300D03*
X1021115Y262300D03*
X1024495Y260300D03*
X1027875Y258400D03*
X1031255Y256400D03*
X1005345Y263709D03*
X1001965Y265660D03*
X1009256Y269777D03*
X1008725Y261760D03*
X1006665Y277360D03*
X1006700Y270700D03*
X1006665Y273460D03*
X1011100Y268100D03*
X1015485Y257860D03*
X1018865Y255909D03*
X1012105Y259809D03*
X995206Y296860D03*
X985066Y294909D03*
Y287109D03*
X988446Y285160D03*
X991826Y287109D03*
X995206Y281260D03*
X978306Y298809D03*
Y287109D03*
X981686Y285160D03*
X978306Y294909D03*
X981686Y296860D03*
Y289060D03*
X978306Y291009D03*
X998586Y302709D03*
Y306609D03*
Y310509D03*
Y287109D03*
Y294909D03*
Y291009D03*
Y298809D03*
Y283209D03*
X985066Y302709D03*
X978306D03*
X988446Y304660D03*
Y308560D03*
X985066Y306609D03*
X995206Y304660D03*
Y308560D03*
X991826Y306609D03*
X978306D03*
X981686Y308560D03*
Y304660D03*
X974926D03*
Y308560D03*
X995206Y300760D03*
X991826Y302709D03*
X974926Y285160D03*
Y296860D03*
Y289060D03*
X995206Y292959D03*
X988446Y296860D03*
X991826Y294909D03*
X995206Y289060D03*
X988446D03*
X991826Y291009D03*
X985066D03*
X995206Y285160D03*
X985066Y298809D03*
X991826D03*
X998586Y314409D03*
X995206Y312460D03*
X998586Y318309D03*
Y322209D03*
Y326110D03*
Y330009D03*
X995206Y316360D03*
X985066Y314409D03*
X978306D03*
Y318309D03*
Y322209D03*
X981686Y320260D03*
X974926Y316360D03*
Y320260D03*
X985066Y326110D03*
X981686Y328060D03*
X988446D03*
Y324160D03*
X985066Y318309D03*
Y322209D03*
X988446Y320260D03*
X981686Y324160D03*
Y316360D03*
X1006665Y300760D03*
Y304660D03*
Y308560D03*
Y285160D03*
Y296860D03*
Y289060D03*
Y281260D03*
Y292959D03*
X1008725Y335860D03*
X1005345Y333909D03*
X1001965Y331960D03*
X1007595Y327609D03*
X1021115Y335409D03*
X1018865Y341709D03*
X1017735Y333460D03*
X1015485Y339760D03*
X1024495Y337360D03*
X1012105Y337809D03*
X1006665Y312460D03*
X1014355Y331509D03*
X1010975Y329560D03*
X1027875Y339309D03*
X1031255Y341260D03*
X1006665Y324160D03*
Y316360D03*
Y320260D03*
X995206Y343660D03*
X985066Y361209D03*
X974926Y355360D03*
Y347560D03*
X981686D03*
X978306Y345609D03*
X981686Y355360D03*
X985066Y349509D03*
X998586D03*
X978306Y365109D03*
X981686Y363160D03*
X974926D03*
Y367060D03*
Y370959D03*
Y343660D03*
X995206Y359260D03*
X988446D03*
Y347560D03*
X991826Y345609D03*
X988446Y351460D03*
Y355360D03*
X985066Y372909D03*
X974926Y374860D03*
X985066Y384609D03*
X998586Y376809D03*
X991826Y388509D03*
X995206Y390460D03*
X974926Y386560D03*
X991826Y376809D03*
X974066Y399911D03*
X978306Y376809D03*
X974926Y378760D03*
X981686D03*
X985066Y380709D03*
X1022245Y343660D03*
X1001965Y359260D03*
X1005345Y349509D03*
X1008725Y359260D03*
X1015485D03*
X1022245D03*
X1029005D03*
X1032385Y388509D03*
Y376809D03*
X1005345D03*
Y388509D03*
X1001965Y386560D03*
X1025625Y376809D03*
Y388509D03*
X1018865Y376809D03*
X1012105D03*
X1018865Y388509D03*
X1012105D03*
X987401Y515364D03*
X990748Y512792D03*
X997441Y518157D03*
X980708Y510114D03*
X977362Y518157D03*
X1000490Y509999D03*
X1016473Y515152D03*
Y510114D03*
X1008650Y515200D03*
X1008526Y510114D03*
X990748Y536957D03*
X977362Y529014D03*
X980708Y536957D03*
X987401Y529014D03*
X990748Y547922D03*
X980708Y547914D03*
X997441Y529022D03*
X977362Y555857D03*
X987401D03*
X997441D03*
X977362Y566814D03*
X990748Y574757D03*
Y585722D03*
X980708Y585714D03*
Y574757D03*
X997441Y566822D03*
X987401Y566814D03*
X1000787Y536957D03*
Y547922D03*
X1017300Y536200D03*
X1017519Y529057D03*
X1017300Y547914D03*
X1007518Y536727D03*
X1007480Y528942D03*
X1007280Y547914D03*
X1016800Y566814D03*
X1019277Y585714D03*
X1016800Y574742D03*
X1000787Y585722D03*
Y574757D03*
X1016819Y555842D03*
X1007518D03*
Y566814D03*
X1007480Y574742D03*
X1006633Y585714D03*
X977362Y593657D03*
X987401D03*
X997441D03*
Y607292D03*
X977362D03*
X990748Y612457D03*
X980708Y609864D03*
X987401Y604499D03*
X1016778Y611759D03*
X1017519Y604614D03*
Y593642D03*
X1007480Y612242D03*
X1000787Y609864D03*
X1007480Y604614D03*
X1006634Y593642D03*
X1047637Y-4536D03*
X1057676Y-1743D03*
X1047637Y9107D03*
X1057677D03*
X1050983Y-7108D03*
X1050984Y17042D03*
X1061023Y-9786D03*
X1067716Y-4536D03*
Y-9901D03*
X1081102Y-4536D03*
X1074409D03*
X1084448Y-7108D03*
X1077755D03*
X1091141Y-1843D03*
X1067716Y9107D03*
X1091141D03*
X1074409D03*
X1081102D03*
X1061024Y17057D03*
X1067716Y28007D03*
Y17042D03*
X1091141D03*
X1084450Y17057D03*
X1077757D03*
X1091141Y28007D03*
X1050984Y54842D03*
X1047637Y35942D03*
Y46907D03*
X1057677Y35942D03*
Y46907D03*
X1057676Y87392D03*
X1050983Y92757D03*
X1047637Y84599D03*
X1035000Y81200D03*
X1057677Y73742D03*
X1047637D03*
X1061024Y54857D03*
X1067716Y54842D03*
Y35942D03*
Y46907D03*
Y65807D03*
X1091141Y54842D03*
Y35942D03*
X1084450Y54857D03*
X1081102Y35942D03*
X1074409D03*
X1077757Y54857D03*
X1081102Y46907D03*
X1074409D03*
X1091141D03*
Y65807D03*
X1067716Y89964D03*
Y84599D03*
X1081102D03*
X1091141Y87392D03*
Y92657D03*
X1077755Y92757D03*
X1074409Y84714D03*
X1084448Y92757D03*
X1061023Y89964D03*
X1067716Y73742D03*
X1074409D03*
X1081102D03*
X1091141D03*
X1057314Y209109D03*
X1045904D03*
X1039145D03*
X1045904Y220809D03*
X1057314D03*
X1035765Y238360D03*
Y250060D03*
X1057314Y248109D03*
X1039145D03*
X1042524Y250060D03*
X1049284D03*
X1045904Y248109D03*
X1042524Y238360D03*
X1039145Y220809D03*
X1038015Y256500D03*
X1041395Y254259D03*
X1048154D03*
X1051534Y256500D03*
X1044774Y256400D03*
X1054914Y254500D03*
X1034635Y254259D03*
X1071102Y292904D03*
X1068102D03*
X1063902D03*
X1075302Y309904D03*
X1082502D03*
X1092756Y309841D03*
X1089702Y309904D03*
X1085502D03*
X1078302D03*
X1071102D03*
X1068102D03*
X1063902D03*
X1060902D03*
Y292904D03*
X1085502D03*
X1082502D03*
X1078302D03*
X1075302D03*
X1089702D03*
X1092702D03*
X1042524Y359260D03*
X1049284Y351460D03*
X1045904Y353409D03*
X1035765Y351460D03*
Y359260D03*
X1039145Y353409D03*
X1042524Y351460D03*
X1034635Y343209D03*
X1038015Y345160D03*
X1041395Y347109D03*
X1048154D03*
X1044774Y345160D03*
X1051534D03*
X1039145Y388509D03*
X1045904D03*
X1052664D03*
X1039145Y376809D03*
X1045904D03*
X1052664D03*
X1086841Y358547D03*
Y354647D03*
X1073322D03*
X1076702Y356596D03*
X1080082Y354647D03*
X1083462Y368296D03*
X1076702Y372197D03*
Y368296D03*
X1073322Y362447D03*
X1086841D03*
X1090221Y372197D03*
Y364396D03*
X1093601Y366347D03*
X1090221Y368296D03*
X1076702Y360496D03*
X1083462D03*
X1093601Y358547D03*
X1071072Y348497D03*
X1087971Y346546D03*
X1074452D03*
X1081212D03*
X1077832Y348497D03*
X1084591D03*
X1090221Y379996D03*
X1073323Y401449D03*
X1078962Y399496D03*
X1093601Y401447D03*
X1060694Y374860D03*
X1073322Y374146D03*
X1086841D03*
X1073323Y397548D03*
X1073322Y385847D03*
X1080082Y393647D03*
X1083462Y391696D03*
X1080082Y385847D03*
X1083462Y376096D03*
X1080082Y378047D03*
X1083462Y379996D03*
X1076702Y376096D03*
X1090221Y395595D03*
X1086841Y389747D03*
X1093601Y393647D03*
X1090221Y391696D03*
X1093601Y385847D03*
X1086841D03*
X1093601Y397546D03*
Y378047D03*
X1086841Y381947D03*
X1093601Y405347D03*
X1077832Y407800D03*
X1047637Y509999D03*
X1057676Y512792D03*
X1035000Y521556D03*
X1050983Y518157D03*
X1067716Y509999D03*
X1074409Y510114D03*
X1061023Y515364D03*
X1091141Y518057D03*
X1077755Y518157D03*
X1081102Y509999D03*
X1084448Y518157D03*
X1091141Y512792D03*
X1067716Y515364D03*
X1057677Y547907D03*
Y536942D03*
X1047637Y547907D03*
Y536942D03*
X1057677Y574742D03*
Y585707D03*
X1047637Y574742D03*
Y585707D03*
X1050984Y555842D03*
X1074409Y547907D03*
X1081102D03*
X1091141D03*
Y529007D03*
Y536942D03*
X1074409D03*
X1081102D03*
X1067716D03*
Y529007D03*
X1061024Y555857D03*
X1077757D03*
X1084450D03*
X1091141Y555842D03*
X1067716D03*
X1081102Y574742D03*
Y585707D03*
X1074409D03*
X1091141Y574742D03*
Y585707D03*
X1067716Y574742D03*
Y585599D03*
Y566807D03*
X1091141D03*
X1074409Y574742D03*
X1091141Y612557D03*
X1057676Y612657D03*
X1050984Y593642D03*
X1047637Y609864D03*
X1061024Y593657D03*
X1061023Y604614D03*
X1077757Y593657D03*
X1084450D03*
X1067716Y593642D03*
Y609864D03*
Y604499D03*
X1081102Y609864D03*
X1091141Y593642D03*
Y607292D03*
X1084448D03*
X1077755D03*
X1050983D03*
X1074409Y609864D03*
X1137540Y266896D03*
X1147680Y268847D03*
X1137540Y270796D03*
X1140920Y268847D03*
Y264947D03*
X1144300Y262996D03*
X1126280Y266896D03*
X1129660Y264947D03*
X1122900D03*
Y268847D03*
X1126280Y262996D03*
X1154440Y264947D03*
Y311747D03*
X1157820Y305896D03*
X1154440Y303947D03*
X1157820Y301996D03*
X1154440Y300047D03*
X1118391Y332897D03*
X1134160Y307847D03*
X1151060Y294196D03*
X1147680Y300047D03*
Y296147D03*
X1140920Y307847D03*
Y311747D03*
X1151060Y301996D03*
X1144300Y305896D03*
X1147680Y311747D03*
X1157820Y298096D03*
X1154440Y296147D03*
X1134160Y335147D03*
Y339047D03*
X1140920Y319547D03*
X1124021Y325396D03*
X1127400Y323446D03*
X1124021Y329296D03*
Y333196D03*
X1154440Y327347D03*
X1147680Y339047D03*
X1157820Y321496D03*
X1144300Y313696D03*
X1151060D03*
X1144300Y325396D03*
Y321496D03*
X1151060Y329296D03*
X1147680Y335147D03*
Y331247D03*
X1140920Y335147D03*
X1144300Y333196D03*
X1151060Y325396D03*
Y321496D03*
X1147680Y323446D03*
X1137540Y329296D03*
X1144300D03*
X1140920Y327347D03*
X1130780Y340996D03*
Y337096D03*
X1127400Y331247D03*
Y335147D03*
Y339047D03*
X1147680Y315647D03*
X1151060Y317596D03*
X1137540Y337096D03*
Y340996D03*
Y333196D03*
X1096981Y368296D03*
Y372197D03*
X1101491Y342646D03*
X1098111Y344597D03*
X1096981Y376096D03*
X1134160Y358547D03*
X1157820Y356596D03*
X1144300Y352696D03*
X1154440Y350747D03*
Y362447D03*
X1144300Y368296D03*
X1137540Y352696D03*
X1130780Y356596D03*
X1134160Y342947D03*
Y354647D03*
Y350747D03*
X1137540Y348796D03*
Y344896D03*
X1157820Y379996D03*
X1147680Y389747D03*
X1144300Y376096D03*
X1151060Y383896D03*
X1096699Y407782D03*
X1174719Y292247D03*
Y288347D03*
X1171339Y286396D03*
Y290296D03*
X1167960Y300047D03*
X1164580Y298096D03*
X1167960Y296147D03*
Y292247D03*
Y288347D03*
X1161200Y296147D03*
X1178099Y290296D03*
X1174719Y303947D03*
X1167960D03*
X1178099Y309797D03*
X1171339Y305896D03*
X1164580Y309797D03*
Y305896D03*
X1167960Y307847D03*
Y311747D03*
X1171339Y309797D03*
X1178099Y301996D03*
X1174719Y311747D03*
Y307847D03*
X1178099Y305896D03*
X1171339Y298096D03*
Y294196D03*
X1174719Y296147D03*
Y339047D03*
X1164580Y340996D03*
X1167960Y331247D03*
X1171339Y321496D03*
X1178099Y313696D03*
X1171339D03*
X1164580D03*
X1184859Y325396D03*
Y333196D03*
X1198379Y337096D03*
Y329296D03*
X1167960Y358547D03*
X1171339Y344896D03*
X1174719Y350747D03*
X1167960Y366347D03*
X1171339Y368296D03*
X1161200Y374146D03*
X1178099Y391696D03*
X1174719Y397546D03*
X1164580Y399496D03*
X1188239Y370247D03*
X1191619Y372197D03*
Y364396D03*
Y352696D03*
X1194999Y342947D03*
X1181479Y385847D03*
X1188239Y381947D03*
X1208819Y385847D03*
X1181479Y405347D03*
X1251344Y127925D03*
X1221767Y175858D03*
X1263080Y191320D03*
X1260140Y191670D03*
X1252800Y176000D03*
X1255200D03*
X1260510Y206840D03*
X1267220Y203600D03*
X1267218Y207495D03*
X1258810Y204840D03*
X1263728Y211444D03*
X1262250Y201227D03*
X1265718Y201459D03*
X1258482Y201495D03*
X1257770Y199150D03*
X1260260Y199862D03*
X1264180Y199510D03*
X1240500Y218200D03*
X1240452Y208240D03*
Y215740D03*
Y213240D03*
Y210740D03*
X1243196Y207002D03*
X1242800Y204150D03*
X1244380Y202160D03*
X1255310Y193850D03*
X1252930Y193270D03*
X1263040Y193930D03*
X1259360Y193950D03*
X1257210Y192340D03*
X1268986Y205727D03*
X1269254Y197923D03*
X1270930Y200220D03*
X1268930Y201820D03*
X1272522Y202191D03*
X1270754Y203959D03*
X1267486Y199691D03*
X1262018Y197959D03*
X1265786Y197691D03*
X1259518Y197459D03*
X1263950Y203227D03*
X1260620Y203130D03*
X1255982Y200995D03*
X1255833Y197423D03*
X1256810Y203340D03*
X1262182Y204995D03*
X1265420Y205400D03*
X1250235Y199342D03*
X1251940Y197530D03*
X1247803Y198486D03*
X1254065Y199191D03*
X1252330Y201030D03*
X1254310Y202840D03*
X1250625Y202804D03*
X1248290Y201720D03*
X1246620Y203570D03*
X1246090Y200330D03*
X1245014Y205405D03*
X1251089Y194810D03*
X1249571Y196718D03*
X1253521Y195666D03*
X1267554Y195923D03*
X1261220Y195650D03*
X1263804Y196318D03*
X1265570Y194510D03*
X1257601Y195655D03*
X1262080Y209140D03*
X1265450Y209263D03*
X1263680Y207160D03*
X1243300Y223100D03*
X1251395Y226373D03*
X1253791Y226228D03*
X1248672Y226494D03*
X1252221Y228668D03*
X1245300Y224800D03*
X1301279Y10058D03*
X1304079D03*
X1306879D03*
X1301200Y12610D03*
X1306800D03*
X1301200Y15200D03*
X1301100Y2700D03*
X1316300Y-14800D03*
X1320800Y-16900D03*
X1307900Y-14700D03*
X1309500Y-16800D03*
X1323600Y-16900D03*
X1322000Y-14800D03*
X1324800D03*
X1326000Y-12700D03*
X1323600Y-12600D03*
X1327600Y-14800D03*
Y4700D03*
X1326400Y2600D03*
X1324800Y4700D03*
X1322000D03*
X1323600Y2600D03*
X1306700Y2700D03*
X1309500D03*
X1307900Y4800D03*
X1320800Y2600D03*
X1316300Y4700D03*
X1317900Y2600D03*
X1319200Y4700D03*
X1313500Y4800D03*
X1315004Y2567D03*
X1326400Y-16900D03*
X1302300Y4800D03*
X1303900Y2700D03*
X1310700Y4800D03*
X1312300Y2700D03*
X1305100Y4800D03*
X1322532Y9822D03*
X1325332D03*
X1306700Y-16800D03*
X1328800Y-12700D03*
X1312300Y-16800D03*
X1310700Y-14700D03*
X1315004Y-16933D03*
X1313500Y-14700D03*
X1319200Y-14800D03*
X1317900Y-16900D03*
X1321452Y31803D03*
X1304000Y15200D03*
X1328085Y9865D03*
X1322483Y12834D03*
X1328045Y15831D03*
X1325308Y15734D03*
X1322508D03*
X1328123Y12730D03*
X1306800Y15200D03*
X1328987Y2525D03*
X1313942Y30714D03*
X1309760Y30691D03*
X1316300Y31911D03*
X1318700Y31943D03*
X1311809Y32096D03*
X1325383Y12634D03*
X1304000Y12610D03*
X1295581Y94320D03*
X1310600Y41500D03*
X1308100D03*
X1330100Y165000D03*
Y170000D03*
X1340100Y165000D03*
Y170000D03*
X1335100D03*
Y165000D03*
X1320100D03*
X1325100D03*
X1320100Y170000D03*
X1325100D03*
X1331770Y399490D03*
X1332650Y374450D03*
X1317788Y402562D03*
Y400062D03*
X1331856Y401995D03*
X1329064Y399556D03*
X1329288Y402062D03*
X1330200Y377300D03*
X1330758Y389785D03*
Y386785D03*
Y383785D03*
X1324872Y380682D03*
X1322054Y380560D03*
X1324872Y383682D03*
X1327800Y383500D03*
X1325000Y377500D03*
X1327600Y377400D03*
X1319300Y378500D03*
X1327700Y380400D03*
X1322100Y377800D03*
X1323288Y402062D03*
X1323064Y399556D03*
X1320423Y399579D03*
X1320288Y402062D03*
X1326288D03*
X1326064Y399556D03*
X1332600Y377200D03*
X1332748Y380503D03*
X1330190Y380406D03*
X1334889Y421400D03*
X1332236Y419004D03*
X1329400Y404524D03*
X1329736Y419004D03*
X1329889Y421400D03*
X1332389D03*
X1331973Y404580D03*
X1322370Y421400D03*
X1324889Y421470D03*
X1320400Y404524D03*
X1326400D03*
X1323400D03*
X1324736Y419074D03*
X1322217Y419004D03*
X1327236Y419030D03*
X1327389Y421426D03*
X1334967Y419001D03*
X1300000Y552400D03*
Y558400D03*
Y555400D03*
X1317500Y552400D03*
X1320500D03*
X1323500D03*
X1317500Y555400D03*
X1320500D03*
X1323500D03*
X1303000Y576000D03*
Y579000D03*
Y571400D03*
Y568900D03*
Y565900D03*
Y563400D03*
X1306000Y579000D03*
X1323774Y563145D03*
Y566145D03*
X1309000Y565900D03*
Y563400D03*
Y571400D03*
X1306000Y568900D03*
X1309000D03*
X1306000Y576000D03*
X1324000Y568900D03*
X1306000Y571400D03*
X1321000D03*
X1324000D03*
X1321000Y568900D03*
X1318000D03*
X1312000D03*
X1318000Y571400D03*
X1315000D03*
Y568900D03*
X1312000Y571400D03*
X1320500Y558400D03*
X1317500D03*
X1312000Y563400D03*
Y565900D03*
X1315000Y563400D03*
Y565900D03*
X1323500Y558400D03*
X1318000Y563400D03*
Y565900D03*
X1321000Y563400D03*
Y565900D03*
X1306000D03*
Y563400D03*
X1306600Y610000D03*
X1306556Y607558D03*
X1324200Y610100D03*
Y600100D03*
Y597600D03*
X1321100Y598500D03*
Y601000D03*
X1315100Y598500D03*
Y601000D03*
X1312100Y598500D03*
X1309100D03*
Y601000D03*
X1312100D03*
X1318100Y598500D03*
Y601000D03*
X1324200Y602700D03*
Y605100D03*
Y607500D03*
X1371500Y63200D03*
X1351500Y83000D03*
X1367700Y86450D03*
X1380100Y165000D03*
X1350100Y170000D03*
X1355100D03*
X1360100D03*
X1355100Y165000D03*
X1360100D03*
X1345100D03*
X1350100D03*
X1345100Y170000D03*
X1365100D03*
Y165000D03*
X1370100D03*
X1375100Y170000D03*
X1370100D03*
X1375100Y165000D03*
X1380100Y170000D03*
X1394370Y384230D03*
X1390100Y432500D03*
X1385100Y427500D03*
Y442500D03*
Y437500D03*
X1389900Y427400D03*
X1385100Y432500D03*
X1349800Y458200D03*
X1350100Y447500D03*
Y452500D03*
X1360100Y447500D03*
Y452500D03*
Y457500D03*
X1365100Y432500D03*
Y427500D03*
Y437500D03*
X1380100Y442500D03*
Y437500D03*
X1370100D03*
X1375100D03*
X1385316Y574705D03*
X1371100Y584656D03*
X1384744Y605689D03*
X1371100Y615756D03*
X1450973Y112225D03*
X1451021Y151626D03*
X1438348Y155908D03*
X1454070Y163360D03*
X1454660Y166200D03*
X1435655Y246550D03*
X1491164Y82923D03*
X1496038Y154229D03*
X1472200Y243000D03*
X1508650Y287500D03*
X1497200Y421200D03*
X1505715Y441368D03*
X1506059Y429249D03*
X1505459Y421107D03*
X1503128Y419892D03*
X1512350Y423050D03*
X1518650Y426200D03*
Y423050D03*
X1515500Y426200D03*
Y423050D03*
X1524950Y426200D03*
Y423050D03*
X1509200Y416750D03*
X1512350D03*
X1505605Y423604D03*
X1509200Y423050D03*
Y419900D03*
X1515500D03*
X1512350D03*
Y426200D03*
X1509200D03*
X1515500Y429350D03*
X1518650D03*
X1509200D03*
X1512350D03*
X1518650Y438800D03*
X1515500D03*
X1512350D03*
X1505392Y437133D03*
X1509200Y438800D03*
Y441950D03*
X1512350D03*
X1515500D03*
X1524950Y438800D03*
X1509200Y435650D03*
X1518650D03*
X1515500D03*
X1512350D03*
X1524950D03*
X1525000Y416750D03*
X1516700Y409900D03*
X1518650Y413600D03*
X1469301Y607790D03*
X1480975Y620100D03*
X1516400Y619800D03*
X1504700Y608500D03*
X1538870Y78980D03*
X1541988Y90207D03*
Y92707D03*
X1541670Y87760D03*
X1544180Y91660D03*
X1589622Y112876D03*
X1577700Y155353D03*
Y140149D03*
X1567520Y133354D03*
X1589200Y121800D03*
X1549000Y115571D03*
X1549187Y104713D03*
X1541800Y99700D03*
X1541900Y97300D03*
X1583874Y217746D03*
X1582249Y191716D03*
X1533596Y273504D03*
X1532237Y247801D03*
X1533228Y325000D03*
X1551404Y309376D03*
X1584975Y460210D03*
X1587475D03*
X1582200Y460310D03*
X1531250Y445100D03*
Y448250D03*
Y426200D03*
Y429350D03*
Y423050D03*
Y438800D03*
Y435650D03*
X1528475Y407934D03*
X1543850Y416750D03*
Y413600D03*
X1540700Y416750D03*
X1534400D03*
X1537550D03*
X1540700Y445100D03*
X1537550Y448250D03*
X1534400D03*
X1540700D03*
X1537550Y445100D03*
X1534400D03*
X1540700Y435650D03*
X1547754Y430351D03*
X1547755Y423570D03*
X1547754Y427884D03*
X1553825Y453686D03*
X1547000Y435650D03*
X1549925Y431594D03*
X1547755Y421138D03*
X1540700Y423050D03*
X1537550Y429350D03*
X1540700D03*
X1534400Y426200D03*
X1537550D03*
X1540700D03*
X1534400Y429350D03*
Y423050D03*
X1537550D03*
X1534400Y438800D03*
Y435650D03*
X1537550Y438800D03*
X1540700D03*
X1536300Y455200D03*
X1619000Y38500D03*
X1606579Y86726D03*
X1599500Y84500D03*
X1614169Y95004D03*
X1617347Y94581D03*
X1590949Y97850D03*
X1637870Y197577D03*
X1590495Y214525D03*
X1650600Y186300D03*
X1648349Y182276D03*
X1627177Y260267D03*
X1592110Y322002D03*
X1614900Y498575D03*
X1615100Y481400D03*
X1617600D03*
X1612500Y510300D03*
X1615000D03*
X1617771Y498714D03*
X1599070Y562266D03*
X1596570D03*
X1599120Y564764D03*
X1596620D03*
X1596600Y567250D03*
X1697300Y73296D03*
X1689250Y86000D03*
X1657835Y156436D03*
X1680370Y185900D03*
X1655978Y207827D03*
X1682950Y184140D03*
X1680450Y183401D03*
X1702400Y193450D03*
X1702450Y190000D03*
X1664321Y195244D03*
X1658082Y195298D03*
X1702500Y187000D03*
X1674066Y196666D03*
X1660972Y401447D03*
X1710594Y519900D03*
X1719100Y176000D03*
X1749295Y176104D03*
X1723189Y176012D03*
X1714530Y519900D03*
X1777000Y115750D03*
X1778000Y120000D03*
X1780720Y153850D03*
X1784750Y124000D03*
X1791113Y496670D03*
X1788045Y496654D03*
X1784878Y496701D03*
X1840500Y484650D03*
Y487250D03*
X1868200Y590939D03*
X1931639Y178396D03*
X1947550Y485350D03*
X1910500Y472000D03*
Y475000D03*
X1921244Y533750D03*
X1922900Y604450D03*
X1919900Y604550D03*
X1959400Y601100D03*
G54D13*
X42724Y644684D03*
Y644656D03*
Y654684D03*
Y654656D03*
X67724Y644684D03*
Y644656D03*
Y654684D03*
Y654656D03*
X221656Y644656D03*
X196656D03*
X231446Y644756D03*
Y644784D03*
X221656Y644684D03*
X196656D03*
X221656Y654656D03*
X196656D03*
X231446Y654756D03*
Y654784D03*
X221656Y654684D03*
X196656D03*
X256446Y644756D03*
Y644784D03*
Y654756D03*
Y654784D03*
X409240Y644564D03*
X384240D03*
X418914Y644486D03*
Y644514D03*
X409240Y644536D03*
X384240D03*
X409240Y654564D03*
X384240D03*
X418914Y654486D03*
Y654514D03*
X409240Y654536D03*
X384240D03*
X443914Y644486D03*
Y644514D03*
Y654486D03*
Y654514D03*
X596707Y644293D03*
X571707D03*
X596708Y644266D03*
X571708D03*
X596707Y654293D03*
X571707D03*
X596708Y654266D03*
X571708D03*
X606462Y644245D03*
X631462D03*
X606462Y644217D03*
X631462D03*
X606462Y654245D03*
X631462D03*
X606462Y654217D03*
X631462D03*
X912351Y644245D03*
X887351D03*
X912351Y644273D03*
X887351D03*
X912351Y654245D03*
X887351D03*
X912351Y654273D03*
X887351D03*
X922116Y644206D03*
X947116D03*
X922116Y644234D03*
X947116D03*
X922116Y654206D03*
X947116D03*
X922116Y654234D03*
X947116D03*
X1200877Y644262D03*
Y644234D03*
Y654262D03*
Y654234D03*
X1225877Y644262D03*
X1235614Y644236D03*
X1260614D03*
X1235614Y644264D03*
X1260614D03*
X1225877Y644234D03*
Y654262D03*
X1235614Y654236D03*
X1260614D03*
X1235614Y654264D03*
X1260614D03*
X1225877Y654234D03*
X1514375Y644292D03*
Y644264D03*
Y654292D03*
Y654264D03*
X1539375Y644292D03*
Y644264D03*
Y654292D03*
Y654264D03*
G54D14*
X109980Y145531D03*
G54D15*
X72800Y105000D03*
G54D16*
X49560Y649770D03*
Y644670D03*
X54360D03*
X49560Y649570D03*
Y644670D03*
X54360D03*
X49560Y654670D03*
X54360D03*
X49560D03*
X54360D03*
X214820Y649570D03*
Y644670D03*
X210020D03*
X214820Y649770D03*
Y644670D03*
X210020D03*
X214820Y654670D03*
X210020D03*
X214820D03*
X210020D03*
X238282Y649670D03*
Y644770D03*
X243082D03*
X238282Y649870D03*
Y644770D03*
X243082D03*
X238282Y654770D03*
X243082D03*
X238282D03*
X243082D03*
X402404Y649650D03*
Y644550D03*
X397604D03*
X402404Y649450D03*
Y644550D03*
X397604D03*
X402404Y654550D03*
X397604D03*
X402404D03*
X397604D03*
X425750Y649400D03*
Y644500D03*
X430550D03*
X425750Y649600D03*
Y644500D03*
X430550D03*
X425750Y654500D03*
X430550D03*
X425750D03*
X430550D03*
X589871Y649379D03*
Y644279D03*
X585071D03*
X589872Y649180D03*
Y644280D03*
X585072D03*
X589871Y654279D03*
X585071D03*
X589872Y654280D03*
X585072D03*
X613298Y649331D03*
Y644231D03*
X618098D03*
X613298Y649131D03*
Y644231D03*
X618098D03*
X613298Y654231D03*
X618098D03*
X613298D03*
X618098D03*
X905515Y649159D03*
Y644259D03*
X900715D03*
X905515Y649359D03*
Y644259D03*
X900715D03*
X905515Y654259D03*
X900715D03*
X905515D03*
X900715D03*
X928952Y649120D03*
Y644220D03*
X933752D03*
X928952Y649320D03*
Y644220D03*
X933752D03*
X928952Y654220D03*
X933752D03*
X928952D03*
X933752D03*
X1219041Y649348D03*
Y644248D03*
X1214241D03*
X1219041Y649148D03*
Y644248D03*
X1214241D03*
X1219041Y654248D03*
X1214241D03*
X1219041D03*
X1214241D03*
X1242450Y649150D03*
Y644250D03*
X1247250D03*
X1242450Y649350D03*
Y644250D03*
X1247250D03*
X1242450Y654250D03*
X1247250D03*
X1242450D03*
X1247250D03*
X1527739Y644278D03*
D03*
Y654278D03*
D03*
X1532539Y649378D03*
Y644278D03*
Y649178D03*
Y644278D03*
Y654278D03*
D03*
G54D17*
X320784Y203219D03*
X401377Y28022D03*
X411416D03*
X401377Y65822D03*
X411416D03*
X401377Y529022D03*
X411416D03*
X401377Y566822D03*
X411416D03*
X428149Y28022D03*
X434842Y28268D03*
X421456Y35957D03*
X434842Y65822D03*
X428149D03*
Y529022D03*
X434842D03*
X428149Y566822D03*
X434842D03*
X970392Y203219D03*
X1050985Y28022D03*
X1061024D03*
X1077757D03*
X1084450Y28098D03*
X1050985Y65822D03*
X1071064Y35957D03*
X1061024Y65822D03*
X1084450D03*
X1077757D03*
X1050985Y529022D03*
Y566822D03*
X1061024Y529022D03*
X1084450D03*
X1077757D03*
X1067716Y547907D03*
X1071064Y574757D03*
X1061024Y566822D03*
X1084450D03*
X1077757D03*
X1635750Y128240D03*
X1651536Y134388D03*
X1642087Y143837D03*
Y124940D03*
X1645237D03*
X1637363Y149484D03*
X1651536Y140687D03*
Y143837D03*
Y131239D03*
Y124939D03*
X1626339Y150136D03*
X1635788Y153286D03*
X1623190Y146987D03*
Y140687D03*
Y134388D03*
Y128089D03*
Y124940D03*
X1717014Y148950D03*
Y97550D03*
Y104850D03*
Y111150D03*
Y133200D03*
X1743500Y96400D03*
X1735914Y101700D03*
X1745364Y117450D03*
Y98550D03*
X1745363Y108004D03*
X1746189Y131624D03*
X1745364Y142650D03*
X1726464Y117450D03*
X1720164Y117451D03*
Y123750D03*
X1723314D03*
X1745768Y111743D03*
X1745364Y123750D03*
X1742214D03*
Y114300D03*
G54D18*
X1952756Y-14960D03*
G54D19*
G01X70725Y102925D02*
X72800Y105000D01*
G01D02*
X74875Y107075D01*
G01X70725D02*
X72800Y105000D01*
G01D02*
X74875Y102925D01*
G01X1469301Y607790D02*
Y605399D01*
G01X1504700Y608500D02*
Y606200D01*
M02*
